(kicad_pcb
	(version 20260206)
	(generator "pcbnew")
	(generator_version "10.0")
	(general
		(thickness 1.6)
		(legacy_teardrops no)
	)
	(paper "A4")
	(layers
		(0 "F.Cu" signal "TOP")
		(4 "In1.Cu" signal "L02_GND1")
		(6 "In2.Cu" signal "L03_SIG1")
		(8 "In3.Cu" signal "L04_GND2")
		(10 "In4.Cu" signal "L05_VCC1")
		(12 "In5.Cu" signal "L06_VCC2")
		(14 "In6.Cu" signal "L07_GND3")
		(16 "In7.Cu" signal "L08_SIG2")
		(18 "In8.Cu" signal "L09_GND4")
		(2 "B.Cu" signal "BOTTOM")
		(9 "F.Adhes" user "F.Adhesive")
		(11 "B.Adhes" user "B.Adhesive")
		(13 "F.Paste" user "Package Geometry/Pastemask Top")
		(15 "B.Paste" user "Package Geometry/Pastemask Bottom")
		(5 "F.SilkS" user "Ref Des/Silkscreen Top")
		(7 "B.SilkS" user "Ref Des/Silkscreen Bottom")
		(1 "F.Mask" user "Board Geometry/Soldermask Top")
		(3 "B.Mask" user "Board Geometry/Soldermask Bottom")
		(17 "Dwgs.User" user "User.Drawings")
		(19 "Cmts.User" user "User.Comments")
		(21 "Eco1.User" user "User.Eco1")
		(23 "Eco2.User" user "User.Eco2")
		(25 "Edge.Cuts" user "Board Geometry/Outline")
		(27 "Margin" user)
		(31 "F.CrtYd" user "Package Geometry/Place Bound Top")
		(29 "B.CrtYd" user "Package Geometry/Place Bound Bottom")
		(35 "F.Fab" user "Ref Des/Assembly Top")
		(33 "B.Fab" user "Ref Des/Assembly Bottom")
	)
	(setup
		(pad_to_mask_clearance 0)
		(allow_soldermask_bridges_in_footprints no)
		(tenting
			(front yes)
			(back yes)
		)
		(covering
			(front no)
			(back no)
		)
		(plugging
			(front no)
			(back no)
		)
		(capping no)
		(filling no)
		(pcbplotparams
			(layerselection 0x00000000_00000000_55555555_5755f5ff)
			(plot_on_all_layers_selection 0x00000000_00000000_00000000_00000000)
			(disableapertmacros no)
			(usegerberextensions no)
			(usegerberattributes yes)
			(usegerberadvancedattributes yes)
			(creategerberjobfile yes)
			(dashed_line_dash_ratio 12)
			(dashed_line_gap_ratio 3)
			(svgprecision 4)
			(plotframeref no)
			(mode 1)
			(useauxorigin no)
			(pdf_front_fp_property_popups yes)
			(pdf_back_fp_property_popups yes)
			(pdf_metadata yes)
			(pdf_single_document no)
			(dxfpolygonmode yes)
			(dxfimperialunits yes)
			(dxfusepcbnewfont yes)
			(psnegative no)
			(psa4output no)
			(plot_black_and_white yes)
			(sketchpadsonfab no)
			(plotpadnumbers no)
			(hidednponfab no)
			(sketchdnponfab yes)
			(crossoutdnponfab yes)
			(subtractmaskfromsilk no)
			(outputformat 1)
			(mirror no)
			(drillshape 1)
			(scaleselection 1)
			(outputdirectory "")
		)
	)
	(footprint ""
		(layer "F.Cu")
		(at 137.6934 -83.9724)
		(property "Reference" "CR10"
			(at -0.889 -4.65963 0)
			(unlocked yes)
			(layer "F.SilkS")
			(effects
				(font
					(size 0.7874 0.5842)
					(thickness 0.1524)
				)
			)
		)
		(property "Value" "VAL*"
			(at -0.011176 6.627876 0)
			(unlocked yes)
			(layer "F.Fab")
			(hide yes)
			(effects
				(font
					(size 0.7874 0.5842)
					(thickness 0.1524)
				)
			)
		)
		(property "Tolerance" "TOL*"
			(at 0.001524 7.60222 0)
			(unlocked yes)
			(layer "Cmts.User")
			(hide yes)
			(effects
				(font
					(size 0.7874 0.5842)
					(thickness 0.1524)
				)
			)
		)
		(property "User Part Number" "PARTNUM*"
			(at 0 5.66674 0)
			(unlocked yes)
			(layer "Cmts.User")
			(hide yes)
			(effects
				(font
					(size 0.7874 0.5842)
					(thickness 0.1524)
				)
			)
		)
		(property "Device Type" "DIODE_2E-G122-10190-01"
			(at 0 4.47294 0)
			(unlocked yes)
			(layer "F.Fab")
			(hide yes)
			(effects
				(font
					(size 0.7874 0.5842)
					(thickness 0.1524)
				)
			)
		)
		(duplicate_pad_numbers_are_jumpers no)
		(fp_line
			(start -6.311392 -1.896872)
			(end -5.041392 -1.896872)
			(stroke
				(width 0.1)
				(type default)
			)
			(layer "F.SilkS")
		)
		(fp_line
			(start -5.676392 -1.261872)
			(end -5.676392 -2.531872)
			(stroke
				(width 0.1)
				(type default)
			)
			(layer "F.SilkS")
		)
		(fp_line
			(start -4.747768 -3.363976)
			(end 4.747768 -3.363976)
			(stroke
				(width 0.1)
				(type default)
			)
			(layer "F.SilkS")
		)
		(fp_line
			(start -4.747768 3.363976)
			(end -4.747768 -3.363976)
			(stroke
				(width 0.1)
				(type default)
			)
			(layer "F.SilkS")
		)
		(fp_line
			(start 4.747768 -3.363976)
			(end 4.747768 3.363976)
			(stroke
				(width 0.1)
				(type default)
			)
			(layer "F.SilkS")
		)
		(fp_line
			(start 4.747768 3.363976)
			(end -4.747768 3.363976)
			(stroke
				(width 0.1)
				(type default)
			)
			(layer "F.SilkS")
		)
		(fp_rect
			(start -5.001768 -3.617976)
			(end 5.001768 3.617976)
			(stroke
				(width 0)
				(type default)
			)
			(fill no)
			(layer "F.CrtYd")
		)
		(fp_line
			(start -5.295392 -2.024126)
			(end -4.025392 -2.024126)
			(stroke
				(width 0.1)
				(type default)
			)
			(layer "F.Fab")
		)
		(fp_line
			(start -4.660392 -1.389126)
			(end -4.660392 -2.659126)
			(stroke
				(width 0.1)
				(type default)
			)
			(layer "F.Fab")
		)
		(fp_line
			(start -3.554984 -3.109976)
			(end 3.554984 -3.109976)
			(stroke
				(width 0.1)
				(type default)
			)
			(layer "F.Fab")
		)
		(fp_line
			(start -3.554984 3.109976)
			(end -3.554984 -3.109976)
			(stroke
				(width 0.1)
				(type default)
			)
			(layer "F.Fab")
		)
		(fp_line
			(start 3.554984 -3.109976)
			(end 3.554984 3.109976)
			(stroke
				(width 0.1)
				(type default)
			)
			(layer "F.Fab")
		)
		(fp_line
			(start 3.554984 3.109976)
			(end -3.554984 3.109976)
			(stroke
				(width 0.1)
				(type default)
			)
			(layer "F.Fab")
		)
		(fp_text user "A"
			(at -5.7404 -0.18923 0)
			(unlocked yes)
			(layer "F.SilkS")
			(effects
				(font
					(size 0.7874 0.5842)
					(thickness 0.1524)
				)
			)
		)
		(fp_text user "C"
			(at 5.9436 -0.69723 0)
			(unlocked yes)
			(layer "F.SilkS")
			(effects
				(font
					(size 0.7874 0.5842)
					(thickness 0.1524)
				)
			)
		)
		(fp_text user "A"
			(at -4.4704 0.15367 0)
			(unlocked yes)
			(layer "F.Fab")
			(effects
				(font
					(size 0.7874 0.5842)
					(thickness 0.1524)
				)
			)
		)
		(fp_text user "C"
			(at 4.1656 -0.10033 0)
			(unlocked yes)
			(layer "F.Fab")
			(effects
				(font
					(size 0.7874 0.5842)
					(thickness 0.1524)
				)
			)
		)
		(pad "A" smd rect
			(at -3.299968 0)
			(size 2.3876 3.302)
			(layers "F.Cu" "F.Mask" "F.Paste")
			(net "SG")
		)
		(pad "C" smd rect
			(at 3.299968 0)
			(size 2.3876 3.302)
			(layers "F.Cu" "F.Mask" "F.Paste")
			(net "XP12R0V_IN")
		)
	)
	(footprint ""
		(layer "F.Cu")
		(at 146.558 -15.4686)
		(property "Reference" "C231"
			(at 2.667 1.02997 0)
			(unlocked yes)
			(layer "F.SilkS")
			(effects
				(font
					(size 0.7874 0.5842)
					(thickness 0.1524)
				)
			)
		)
		(property "Value" "VAL*"
			(at 0.193548 2.13614 0)
			(unlocked yes)
			(layer "F.Fab")
			(hide yes)
			(effects
				(font
					(size 0.7874 0.5842)
					(thickness 0.1524)
				)
			)
		)
		(property "Tolerance" "TOL*"
			(at 0.216154 3.1496 0)
			(unlocked yes)
			(layer "Cmts.User")
			(hide yes)
			(effects
				(font
					(size 0.7874 0.5842)
					(thickness 0.1524)
				)
			)
		)
		(property "Device Type" "CAPACITOR-G104-0B103-EK,0.01UFA"
			(at 0.184404 1.180592 0)
			(unlocked yes)
			(layer "F.Fab")
			(hide yes)
			(effects
				(font
					(size 0.7874 0.5842)
					(thickness 0.1524)
				)
			)
		)
		(property "User Part Number" "PARTNUM*"
			(at 0.216154 4.185666 0)
			(unlocked yes)
			(layer "Cmts.User")
			(hide yes)
			(effects
				(font
					(size 0.7874 0.5842)
					(thickness 0.1524)
				)
			)
		)
		(duplicate_pad_numbers_are_jumpers no)
		(fp_line
			(start -0.671322 -0.4445)
			(end 0.671322 -0.4445)
			(stroke
				(width 0.1)
				(type default)
			)
			(layer "F.SilkS")
		)
		(fp_line
			(start -0.671322 0.4445)
			(end -0.671322 -0.4445)
			(stroke
				(width 0.1)
				(type default)
			)
			(layer "F.SilkS")
		)
		(fp_line
			(start 0.671322 -0.4445)
			(end 0.671322 0.4445)
			(stroke
				(width 0.1)
				(type default)
			)
			(layer "F.SilkS")
		)
		(fp_line
			(start 0.671322 0.4445)
			(end -0.671322 0.4445)
			(stroke
				(width 0.1)
				(type default)
			)
			(layer "F.SilkS")
		)
		(fp_rect
			(start 0.671322 -0.4445)
			(end -0.671322 0.4445)
			(stroke
				(width 0)
				(type default)
			)
			(fill no)
			(layer "F.CrtYd")
		)
		(fp_line
			(start -0.31496 -0.1651)
			(end -0.31496 0.1651)
			(stroke
				(width 0.1)
				(type default)
			)
			(layer "F.Fab")
		)
		(fp_line
			(start -0.31496 0.1651)
			(end 0.31496 0.1651)
			(stroke
				(width 0.1)
				(type default)
			)
			(layer "F.Fab")
		)
		(fp_line
			(start 0.31496 -0.1651)
			(end -0.31496 -0.1651)
			(stroke
				(width 0.1)
				(type default)
			)
			(layer "F.Fab")
		)
		(fp_line
			(start 0.31496 0.1651)
			(end 0.31496 -0.1651)
			(stroke
				(width 0.1)
				(type default)
			)
			(layer "F.Fab")
		)
		(pad "1" smd rect
			(at -0.264922 0)
			(size 0.3048 0.381)
			(layers "F.Cu" "F.Mask" "F.Paste")
			(net "UNNAMED_515_CAPACITOR_I132_1")
		)
		(pad "2" smd rect
			(at 0.264922 0)
			(size 0.3048 0.381)
			(layers "F.Cu" "F.Mask" "F.Paste")
			(net "SG")
		)
		(zone
			(layer "F.Cu")
			(hatch none 0.5)
			(connect_pads
				(clearance 0)
			)
			(min_thickness 0.25)
			(keepout
				(tracks allowed)
				(vias not_allowed)
				(pads allowed)
				(copperpour not_allowed)
				(footprints allowed)
			)
			(placement
				(enabled no)
				(sheetname "")
			)
			(fill
				(thermal_gap 0.5)
				(thermal_bridge_width 0.5)
				(island_removal_mode 0)
			)
			(polygon
				(pts
					(xy 146.670522 -15.6591) (xy 146.445478 -15.6591) (xy 146.445478 -15.2781) (xy 146.670522 -15.2781)
				)
			)
		)
	)
	(footprint ""
		(layer "F.Cu")
		(at 112.7506 -24.7142)
		(property "Reference" "R241"
			(at -0.2286 8.62457 0)
			(unlocked yes)
			(layer "F.SilkS")
			(effects
				(font
					(size 0.7874 0.5842)
					(thickness 0.1524)
				)
			)
		)
		(property "Value" "VAL*"
			(at 0.02032 2.13233 0)
			(unlocked yes)
			(layer "F.Fab")
			(hide yes)
			(effects
				(font
					(size 0.7874 0.5842)
					(thickness 0.1524)
				)
			)
		)
		(property "Device Type" "RESISTOR-G155-11500-01,150OHM,A"
			(at 0.008382 1.210564 0)
			(unlocked yes)
			(layer "F.Fab")
			(hide yes)
			(effects
				(font
					(size 0.7874 0.5842)
					(thickness 0.1524)
				)
			)
		)
		(property "User Part Number" "PARTNUM*"
			(at 0.02032 4.024884 0)
			(unlocked yes)
			(layer "Cmts.User")
			(hide yes)
			(effects
				(font
					(size 0.7874 0.5842)
					(thickness 0.1524)
				)
			)
		)
		(property "Tolerance" "TOL*"
			(at 0.044704 3.05435 0)
			(unlocked yes)
			(layer "Cmts.User")
			(hide yes)
			(effects
				(font
					(size 0.7874 0.5842)
					(thickness 0.1524)
				)
			)
		)
		(duplicate_pad_numbers_are_jumpers no)
		(fp_line
			(start -1.143 -0.5588)
			(end -1.143 0.5588)
			(stroke
				(width 0.1)
				(type default)
			)
			(layer "F.SilkS")
		)
		(fp_line
			(start -1.143 0.5588)
			(end 1.143 0.5588)
			(stroke
				(width 0.1)
				(type default)
			)
			(layer "F.SilkS")
		)
		(fp_line
			(start 1.143 -0.5588)
			(end -1.143 -0.5588)
			(stroke
				(width 0.1)
				(type default)
			)
			(layer "F.SilkS")
		)
		(fp_line
			(start 1.143 0.5588)
			(end 1.143 -0.5588)
			(stroke
				(width 0.1)
				(type default)
			)
			(layer "F.SilkS")
		)
		(fp_rect
			(start -1.143 -0.5588)
			(end 1.143 0.5588)
			(stroke
				(width 0)
				(type default)
			)
			(fill no)
			(layer "F.CrtYd")
		)
		(fp_line
			(start -0.508 -0.3048)
			(end -0.508 0.3048)
			(stroke
				(width 0.1)
				(type default)
			)
			(layer "F.Fab")
		)
		(fp_line
			(start -0.508 0.3048)
			(end 0.508 0.3048)
			(stroke
				(width 0.1)
				(type default)
			)
			(layer "F.Fab")
		)
		(fp_line
			(start 0.508 -0.3048)
			(end -0.508 -0.3048)
			(stroke
				(width 0.1)
				(type default)
			)
			(layer "F.Fab")
		)
		(fp_line
			(start 0.508 0.3048)
			(end 0.508 -0.3048)
			(stroke
				(width 0.1)
				(type default)
			)
			(layer "F.Fab")
		)
		(pad "1" smd rect
			(at -0.5334 0)
			(size 0.7112 0.6096)
			(layers "F.Cu" "F.Mask" "F.Paste")
			(net "OSC_200M_CLKP")
		)
		(pad "2" smd rect
			(at 0.5334 0)
			(size 0.7112 0.6096)
			(layers "F.Cu" "F.Mask" "F.Paste")
			(net "SG")
		)
		(zone
			(layer "F.Cu")
			(hatch none 0.5)
			(connect_pads
				(clearance 0)
			)
			(min_thickness 0.25)
			(keepout
				(tracks allowed)
				(vias not_allowed)
				(pads allowed)
				(copperpour not_allowed)
				(footprints allowed)
			)
			(placement
				(enabled no)
				(sheetname "")
			)
			(fill
				(thermal_gap 0.5)
				(thermal_bridge_width 0.5)
				(island_removal_mode 0)
			)
			(polygon
				(pts
					(xy 112.6744 -25.019) (xy 112.6744 -24.4094) (xy 112.8268 -24.4094) (xy 112.8268 -25.019)
				)
			)
		)
	)
	(footprint ""
		(layer "F.Cu")
		(at 124.714 -39.116)
		(property "Reference" "TP137"
			(at -0.60325 0.9398 90)
			(unlocked yes)
			(layer "F.SilkS")
			(effects
				(font
					(size 0.635 0.4064)
					(thickness 0.1524)
				)
				(justify left)
			)
		)
		(property "Value" ""
			(at 0 0 0)
			(layer "F.Fab")
			(effects
				(font
					(size 1.27 1.27)
				)
			)
		)
		(property "Device Type" "TP_PIONT-TP010CT020B030_PTH-TPA"
			(at -1.341882 0.996696 0)
			(unlocked yes)
			(layer "F.Fab")
			(hide yes)
			(effects
				(font
					(size 0.7874 0.5842)
					(thickness 0.1524)
				)
				(justify left)
			)
		)
		(duplicate_pad_numbers_are_jumpers no)
		(fp_poly
			(pts
				(arc
					(start 0.889 0)
					(mid -0.889 0)
					(end 0.889 0)
				)
			)
			(stroke
				(width 0)
				(type default)
			)
			(fill no)
			(layer "B.CrtYd")
		)
		(fp_poly
			(pts
				(arc
					(start 0.889 0)
					(mid -0.889 0)
					(end 0.889 0)
				)
			)
			(stroke
				(width 0)
				(type default)
			)
			(fill no)
			(layer "F.CrtYd")
		)
		(pad "1" thru_hole circle
			(at 0 0)
			(size 0.508 0.508)
			(drill 0.254)
			(layers "*.Cu" "*.Mask")
			(remove_unused_layers no)
			(net "IO_L22N_34")
			(clearance 0.1016)
			(padstack
				(mode front_inner_back)
				(layer "Inner"
					(shape circle)
					(size 0.508 0.508)
					(clearance 0.1016)
				)
				(layer "B.Cu"
					(shape circle)
					(size 0.762 0.762)
					(clearance -0.0254)
				)
			)
		)
	)
	(footprint ""
		(layer "F.Cu")
		(at 145.8214 -90.6018)
		(property "Reference" "C3"
			(at -0.2794 8.21817 0)
			(unlocked yes)
			(layer "F.SilkS")
			(effects
				(font
					(size 0.7874 0.5842)
					(thickness 0.1524)
				)
			)
		)
		(property "Value" "VAL*"
			(at 0.0762 2.067306 0)
			(unlocked yes)
			(layer "F.Fab")
			(hide yes)
			(effects
				(font
					(size 0.7874 0.5842)
					(thickness 0.1524)
				)
			)
		)
		(property "Device Type" "CAPACITOR-G105-0B104-EK,0.1UF,A"
			(at 0.0508 1.127506 0)
			(unlocked yes)
			(layer "F.Fab")
			(hide yes)
			(effects
				(font
					(size 0.7874 0.5842)
					(thickness 0.1524)
				)
			)
		)
		(property "User Part Number" "PARTNUM*"
			(at 0.1016 4.023106 0)
			(unlocked yes)
			(layer "Cmts.User")
			(hide yes)
			(effects
				(font
					(size 0.7874 0.5842)
					(thickness 0.1524)
				)
			)
		)
		(property "Tolerance" "TOL*"
			(at 0.0762 3.032506 0)
			(unlocked yes)
			(layer "Cmts.User")
			(hide yes)
			(effects
				(font
					(size 0.7874 0.5842)
					(thickness 0.1524)
				)
			)
		)
		(duplicate_pad_numbers_are_jumpers no)
		(fp_line
			(start -1.143 -0.5588)
			(end -1.143 0.5588)
			(stroke
				(width 0.1)
				(type default)
			)
			(layer "F.SilkS")
		)
		(fp_line
			(start -1.143 0.5588)
			(end 1.143 0.5588)
			(stroke
				(width 0.1)
				(type default)
			)
			(layer "F.SilkS")
		)
		(fp_line
			(start 1.143 -0.5588)
			(end -1.143 -0.5588)
			(stroke
				(width 0.1)
				(type default)
			)
			(layer "F.SilkS")
		)
		(fp_line
			(start 1.143 0.5588)
			(end 1.143 -0.5588)
			(stroke
				(width 0.1)
				(type default)
			)
			(layer "F.SilkS")
		)
		(fp_rect
			(start -1.143 -0.5588)
			(end 1.143 0.5588)
			(stroke
				(width 0)
				(type default)
			)
			(fill no)
			(layer "F.CrtYd")
		)
		(fp_line
			(start -0.508 -0.3048)
			(end -0.508 0.3048)
			(stroke
				(width 0.1)
				(type default)
			)
			(layer "F.Fab")
		)
		(fp_line
			(start -0.508 0.3048)
			(end 0.508 0.3048)
			(stroke
				(width 0.1)
				(type default)
			)
			(layer "F.Fab")
		)
		(fp_line
			(start 0.508 -0.3048)
			(end -0.508 -0.3048)
			(stroke
				(width 0.1)
				(type default)
			)
			(layer "F.Fab")
		)
		(fp_line
			(start 0.508 0.3048)
			(end 0.508 -0.3048)
			(stroke
				(width 0.1)
				(type default)
			)
			(layer "F.Fab")
		)
		(pad "1" smd rect
			(at -0.5334 0)
			(size 0.7112 0.6096)
			(layers "F.Cu" "F.Mask" "F.Paste")
			(net "XP12R0V_A_EN")
		)
		(pad "2" smd rect
			(at 0.5334 0)
			(size 0.7112 0.6096)
			(layers "F.Cu" "F.Mask" "F.Paste")
			(net "SG")
		)
		(zone
			(layer "F.Cu")
			(hatch none 0.5)
			(connect_pads
				(clearance 0)
			)
			(min_thickness 0.25)
			(keepout
				(tracks allowed)
				(vias not_allowed)
				(pads allowed)
				(copperpour not_allowed)
				(footprints allowed)
			)
			(placement
				(enabled no)
				(sheetname "")
			)
			(fill
				(thermal_gap 0.5)
				(thermal_bridge_width 0.5)
				(island_removal_mode 0)
			)
			(polygon
				(pts
					(xy 145.7452 -90.9066) (xy 145.7452 -90.297) (xy 145.8976 -90.297) (xy 145.8976 -90.9066)
				)
			)
		)
	)
	(footprint ""
		(layer "F.Cu")
		(at 112.7125 -28.5242)
		(property "Reference" "R359"
			(at 2.00787 2.1082 90)
			(unlocked yes)
			(layer "F.SilkS")
			(effects
				(font
					(size 0.7874 0.5842)
					(thickness 0.1524)
				)
			)
		)
		(property "Value" "VAL*"
			(at 0.02032 2.13233 0)
			(unlocked yes)
			(layer "F.Fab")
			(hide yes)
			(effects
				(font
					(size 0.7874 0.5842)
					(thickness 0.1524)
				)
			)
		)
		(property "Tolerance" "TOL*"
			(at 0.044704 3.05435 0)
			(unlocked yes)
			(layer "Cmts.User")
			(hide yes)
			(effects
				(font
					(size 0.7874 0.5842)
					(thickness 0.1524)
				)
			)
		)
		(property "User Part Number" "PARTNUM*"
			(at 0.02032 4.024884 0)
			(unlocked yes)
			(layer "Cmts.User")
			(hide yes)
			(effects
				(font
					(size 0.7874 0.5842)
					(thickness 0.1524)
				)
			)
		)
		(property "Device Type" "RESISTOR-G155-11002-01,10KOHM,A"
			(at 0.008382 1.210564 0)
			(unlocked yes)
			(layer "F.Fab")
			(hide yes)
			(effects
				(font
					(size 0.7874 0.5842)
					(thickness 0.1524)
				)
			)
		)
		(duplicate_pad_numbers_are_jumpers no)
		(fp_line
			(start -1.143 -0.5588)
			(end -1.143 0.5588)
			(stroke
				(width 0.1)
				(type default)
			)
			(layer "F.SilkS")
		)
		(fp_line
			(start -1.143 0.5588)
			(end 1.143 0.5588)
			(stroke
				(width 0.1)
				(type default)
			)
			(layer "F.SilkS")
		)
		(fp_line
			(start 1.143 -0.5588)
			(end -1.143 -0.5588)
			(stroke
				(width 0.1)
				(type default)
			)
			(layer "F.SilkS")
		)
		(fp_line
			(start 1.143 0.5588)
			(end 1.143 -0.5588)
			(stroke
				(width 0.1)
				(type default)
			)
			(layer "F.SilkS")
		)
		(fp_poly
			(pts
				(xy -1.143 0.5588) (xy 1.143 0.5588) (xy 1.143 -0.5588) (xy -1.143 -0.5588)
			)
			(stroke
				(width 0)
				(type default)
			)
			(fill no)
			(layer "F.CrtYd")
		)
		(fp_line
			(start -0.508 -0.3048)
			(end -0.508 0.3048)
			(stroke
				(width 0.1)
				(type default)
			)
			(layer "F.Fab")
		)
		(fp_line
			(start -0.508 0.3048)
			(end 0.508 0.3048)
			(stroke
				(width 0.1)
				(type default)
			)
			(layer "F.Fab")
		)
		(fp_line
			(start 0.508 -0.3048)
			(end -0.508 -0.3048)
			(stroke
				(width 0.1)
				(type default)
			)
			(layer "F.Fab")
		)
		(fp_line
			(start 0.508 0.3048)
			(end 0.508 -0.3048)
			(stroke
				(width 0.1)
				(type default)
			)
			(layer "F.Fab")
		)
		(pad "1" smd rect
			(at -0.5334 0)
			(size 0.7112 0.6096)
			(layers "F.Cu" "F.Mask" "F.Paste")
			(net "MHZ200CLKP_CLKIN")
		)
		(pad "2" smd rect
			(at 0.5334 0)
			(size 0.7112 0.6096)
			(layers "F.Cu" "F.Mask" "F.Paste")
			(net "SG")
		)
		(zone
			(layer "F.Cu")
			(hatch none 0.5)
			(connect_pads
				(clearance 0)
			)
			(min_thickness 0.25)
			(keepout
				(tracks allowed)
				(vias not_allowed)
				(pads allowed)
				(copperpour not_allowed)
				(footprints allowed)
			)
			(placement
				(enabled no)
				(sheetname "")
			)
			(fill
				(thermal_gap 0.5)
				(thermal_bridge_width 0.5)
				(island_removal_mode 0)
			)
			(polygon
				(pts
					(xy 112.6363 -28.2194) (xy 112.7887 -28.2194) (xy 112.7887 -28.829) (xy 112.6363 -28.829)
				)
			)
		)
		(zone
			(layer "F.Cu")
			(hatch none 0.5)
			(connect_pads
				(clearance 0)
			)
			(min_thickness 0.25)
			(keepout
				(tracks not_allowed)
				(vias allowed)
				(pads allowed)
				(copperpour not_allowed)
				(footprints allowed)
			)
			(placement
				(enabled no)
				(sheetname "")
			)
			(fill
				(thermal_gap 0.5)
				(thermal_bridge_width 0.5)
				(island_removal_mode 0)
			)
			(polygon
				(pts
					(xy 112.6363 -28.2194) (xy 112.7887 -28.2194) (xy 112.7887 -28.829) (xy 112.6363 -28.829)
				)
			)
		)
	)
	(footprint ""
		(layer "F.Cu")
		(at 11.4808 -59.6138 -90)
		(property "Reference" "R498"
			(at -0.5842 1.40843 90)
			(unlocked yes)
			(layer "F.SilkS")
			(effects
				(font
					(size 0.7874 0.5842)
					(thickness 0.1524)
				)
			)
		)
		(property "Value" "VAL*"
			(at 0.02032 2.13233 270)
			(unlocked yes)
			(layer "F.Fab")
			(hide yes)
			(effects
				(font
					(size 0.7874 0.5842)
					(thickness 0.1524)
				)
			)
		)
		(property "Tolerance" "TOL*"
			(at 0.044704 3.05435 270)
			(unlocked yes)
			(layer "Cmts.User")
			(hide yes)
			(effects
				(font
					(size 0.7874 0.5842)
					(thickness 0.1524)
				)
			)
		)
		(property "User Part Number" "PARTNUM*"
			(at 0.02032 4.024884 270)
			(unlocked yes)
			(layer "Cmts.User")
			(hide yes)
			(effects
				(font
					(size 0.7874 0.5842)
					(thickness 0.1524)
				)
			)
		)
		(property "Device Type" "RESISTOR-G155-11004-01,1MOHM,1%"
			(at 0.008382 1.210564 270)
			(unlocked yes)
			(layer "F.Fab")
			(hide yes)
			(effects
				(font
					(size 0.7874 0.5842)
					(thickness 0.1524)
				)
			)
		)
		(duplicate_pad_numbers_are_jumpers no)
		(fp_line
			(start -1.143 0.5588)
			(end 1.143 0.5588)
			(stroke
				(width 0.1)
				(type default)
			)
			(layer "F.SilkS")
		)
		(fp_line
			(start 1.143 0.5588)
			(end 1.143 -0.5588)
			(stroke
				(width 0.1)
				(type default)
			)
			(layer "F.SilkS")
		)
		(fp_line
			(start -1.143 -0.5588)
			(end -1.143 0.5588)
			(stroke
				(width 0.1)
				(type default)
			)
			(layer "F.SilkS")
		)
		(fp_line
			(start 1.143 -0.5588)
			(end -1.143 -0.5588)
			(stroke
				(width 0.1)
				(type default)
			)
			(layer "F.SilkS")
		)
		(fp_poly
			(pts
				(xy -1.143 0.5588) (xy 1.143 0.5588) (xy 1.143 -0.5588) (xy -1.143 -0.5588)
			)
			(stroke
				(width 0)
				(type default)
			)
			(fill no)
			(layer "F.CrtYd")
		)
		(fp_line
			(start -0.508 0.3048)
			(end 0.508 0.3048)
			(stroke
				(width 0.1)
				(type default)
			)
			(layer "F.Fab")
		)
		(fp_line
			(start 0.508 0.3048)
			(end 0.508 -0.3048)
			(stroke
				(width 0.1)
				(type default)
			)
			(layer "F.Fab")
		)
		(fp_line
			(start -0.508 -0.3048)
			(end -0.508 0.3048)
			(stroke
				(width 0.1)
				(type default)
			)
			(layer "F.Fab")
		)
		(fp_line
			(start 0.508 -0.3048)
			(end -0.508 -0.3048)
			(stroke
				(width 0.1)
				(type default)
			)
			(layer "F.Fab")
		)
		(pad "1" smd rect
			(at -0.5334 0 270)
			(size 0.7112 0.6096)
			(layers "F.Cu" "F.Mask" "F.Paste")
			(net "SG")
		)
		(pad "2" smd rect
			(at 0.5334 0 270)
			(size 0.7112 0.6096)
			(layers "F.Cu" "F.Mask" "F.Paste")
			(net "BF_SMA1_SIG_IO_CONN")
		)
		(zone
			(layer "F.Cu")
			(hatch none 0.5)
			(connect_pads
				(clearance 0)
			)
			(min_thickness 0.25)
			(keepout
				(tracks allowed)
				(vias not_allowed)
				(pads allowed)
				(copperpour not_allowed)
				(footprints allowed)
			)
			(placement
				(enabled no)
				(sheetname "")
			)
			(fill
				(thermal_gap 0.5)
				(thermal_bridge_width 0.5)
				(island_removal_mode 0)
			)
			(polygon
				(pts
					(xy 11.176 -59.69) (xy 11.176 -59.5376) (xy 11.7856 -59.5376) (xy 11.7856 -59.69)
				)
			)
		)
		(zone
			(layer "F.Cu")
			(hatch none 0.5)
			(connect_pads
				(clearance 0)
			)
			(min_thickness 0.25)
			(keepout
				(tracks not_allowed)
				(vias allowed)
				(pads allowed)
				(copperpour not_allowed)
				(footprints allowed)
			)
			(placement
				(enabled no)
				(sheetname "")
			)
			(fill
				(thermal_gap 0.5)
				(thermal_bridge_width 0.5)
				(island_removal_mode 0)
			)
			(polygon
				(pts
					(xy 11.176 -59.69) (xy 11.176 -59.5376) (xy 11.7856 -59.5376) (xy 11.7856 -59.69)
				)
			)
		)
	)
	(footprint ""
		(layer "F.Cu")
		(at 135.763 -64.4144 180)
		(property "Reference" "TP56"
			(at -1.30175 -0.3048 90)
			(unlocked yes)
			(layer "F.SilkS")
			(effects
				(font
					(size 0.635 0.4064)
					(thickness 0.1524)
				)
				(justify left)
			)
		)
		(property "Value" ""
			(at 0 0 180)
			(layer "F.Fab")
			(effects
				(font
					(size 1.27 1.27)
				)
			)
		)
		(property "Device Type" "TP_PIONT-TP010CT020B030_PTH-TPA"
			(at -1.341882 0.996696 180)
			(unlocked yes)
			(layer "F.Fab")
			(hide yes)
			(effects
				(font
					(size 0.7874 0.5842)
					(thickness 0.1524)
				)
				(justify left)
			)
		)
		(duplicate_pad_numbers_are_jumpers no)
		(fp_poly
			(pts
				(arc
					(start -0.889 0)
					(mid 0.889 0)
					(end -0.889 0)
				)
			)
			(stroke
				(width 0)
				(type default)
			)
			(fill no)
			(layer "B.CrtYd")
		)
		(fp_poly
			(pts
				(arc
					(start -0.889 0)
					(mid 0.889 0)
					(end -0.889 0)
				)
			)
			(stroke
				(width 0)
				(type default)
			)
			(fill no)
			(layer "F.CrtYd")
		)
		(pad "1" thru_hole circle
			(at 0 0 180)
			(size 0.508 0.508)
			(drill 0.254)
			(layers "*.Cu" "*.Mask")
			(remove_unused_layers no)
			(net "XP1R8V_FPGA")
			(clearance 0.1016)
			(padstack
				(mode front_inner_back)
				(layer "Inner"
					(shape circle)
					(size 0.508 0.508)
					(clearance 0.1016)
				)
				(layer "B.Cu"
					(shape circle)
					(size 0.762 0.762)
					(clearance -0.0254)
				)
			)
		)
	)
	(footprint ""
		(layer "F.Cu")
		(at 134.62 -103.251)
		(property "Reference" "TP44"
			(at -3.8862 0.29337 0)
			(unlocked yes)
			(layer "F.SilkS")
			(effects
				(font
					(size 0.7874 0.5842)
					(thickness 0.1524)
				)
				(justify left)
			)
		)
		(property "Value" ""
			(at 0 0 0)
			(layer "F.Fab")
			(effects
				(font
					(size 1.27 1.27)
				)
			)
		)
		(property "Device Type" "TP_PIONT-TP010CT020B030_PTH-TPA"
			(at -1.341882 0.996696 0)
			(unlocked yes)
			(layer "F.Fab")
			(hide yes)
			(effects
				(font
					(size 0.7874 0.5842)
					(thickness 0.000001)
				)
				(justify left)
			)
		)
		(duplicate_pad_numbers_are_jumpers no)
		(fp_poly
			(pts
				(arc
					(start 0.889 0)
					(mid -0.889 0)
					(end 0.889 0)
				)
			)
			(stroke
				(width 0)
				(type default)
			)
			(fill no)
			(layer "B.CrtYd")
		)
		(fp_poly
			(pts
				(arc
					(start 0.889 0)
					(mid -0.889 0)
					(end 0.889 0)
				)
			)
			(stroke
				(width 0)
				(type default)
			)
			(fill no)
			(layer "F.CrtYd")
		)
		(pad "1" thru_hole circle
			(at 0 0)
			(size 0.508 0.508)
			(drill 0.254)
			(layers "*.Cu" "*.Mask")
			(remove_unused_layers no)
			(net "FPGA_DONE")
			(clearance 0.1016)
			(padstack
				(mode front_inner_back)
				(layer "Inner"
					(shape circle)
					(size 0.508 0.508)
					(clearance 0.1016)
				)
				(layer "B.Cu"
					(shape circle)
					(size 0.762 0.762)
					(clearance -0.0254)
				)
			)
		)
	)
	(footprint ""
		(layer "F.Cu")
		(at 48.26 -126.238)
		(property "Reference" "SP25"
			(at 0 0 0)
			(layer "F.SilkS")
			(hide yes)
			(effects
				(font
					(size 1.27 1.27)
				)
			)
		)
		(property "Value" ""
			(at 0 0 0)
			(layer "F.Fab")
			(effects
				(font
					(size 1.27 1.27)
				)
			)
		)
		(duplicate_pad_numbers_are_jumpers no)
	)
	(footprint ""
		(layer "F.Cu")
		(at 144.78 -54.102 -90)
		(property "Reference" "C262"
			(at 1.524 -3.08737 90)
			(unlocked yes)
			(layer "F.SilkS")
			(effects
				(font
					(size 0.7874 0.5842)
					(thickness 0.1524)
				)
			)
		)
		(property "Value" "VAL*"
			(at 0.0762 2.067306 270)
			(unlocked yes)
			(layer "F.Fab")
			(hide yes)
			(effects
				(font
					(size 0.7874 0.5842)
					(thickness 0.1524)
				)
			)
		)
		(property "Device Type" "CAPACITOR-G105-0B104-EK,0.1UF,A"
			(at 0.0508 1.127506 270)
			(unlocked yes)
			(layer "F.Fab")
			(hide yes)
			(effects
				(font
					(size 0.7874 0.5842)
					(thickness 0.1524)
				)
			)
		)
		(property "User Part Number" "PARTNUM*"
			(at 0.1016 4.023106 270)
			(unlocked yes)
			(layer "Cmts.User")
			(hide yes)
			(effects
				(font
					(size 0.7874 0.5842)
					(thickness 0.1524)
				)
			)
		)
		(property "Tolerance" "TOL*"
			(at 0.0762 3.032506 270)
			(unlocked yes)
			(layer "Cmts.User")
			(hide yes)
			(effects
				(font
					(size 0.7874 0.5842)
					(thickness 0.1524)
				)
			)
		)
		(duplicate_pad_numbers_are_jumpers no)
		(fp_line
			(start -1.143 0.5588)
			(end 1.143 0.5588)
			(stroke
				(width 0.1)
				(type default)
			)
			(layer "F.SilkS")
		)
		(fp_line
			(start 1.143 0.5588)
			(end 1.143 -0.5588)
			(stroke
				(width 0.1)
				(type default)
			)
			(layer "F.SilkS")
		)
		(fp_line
			(start -1.143 -0.5588)
			(end -1.143 0.5588)
			(stroke
				(width 0.1)
				(type default)
			)
			(layer "F.SilkS")
		)
		(fp_line
			(start 1.143 -0.5588)
			(end -1.143 -0.5588)
			(stroke
				(width 0.1)
				(type default)
			)
			(layer "F.SilkS")
		)
		(fp_rect
			(start 1.143 0.5588)
			(end -1.143 -0.5588)
			(stroke
				(width 0)
				(type default)
			)
			(fill no)
			(layer "F.CrtYd")
		)
		(fp_line
			(start -0.508 0.3048)
			(end 0.508 0.3048)
			(stroke
				(width 0.1)
				(type default)
			)
			(layer "F.Fab")
		)
		(fp_line
			(start 0.508 0.3048)
			(end 0.508 -0.3048)
			(stroke
				(width 0.1)
				(type default)
			)
			(layer "F.Fab")
		)
		(fp_line
			(start -0.508 -0.3048)
			(end -0.508 0.3048)
			(stroke
				(width 0.1)
				(type default)
			)
			(layer "F.Fab")
		)
		(fp_line
			(start 0.508 -0.3048)
			(end -0.508 -0.3048)
			(stroke
				(width 0.1)
				(type default)
			)
			(layer "F.Fab")
		)
		(pad "1" smd rect
			(at -0.5334 0 270)
			(size 0.7112 0.6096)
			(layers "F.Cu" "F.Mask" "F.Paste")
			(net "VIN_XP1R0V")
		)
		(pad "2" smd rect
			(at 0.5334 0 270)
			(size 0.7112 0.6096)
			(layers "F.Cu" "F.Mask" "F.Paste")
			(net "SG")
		)
		(zone
			(layer "F.Cu")
			(hatch none 0.5)
			(connect_pads
				(clearance 0)
			)
			(min_thickness 0.25)
			(keepout
				(tracks allowed)
				(vias not_allowed)
				(pads allowed)
				(copperpour not_allowed)
				(footprints allowed)
			)
			(placement
				(enabled no)
				(sheetname "")
			)
			(fill
				(thermal_gap 0.5)
				(thermal_bridge_width 0.5)
				(island_removal_mode 0)
			)
			(polygon
				(pts
					(xy 144.4752 -54.0258) (xy 145.0848 -54.0258) (xy 145.0848 -54.1782) (xy 144.4752 -54.1782)
				)
			)
		)
	)
	(footprint ""
		(layer "F.Cu")
		(at 162.56 -25.908 180)
		(property "Reference" "R414"
			(at -2.667 -0.80137 0)
			(unlocked yes)
			(layer "F.SilkS")
			(effects
				(font
					(size 0.7874 0.5842)
					(thickness 0.1524)
				)
			)
		)
		(property "Value" "VAL*"
			(at 0.02032 2.13233 180)
			(unlocked yes)
			(layer "F.Fab")
			(hide yes)
			(effects
				(font
					(size 0.7874 0.5842)
					(thickness 0.1524)
				)
			)
		)
		(property "Tolerance" "TOL*"
			(at 0.044704 3.05435 180)
			(unlocked yes)
			(layer "Cmts.User")
			(hide yes)
			(effects
				(font
					(size 0.7874 0.5842)
					(thickness 0.1524)
				)
			)
		)
		(property "User Part Number" "PARTNUM*"
			(at 0.02032 4.024884 180)
			(unlocked yes)
			(layer "Cmts.User")
			(hide yes)
			(effects
				(font
					(size 0.7874 0.5842)
					(thickness 0.1524)
				)
			)
		)
		(property "Device Type" "RESISTOR-G155-14701-01,4.7KOHMA"
			(at 0.008382 1.210564 180)
			(unlocked yes)
			(layer "F.Fab")
			(hide yes)
			(effects
				(font
					(size 0.7874 0.5842)
					(thickness 0.1524)
				)
			)
		)
		(duplicate_pad_numbers_are_jumpers no)
		(fp_line
			(start 1.143 0.5588)
			(end 1.143 -0.5588)
			(stroke
				(width 0.1)
				(type default)
			)
			(layer "F.SilkS")
		)
		(fp_line
			(start 1.143 -0.5588)
			(end -1.143 -0.5588)
			(stroke
				(width 0.1)
				(type default)
			)
			(layer "F.SilkS")
		)
		(fp_line
			(start -1.143 0.5588)
			(end 1.143 0.5588)
			(stroke
				(width 0.1)
				(type default)
			)
			(layer "F.SilkS")
		)
		(fp_line
			(start -1.143 -0.5588)
			(end -1.143 0.5588)
			(stroke
				(width 0.1)
				(type default)
			)
			(layer "F.SilkS")
		)
		(fp_rect
			(start 1.143 -0.5588)
			(end -1.143 0.5588)
			(stroke
				(width 0)
				(type default)
			)
			(fill no)
			(layer "F.CrtYd")
		)
		(fp_line
			(start 0.508 0.3048)
			(end 0.508 -0.3048)
			(stroke
				(width 0.1)
				(type default)
			)
			(layer "F.Fab")
		)
		(fp_line
			(start 0.508 -0.3048)
			(end -0.508 -0.3048)
			(stroke
				(width 0.1)
				(type default)
			)
			(layer "F.Fab")
		)
		(fp_line
			(start -0.508 0.3048)
			(end 0.508 0.3048)
			(stroke
				(width 0.1)
				(type default)
			)
			(layer "F.Fab")
		)
		(fp_line
			(start -0.508 -0.3048)
			(end -0.508 0.3048)
			(stroke
				(width 0.1)
				(type default)
			)
			(layer "F.Fab")
		)
		(pad "1" smd rect
			(at -0.5334 0 180)
			(size 0.7112 0.6096)
			(layers "F.Cu" "F.Mask" "F.Paste")
			(net "XP3R3V_FPGA")
		)
		(pad "2" smd rect
			(at 0.5334 0 180)
			(size 0.7112 0.6096)
			(layers "F.Cu" "F.Mask" "F.Paste")
			(net "UNNAMED_6_LM75BDPTSSOP8_I81_A1")
		)
		(zone
			(layer "F.Cu")
			(hatch none 0.5)
			(connect_pads
				(clearance 0)
			)
			(min_thickness 0.25)
			(keepout
				(tracks allowed)
				(vias not_allowed)
				(pads allowed)
				(copperpour not_allowed)
				(footprints allowed)
			)
			(placement
				(enabled no)
				(sheetname "")
			)
			(fill
				(thermal_gap 0.5)
				(thermal_bridge_width 0.5)
				(island_removal_mode 0)
			)
			(polygon
				(pts
					(xy 162.4838 -25.6032) (xy 162.6362 -25.6032) (xy 162.6362 -26.2128) (xy 162.4838 -26.2128)
				)
			)
		)
		(zone
			(layer "F.Cu")
			(hatch none 0.5)
			(connect_pads
				(clearance 0)
			)
			(min_thickness 0.25)
			(keepout
				(tracks not_allowed)
				(vias allowed)
				(pads allowed)
				(copperpour not_allowed)
				(footprints allowed)
			)
			(placement
				(enabled no)
				(sheetname "")
			)
			(fill
				(thermal_gap 0.5)
				(thermal_bridge_width 0.5)
				(island_removal_mode 0)
			)
			(polygon
				(pts
					(xy 162.4838 -25.6032) (xy 162.6362 -25.6032) (xy 162.6362 -26.2128) (xy 162.4838 -26.2128)
				)
			)
		)
	)
	(footprint ""
		(layer "F.Cu")
		(at 124.587 -50.165 180)
		(property "Reference" "R94"
			(at -0.127 -2.45237 0)
			(unlocked yes)
			(layer "F.SilkS")
			(effects
				(font
					(size 0.7874 0.5842)
					(thickness 0.1524)
				)
			)
		)
		(property "Value" "VAL*"
			(at 0.02032 2.13233 180)
			(unlocked yes)
			(layer "F.Fab")
			(hide yes)
			(effects
				(font
					(size 0.7874 0.5842)
					(thickness 0.1524)
				)
			)
		)
		(property "Device Type" "RESISTOR-G155-133R0-01,33OHM,1%"
			(at 0.008382 1.210564 180)
			(unlocked yes)
			(layer "F.Fab")
			(hide yes)
			(effects
				(font
					(size 0.7874 0.5842)
					(thickness 0.1524)
				)
			)
		)
		(property "User Part Number" "PARTNUM*"
			(at 0.02032 4.024884 180)
			(unlocked yes)
			(layer "Cmts.User")
			(hide yes)
			(effects
				(font
					(size 0.7874 0.5842)
					(thickness 0.1524)
				)
			)
		)
		(property "Tolerance" "TOL*"
			(at 0.044704 3.05435 180)
			(unlocked yes)
			(layer "Cmts.User")
			(hide yes)
			(effects
				(font
					(size 0.7874 0.5842)
					(thickness 0.1524)
				)
			)
		)
		(duplicate_pad_numbers_are_jumpers no)
		(fp_line
			(start 1.143 0.5588)
			(end 1.143 -0.5588)
			(stroke
				(width 0.1)
				(type default)
			)
			(layer "F.SilkS")
		)
		(fp_line
			(start 1.143 -0.5588)
			(end -1.143 -0.5588)
			(stroke
				(width 0.1)
				(type default)
			)
			(layer "F.SilkS")
		)
		(fp_line
			(start -1.143 0.5588)
			(end 1.143 0.5588)
			(stroke
				(width 0.1)
				(type default)
			)
			(layer "F.SilkS")
		)
		(fp_line
			(start -1.143 -0.5588)
			(end -1.143 0.5588)
			(stroke
				(width 0.1)
				(type default)
			)
			(layer "F.SilkS")
		)
		(fp_rect
			(start 1.143 -0.5588)
			(end -1.143 0.5588)
			(stroke
				(width 0)
				(type default)
			)
			(fill no)
			(layer "F.CrtYd")
		)
		(fp_line
			(start 0.508 0.3048)
			(end 0.508 -0.3048)
			(stroke
				(width 0.1)
				(type default)
			)
			(layer "F.Fab")
		)
		(fp_line
			(start 0.508 -0.3048)
			(end -0.508 -0.3048)
			(stroke
				(width 0.1)
				(type default)
			)
			(layer "F.Fab")
		)
		(fp_line
			(start -0.508 0.3048)
			(end 0.508 0.3048)
			(stroke
				(width 0.1)
				(type default)
			)
			(layer "F.Fab")
		)
		(fp_line
			(start -0.508 -0.3048)
			(end -0.508 0.3048)
			(stroke
				(width 0.1)
				(type default)
			)
			(layer "F.Fab")
		)
		(pad "1" smd rect
			(at -0.5334 0 180)
			(size 0.7112 0.6096)
			(layers "F.Cu" "F.Mask" "F.Paste")
			(net "R_MAC_UART_TX_FPGA_RX")
		)
		(pad "2" smd rect
			(at 0.5334 0 180)
			(size 0.7112 0.6096)
			(layers "F.Cu" "F.Mask" "F.Paste")
			(net "UART_MAC_TX_FPGA_RX")
		)
		(zone
			(layer "F.Cu")
			(hatch none 0.5)
			(connect_pads
				(clearance 0)
			)
			(min_thickness 0.25)
			(keepout
				(tracks allowed)
				(vias not_allowed)
				(pads allowed)
				(copperpour not_allowed)
				(footprints allowed)
			)
			(placement
				(enabled no)
				(sheetname "")
			)
			(fill
				(thermal_gap 0.5)
				(thermal_bridge_width 0.5)
				(island_removal_mode 0)
			)
			(polygon
				(pts
					(xy 124.5108 -49.8602) (xy 124.6632 -49.8602) (xy 124.6632 -50.4698) (xy 124.5108 -50.4698)
				)
			)
		)
	)
	(footprint ""
		(layer "F.Cu")
		(at 115.189 -59.563 90)
		(property "Reference" "R238"
			(at -0.635 -1.86563 90)
			(unlocked yes)
			(layer "F.SilkS")
			(effects
				(font
					(size 0.7874 0.5842)
					(thickness 0.1524)
				)
			)
		)
		(property "Value" "VAL*"
			(at 0.02032 2.13233 90)
			(unlocked yes)
			(layer "F.Fab")
			(hide yes)
			(effects
				(font
					(size 0.7874 0.5842)
					(thickness 0.1524)
				)
			)
		)
		(property "Tolerance" "TOL*"
			(at 0.044704 3.05435 90)
			(unlocked yes)
			(layer "Cmts.User")
			(hide yes)
			(effects
				(font
					(size 0.7874 0.5842)
					(thickness 0.1524)
				)
			)
		)
		(property "User Part Number" "PARTNUM*"
			(at 0.02032 4.024884 90)
			(unlocked yes)
			(layer "Cmts.User")
			(hide yes)
			(effects
				(font
					(size 0.7874 0.5842)
					(thickness 0.1524)
				)
			)
		)
		(property "Device Type" "RESISTOR-G155-133R0-01,33OHM,1%"
			(at 0.008382 1.210564 90)
			(unlocked yes)
			(layer "F.Fab")
			(hide yes)
			(effects
				(font
					(size 0.7874 0.5842)
					(thickness 0.1524)
				)
			)
		)
		(duplicate_pad_numbers_are_jumpers no)
		(fp_line
			(start 1.143 -0.5588)
			(end -1.143 -0.5588)
			(stroke
				(width 0.1)
				(type default)
			)
			(layer "F.SilkS")
		)
		(fp_line
			(start -1.143 -0.5588)
			(end -1.143 0.5588)
			(stroke
				(width 0.1)
				(type default)
			)
			(layer "F.SilkS")
		)
		(fp_line
			(start 1.143 0.5588)
			(end 1.143 -0.5588)
			(stroke
				(width 0.1)
				(type default)
			)
			(layer "F.SilkS")
		)
		(fp_line
			(start -1.143 0.5588)
			(end 1.143 0.5588)
			(stroke
				(width 0.1)
				(type default)
			)
			(layer "F.SilkS")
		)
		(fp_poly
			(pts
				(xy -1.143 0.5588) (xy 1.143 0.5588) (xy 1.143 -0.5588) (xy -1.143 -0.5588)
			)
			(stroke
				(width 0)
				(type default)
			)
			(fill no)
			(layer "F.CrtYd")
		)
		(fp_line
			(start 0.508 -0.3048)
			(end -0.508 -0.3048)
			(stroke
				(width 0.1)
				(type default)
			)
			(layer "F.Fab")
		)
		(fp_line
			(start -0.508 -0.3048)
			(end -0.508 0.3048)
			(stroke
				(width 0.1)
				(type default)
			)
			(layer "F.Fab")
		)
		(fp_line
			(start 0.508 0.3048)
			(end 0.508 -0.3048)
			(stroke
				(width 0.1)
				(type default)
			)
			(layer "F.Fab")
		)
		(fp_line
			(start -0.508 0.3048)
			(end 0.508 0.3048)
			(stroke
				(width 0.1)
				(type default)
			)
			(layer "F.Fab")
		)
		(pad "1" smd rect
			(at -0.5334 0 90)
			(size 0.7112 0.6096)
			(layers "F.Cu" "F.Mask" "F.Paste")
			(net "FPGA_D01")
		)
		(pad "2" smd rect
			(at 0.5334 0 90)
			(size 0.7112 0.6096)
			(layers "F.Cu" "F.Mask" "F.Paste")
			(net "FPGA_FLASH_DQ1_MISO")
		)
		(zone
			(layer "F.Cu")
			(hatch none 0.5)
			(connect_pads
				(clearance 0)
			)
			(min_thickness 0.25)
			(keepout
				(tracks allowed)
				(vias not_allowed)
				(pads allowed)
				(copperpour not_allowed)
				(footprints allowed)
			)
			(placement
				(enabled no)
				(sheetname "")
			)
			(fill
				(thermal_gap 0.5)
				(thermal_bridge_width 0.5)
				(island_removal_mode 0)
			)
			(polygon
				(pts
					(xy 115.4938 -59.4868) (xy 115.4938 -59.6392) (xy 114.8842 -59.6392) (xy 114.8842 -59.4868)
				)
			)
		)
		(zone
			(layer "F.Cu")
			(hatch none 0.5)
			(connect_pads
				(clearance 0)
			)
			(min_thickness 0.25)
			(keepout
				(tracks not_allowed)
				(vias allowed)
				(pads allowed)
				(copperpour not_allowed)
				(footprints allowed)
			)
			(placement
				(enabled no)
				(sheetname "")
			)
			(fill
				(thermal_gap 0.5)
				(thermal_bridge_width 0.5)
				(island_removal_mode 0)
			)
			(polygon
				(pts
					(xy 115.4938 -59.4868) (xy 115.4938 -59.6392) (xy 114.8842 -59.6392) (xy 114.8842 -59.4868)
				)
			)
		)
	)
	(footprint ""
		(layer "F.Cu")
		(at 33.77438 -19.1262 180)
		(property "Reference" "R313"
			(at -3.05562 -0.75057 0)
			(unlocked yes)
			(layer "F.SilkS")
			(effects
				(font
					(size 0.7874 0.5842)
					(thickness 0.1524)
				)
			)
		)
		(property "Value" "VAL*"
			(at 0.02032 2.13233 180)
			(unlocked yes)
			(layer "F.Fab")
			(hide yes)
			(effects
				(font
					(size 0.7874 0.5842)
					(thickness 0.1524)
				)
			)
		)
		(property "Device Type" "RESISTOR-G155-100R0-J0,0OHM,-"
			(at 0.008382 1.210564 180)
			(unlocked yes)
			(layer "F.Fab")
			(hide yes)
			(effects
				(font
					(size 0.7874 0.5842)
					(thickness 0.1524)
				)
			)
		)
		(property "User Part Number" "PARTNUM*"
			(at 0.02032 4.024884 180)
			(unlocked yes)
			(layer "Cmts.User")
			(hide yes)
			(effects
				(font
					(size 0.7874 0.5842)
					(thickness 0.1524)
				)
			)
		)
		(property "Tolerance" "TOL*"
			(at 0.044704 3.05435 180)
			(unlocked yes)
			(layer "Cmts.User")
			(hide yes)
			(effects
				(font
					(size 0.7874 0.5842)
					(thickness 0.1524)
				)
			)
		)
		(duplicate_pad_numbers_are_jumpers no)
		(fp_line
			(start 1.143 0.5588)
			(end 1.143 -0.5588)
			(stroke
				(width 0.1)
				(type default)
			)
			(layer "F.SilkS")
		)
		(fp_line
			(start 1.143 -0.5588)
			(end -1.143 -0.5588)
			(stroke
				(width 0.1)
				(type default)
			)
			(layer "F.SilkS")
		)
		(fp_line
			(start -1.143 0.5588)
			(end 1.143 0.5588)
			(stroke
				(width 0.1)
				(type default)
			)
			(layer "F.SilkS")
		)
		(fp_line
			(start -1.143 -0.5588)
			(end -1.143 0.5588)
			(stroke
				(width 0.1)
				(type default)
			)
			(layer "F.SilkS")
		)
		(fp_poly
			(pts
				(xy -1.143 0.5588) (xy 1.143 0.5588) (xy 1.143 -0.5588) (xy -1.143 -0.5588)
			)
			(stroke
				(width 0)
				(type default)
			)
			(fill no)
			(layer "F.CrtYd")
		)
		(fp_line
			(start 0.508 0.3048)
			(end 0.508 -0.3048)
			(stroke
				(width 0.1)
				(type default)
			)
			(layer "F.Fab")
		)
		(fp_line
			(start 0.508 -0.3048)
			(end -0.508 -0.3048)
			(stroke
				(width 0.1)
				(type default)
			)
			(layer "F.Fab")
		)
		(fp_line
			(start -0.508 0.3048)
			(end 0.508 0.3048)
			(stroke
				(width 0.1)
				(type default)
			)
			(layer "F.Fab")
		)
		(fp_line
			(start -0.508 -0.3048)
			(end -0.508 0.3048)
			(stroke
				(width 0.1)
				(type default)
			)
			(layer "F.Fab")
		)
		(pad "1" smd rect
			(at -0.5334 0 180)
			(size 0.7112 0.6096)
			(layers "F.Cu" "F.Mask" "F.Paste")
			(net "RGB_LED_I2C_SCL")
		)
		(pad "2" smd rect
			(at 0.5334 0 180)
			(size 0.7112 0.6096)
			(layers "F.Cu" "F.Mask" "F.Paste")
			(net "EEPROM_SCL")
		)
		(zone
			(layer "F.Cu")
			(hatch none 0.5)
			(connect_pads
				(clearance 0)
			)
			(min_thickness 0.25)
			(keepout
				(tracks not_allowed)
				(vias allowed)
				(pads allowed)
				(copperpour not_allowed)
				(footprints allowed)
			)
			(placement
				(enabled no)
				(sheetname "")
			)
			(fill
				(thermal_gap 0.5)
				(thermal_bridge_width 0.5)
				(island_removal_mode 0)
			)
			(polygon
				(pts
					(xy 33.85058 -19.431) (xy 33.69818 -19.431) (xy 33.69818 -18.8214) (xy 33.85058 -18.8214)
				)
			)
		)
		(zone
			(layer "F.Cu")
			(hatch none 0.5)
			(connect_pads
				(clearance 0)
			)
			(min_thickness 0.25)
			(keepout
				(tracks allowed)
				(vias not_allowed)
				(pads allowed)
				(copperpour not_allowed)
				(footprints allowed)
			)
			(placement
				(enabled no)
				(sheetname "")
			)
			(fill
				(thermal_gap 0.5)
				(thermal_bridge_width 0.5)
				(island_removal_mode 0)
			)
			(polygon
				(pts
					(xy 33.85058 -19.431) (xy 33.69818 -19.431) (xy 33.69818 -18.8214) (xy 33.85058 -18.8214)
				)
			)
		)
	)
	(footprint ""
		(layer "F.Cu")
		(at 19.468338 -45.593 180)
		(property "Reference" "R400"
			(at -3.518662 0.08763 0)
			(unlocked yes)
			(layer "F.SilkS")
			(effects
				(font
					(size 0.7874 0.5842)
					(thickness 0.1524)
				)
			)
		)
		(property "Value" "VAL*"
			(at 0.02032 2.13233 180)
			(unlocked yes)
			(layer "F.Fab")
			(hide yes)
			(effects
				(font
					(size 0.7874 0.5842)
					(thickness 0.1524)
				)
			)
		)
		(property "Device Type" "RESISTOR-G155-11000-01,100OHM,A"
			(at 0.008382 1.210564 180)
			(unlocked yes)
			(layer "F.Fab")
			(hide yes)
			(effects
				(font
					(size 0.7874 0.5842)
					(thickness 0.1524)
				)
			)
		)
		(property "User Part Number" "PARTNUM*"
			(at 0.02032 4.024884 180)
			(unlocked yes)
			(layer "Cmts.User")
			(hide yes)
			(effects
				(font
					(size 0.7874 0.5842)
					(thickness 0.1524)
				)
			)
		)
		(property "Tolerance" "TOL*"
			(at 0.044704 3.05435 180)
			(unlocked yes)
			(layer "Cmts.User")
			(hide yes)
			(effects
				(font
					(size 0.7874 0.5842)
					(thickness 0.1524)
				)
			)
		)
		(duplicate_pad_numbers_are_jumpers no)
		(fp_line
			(start 1.143 0.5588)
			(end 1.143 -0.5588)
			(stroke
				(width 0.1)
				(type default)
			)
			(layer "F.SilkS")
		)
		(fp_line
			(start 1.143 -0.5588)
			(end -1.143 -0.5588)
			(stroke
				(width 0.1)
				(type default)
			)
			(layer "F.SilkS")
		)
		(fp_line
			(start -1.143 0.5588)
			(end 1.143 0.5588)
			(stroke
				(width 0.1)
				(type default)
			)
			(layer "F.SilkS")
		)
		(fp_line
			(start -1.143 -0.5588)
			(end -1.143 0.5588)
			(stroke
				(width 0.1)
				(type default)
			)
			(layer "F.SilkS")
		)
		(fp_poly
			(pts
				(xy -1.143 0.5588) (xy 1.143 0.5588) (xy 1.143 -0.5588) (xy -1.143 -0.5588)
			)
			(stroke
				(width 0)
				(type default)
			)
			(fill no)
			(layer "F.CrtYd")
		)
		(fp_line
			(start 0.508 0.3048)
			(end 0.508 -0.3048)
			(stroke
				(width 0.1)
				(type default)
			)
			(layer "F.Fab")
		)
		(fp_line
			(start 0.508 -0.3048)
			(end -0.508 -0.3048)
			(stroke
				(width 0.1)
				(type default)
			)
			(layer "F.Fab")
		)
		(fp_line
			(start -0.508 0.3048)
			(end 0.508 0.3048)
			(stroke
				(width 0.1)
				(type default)
			)
			(layer "F.Fab")
		)
		(fp_line
			(start -0.508 -0.3048)
			(end -0.508 0.3048)
			(stroke
				(width 0.1)
				(type default)
			)
			(layer "F.Fab")
		)
		(pad "1" smd rect
			(at -0.5334 0 180)
			(size 0.7112 0.6096)
			(layers "F.Cu" "F.Mask" "F.Paste")
			(net "FPGA_OUT_SMA4_LED_BLUE_N")
		)
		(pad "2" smd rect
			(at 0.5334 0 180)
			(size 0.7112 0.6096)
			(layers "F.Cu" "F.Mask" "F.Paste")
			(net "UNNAMED_14_LED4PV14_I268_1")
		)
		(zone
			(layer "F.Cu")
			(hatch none 0.5)
			(connect_pads
				(clearance 0)
			)
			(min_thickness 0.25)
			(keepout
				(tracks not_allowed)
				(vias allowed)
				(pads allowed)
				(copperpour not_allowed)
				(footprints allowed)
			)
			(placement
				(enabled no)
				(sheetname "")
			)
			(fill
				(thermal_gap 0.5)
				(thermal_bridge_width 0.5)
				(island_removal_mode 0)
			)
			(polygon
				(pts
					(xy 19.544538 -45.8978) (xy 19.392138 -45.8978) (xy 19.392138 -45.2882) (xy 19.544538 -45.2882)
				)
			)
		)
		(zone
			(layer "F.Cu")
			(hatch none 0.5)
			(connect_pads
				(clearance 0)
			)
			(min_thickness 0.25)
			(keepout
				(tracks allowed)
				(vias not_allowed)
				(pads allowed)
				(copperpour not_allowed)
				(footprints allowed)
			)
			(placement
				(enabled no)
				(sheetname "")
			)
			(fill
				(thermal_gap 0.5)
				(thermal_bridge_width 0.5)
				(island_removal_mode 0)
			)
			(polygon
				(pts
					(xy 19.544538 -45.8978) (xy 19.392138 -45.8978) (xy 19.392138 -45.2882) (xy 19.544538 -45.2882)
				)
			)
		)
	)
	(footprint ""
		(layer "F.Cu")
		(at 20.8534 -59.3598 90)
		(property "Reference" "U32"
			(at 0.0762 2.68097 90)
			(unlocked yes)
			(layer "F.SilkS")
			(effects
				(font
					(size 0.7874 0.5842)
					(thickness 0.1524)
				)
			)
		)
		(property "Value" ""
			(at 0 0 90)
			(layer "F.Fab")
			(effects
				(font
					(size 1.27 1.27)
				)
			)
		)
		(property "Device Type" "PCA9508DP_TSSOP8-G223-10278-01"
			(at -0.03175 2.55651 90)
			(unlocked yes)
			(layer "F.Fab")
			(hide yes)
			(effects
				(font
					(size 0.7874 0.5842)
					(thickness 0.1524)
				)
			)
		)
		(property "User Part Number" "PARTNUM*"
			(at -0.037592 3.488182 90)
			(unlocked yes)
			(layer "Cmts.User")
			(hide yes)
			(effects
				(font
					(size 0.7874 0.5842)
					(thickness 0.1524)
				)
			)
		)
		(duplicate_pad_numbers_are_jumpers no)
		(fp_line
			(start 1.778 -1.778)
			(end -1.778 -1.778)
			(stroke
				(width 0.1)
				(type default)
			)
			(layer "F.SilkS")
		)
		(fp_line
			(start -1.778 -1.778)
			(end -1.778 -1.45796)
			(stroke
				(width 0.1)
				(type default)
			)
			(layer "F.SilkS")
		)
		(fp_line
			(start 3.3147 -1.45796)
			(end 1.778 -1.45796)
			(stroke
				(width 0.1)
				(type default)
			)
			(layer "F.SilkS")
		)
		(fp_line
			(start 1.778 -1.45796)
			(end 1.778 -1.778)
			(stroke
				(width 0.1)
				(type default)
			)
			(layer "F.SilkS")
		)
		(fp_line
			(start -1.778 -1.45796)
			(end -3.3147 -1.45796)
			(stroke
				(width 0.1)
				(type default)
			)
			(layer "F.SilkS")
		)
		(fp_line
			(start -3.3147 -1.45796)
			(end -3.3147 1.45796)
			(stroke
				(width 0.1)
				(type default)
			)
			(layer "F.SilkS")
		)
		(fp_line
			(start 3.3147 1.45796)
			(end 3.3147 -1.45796)
			(stroke
				(width 0.1)
				(type default)
			)
			(layer "F.SilkS")
		)
		(fp_line
			(start 1.778 1.45796)
			(end 3.3147 1.45796)
			(stroke
				(width 0.1)
				(type default)
			)
			(layer "F.SilkS")
		)
		(fp_line
			(start -1.778 1.45796)
			(end -1.778 1.778)
			(stroke
				(width 0.1)
				(type default)
			)
			(layer "F.SilkS")
		)
		(fp_line
			(start -3.3147 1.45796)
			(end -1.778 1.45796)
			(stroke
				(width 0.1)
				(type default)
			)
			(layer "F.SilkS")
		)
		(fp_line
			(start 1.778 1.778)
			(end 1.778 1.45796)
			(stroke
				(width 0.1)
				(type default)
			)
			(layer "F.SilkS")
		)
		(fp_line
			(start -1.778 1.778)
			(end 1.778 1.778)
			(stroke
				(width 0.1)
				(type default)
			)
			(layer "F.SilkS")
		)
		(fp_poly
			(pts
				(arc
					(start -3.3528 -1.6764)
					(mid -3.3528 -2.4384)
					(end -3.3528 -1.6764)
				)
			)
			(stroke
				(width 0)
				(type default)
			)
			(fill yes)
			(layer "F.SilkS")
		)
		(fp_poly
			(pts
				(xy -3.5687 -2.032) (xy -3.5687 2.032) (xy 3.5687 2.032) (xy 3.5687 -2.032)
			)
			(stroke
				(width 0)
				(type default)
			)
			(fill no)
			(layer "F.CrtYd")
		)
		(fp_line
			(start 1.524 -1.524)
			(end 1.524 1.524)
			(stroke
				(width 0.1)
				(type default)
			)
			(layer "F.Fab")
		)
		(fp_line
			(start -1.524 -1.524)
			(end 1.524 -1.524)
			(stroke
				(width 0.1)
				(type default)
			)
			(layer "F.Fab")
		)
		(fp_line
			(start 1.524 1.524)
			(end -1.524 1.524)
			(stroke
				(width 0.1)
				(type default)
			)
			(layer "F.Fab")
		)
		(fp_line
			(start -1.524 1.524)
			(end -1.524 -1.524)
			(stroke
				(width 0.1)
				(type default)
			)
			(layer "F.Fab")
		)
		(fp_poly
			(pts
				(arc
					(start -0.9906 -0.5588)
					(mid -0.9906 -1.3208)
					(end -0.9906 -0.5588)
				)
			)
			(stroke
				(width 0)
				(type default)
			)
			(fill yes)
			(layer "F.Fab")
		)
		(fp_text user "8"
			(at 3.72745 -2.0574 0)
			(unlocked yes)
			(layer "F.SilkS")
			(effects
				(font
					(size 0.635 0.4064)
					(thickness 0.1524)
				)
			)
		)
		(fp_text user "4"
			(at -2.95275 2.1336 0)
			(unlocked yes)
			(layer "F.SilkS")
			(effects
				(font
					(size 0.635 0.4064)
					(thickness 0.1524)
				)
			)
		)
		(fp_text user "5"
			(at 2.96545 2.2606 0)
			(unlocked yes)
			(layer "F.SilkS")
			(effects
				(font
					(size 0.635 0.4064)
					(thickness 0.1524)
				)
			)
		)
		(fp_text user "8"
			(at 2.32283 -1.5494 0)
			(unlocked yes)
			(layer "F.Fab")
			(effects
				(font
					(size 0.7874 0.5842)
					(thickness 0.1524)
				)
			)
		)
		(fp_text user "4"
			(at -2.75717 1.4986 0)
			(unlocked yes)
			(layer "F.Fab")
			(effects
				(font
					(size 0.7874 0.5842)
					(thickness 0.1524)
				)
			)
		)
		(fp_text user "5"
			(at 2.32283 1.6256 0)
			(unlocked yes)
			(layer "F.Fab")
			(effects
				(font
					(size 0.7874 0.5842)
					(thickness 0.1524)
				)
			)
		)
		(pad "1" smd rect
			(at -2.2987 -0.97536 180)
			(size 0.4572 1.524)
			(layers "F.Cu" "F.Mask" "F.Paste")
			(net "XP1R8V_ICP10100")
		)
		(pad "2" smd rect
			(at -2.2987 -0.32512 180)
			(size 0.4572 1.524)
			(layers "F.Cu" "F.Mask" "F.Paste")
			(net "BF_ICP10100_I2C_SCL")
		)
		(pad "3" smd rect
			(at -2.2987 0.32512 180)
			(size 0.4572 1.524)
			(layers "F.Cu" "F.Mask" "F.Paste")
			(net "BF_ICP10100_I2C_SDA")
		)
		(pad "4" smd rect
			(at -2.2987 0.97536 180)
			(size 0.4572 1.524)
			(layers "F.Cu" "F.Mask" "F.Paste")
			(net "SG")
		)
		(pad "5" smd rect
			(at 2.2987 0.97536 180)
			(size 0.4572 1.524)
			(layers "F.Cu" "F.Mask" "F.Paste")
			(net "UNNAMED_8_PCA9508DPTSSOP8_I51_E")
		)
		(pad "6" smd rect
			(at 2.2987 0.32512 180)
			(size 0.4572 1.524)
			(layers "F.Cu" "F.Mask" "F.Paste")
			(net "ICP10100_I2C_SDA")
		)
		(pad "7" smd rect
			(at 2.2987 -0.32512 180)
			(size 0.4572 1.524)
			(layers "F.Cu" "F.Mask" "F.Paste")
			(net "ICP10100_I2C_SCL")
		)
		(pad "8" smd rect
			(at 2.2987 -0.97536 180)
			(size 0.4572 1.524)
			(layers "F.Cu" "F.Mask" "F.Paste")
			(net "XP3R3V")
		)
	)
	(footprint ""
		(layer "F.Cu")
		(at 150.749 -28.575 180)
		(property "Reference" "R20"
			(at 1.143 1.99263 0)
			(unlocked yes)
			(layer "F.SilkS")
			(effects
				(font
					(size 0.7874 0.5842)
					(thickness 0.1524)
				)
			)
		)
		(property "Value" "VAL*"
			(at 0.02032 2.13233 180)
			(unlocked yes)
			(layer "F.Fab")
			(hide yes)
			(effects
				(font
					(size 0.7874 0.5842)
					(thickness 0.1524)
				)
			)
		)
		(property "Tolerance" "TOL*"
			(at 0.044704 3.05435 180)
			(unlocked yes)
			(layer "Cmts.User")
			(hide yes)
			(effects
				(font
					(size 0.7874 0.5842)
					(thickness 0.1524)
				)
			)
		)
		(property "User Part Number" "PARTNUM*"
			(at 0.02032 4.024884 180)
			(unlocked yes)
			(layer "Cmts.User")
			(hide yes)
			(effects
				(font
					(size 0.7874 0.5842)
					(thickness 0.1524)
				)
			)
		)
		(property "Device Type" "RESISTOR-G155-14701-01,4.7KOHMA"
			(at 0.008382 1.210564 180)
			(unlocked yes)
			(layer "F.Fab")
			(hide yes)
			(effects
				(font
					(size 0.7874 0.5842)
					(thickness 0.1524)
				)
			)
		)
		(duplicate_pad_numbers_are_jumpers no)
		(fp_line
			(start 1.143 0.5588)
			(end 1.143 -0.5588)
			(stroke
				(width 0.1)
				(type default)
			)
			(layer "F.SilkS")
		)
		(fp_line
			(start 1.143 -0.5588)
			(end -1.143 -0.5588)
			(stroke
				(width 0.1)
				(type default)
			)
			(layer "F.SilkS")
		)
		(fp_line
			(start -1.143 0.5588)
			(end 1.143 0.5588)
			(stroke
				(width 0.1)
				(type default)
			)
			(layer "F.SilkS")
		)
		(fp_line
			(start -1.143 -0.5588)
			(end -1.143 0.5588)
			(stroke
				(width 0.1)
				(type default)
			)
			(layer "F.SilkS")
		)
		(fp_rect
			(start 1.143 -0.5588)
			(end -1.143 0.5588)
			(stroke
				(width 0)
				(type default)
			)
			(fill no)
			(layer "F.CrtYd")
		)
		(fp_line
			(start 0.508 0.3048)
			(end 0.508 -0.3048)
			(stroke
				(width 0.1)
				(type default)
			)
			(layer "F.Fab")
		)
		(fp_line
			(start 0.508 -0.3048)
			(end -0.508 -0.3048)
			(stroke
				(width 0.1)
				(type default)
			)
			(layer "F.Fab")
		)
		(fp_line
			(start -0.508 0.3048)
			(end 0.508 0.3048)
			(stroke
				(width 0.1)
				(type default)
			)
			(layer "F.Fab")
		)
		(fp_line
			(start -0.508 -0.3048)
			(end -0.508 0.3048)
			(stroke
				(width 0.1)
				(type default)
			)
			(layer "F.Fab")
		)
		(pad "1" smd rect
			(at -0.5334 0 180)
			(size 0.7112 0.6096)
			(layers "F.Cu" "F.Mask" "F.Paste")
			(net "XP3R3V_FPGA")
		)
		(pad "2" smd rect
			(at 0.5334 0 180)
			(size 0.7112 0.6096)
			(layers "F.Cu" "F.Mask" "F.Paste")
			(net "LM75B_I2C_SDA")
		)
		(zone
			(layer "F.Cu")
			(hatch none 0.5)
			(connect_pads
				(clearance 0)
			)
			(min_thickness 0.25)
			(keepout
				(tracks allowed)
				(vias not_allowed)
				(pads allowed)
				(copperpour not_allowed)
				(footprints allowed)
			)
			(placement
				(enabled no)
				(sheetname "")
			)
			(fill
				(thermal_gap 0.5)
				(thermal_bridge_width 0.5)
				(island_removal_mode 0)
			)
			(polygon
				(pts
					(xy 150.6728 -28.2702) (xy 150.8252 -28.2702) (xy 150.8252 -28.8798) (xy 150.6728 -28.8798)
				)
			)
		)
	)
	(footprint ""
		(layer "F.Cu")
		(at 162.56 -27.432 180)
		(property "Reference" "R419"
			(at -2.667 0.72263 0)
			(unlocked yes)
			(layer "F.SilkS")
			(effects
				(font
					(size 0.7874 0.5842)
					(thickness 0.1524)
				)
			)
		)
		(property "Value" "VAL*"
			(at 0.02032 2.13233 180)
			(unlocked yes)
			(layer "F.Fab")
			(hide yes)
			(effects
				(font
					(size 0.7874 0.5842)
					(thickness 0.1524)
				)
			)
		)
		(property "Tolerance" "TOL*"
			(at 0.044704 3.05435 180)
			(unlocked yes)
			(layer "Cmts.User")
			(hide yes)
			(effects
				(font
					(size 0.7874 0.5842)
					(thickness 0.1524)
				)
			)
		)
		(property "User Part Number" "PARTNUM*"
			(at 0.02032 4.024884 180)
			(unlocked yes)
			(layer "Cmts.User")
			(hide yes)
			(effects
				(font
					(size 0.7874 0.5842)
					(thickness 0.1524)
				)
			)
		)
		(property "Device Type" "RESISTOR-G155-14701-01,4.7KOHMA"
			(at 0.008382 1.210564 180)
			(unlocked yes)
			(layer "F.Fab")
			(hide yes)
			(effects
				(font
					(size 0.7874 0.5842)
					(thickness 0.1524)
				)
			)
		)
		(duplicate_pad_numbers_are_jumpers no)
		(fp_line
			(start 1.143 0.5588)
			(end 1.143 -0.5588)
			(stroke
				(width 0.1)
				(type default)
			)
			(layer "F.SilkS")
		)
		(fp_line
			(start 1.143 -0.5588)
			(end -1.143 -0.5588)
			(stroke
				(width 0.1)
				(type default)
			)
			(layer "F.SilkS")
		)
		(fp_line
			(start -1.143 0.5588)
			(end 1.143 0.5588)
			(stroke
				(width 0.1)
				(type default)
			)
			(layer "F.SilkS")
		)
		(fp_line
			(start -1.143 -0.5588)
			(end -1.143 0.5588)
			(stroke
				(width 0.1)
				(type default)
			)
			(layer "F.SilkS")
		)
		(fp_rect
			(start 1.143 -0.5588)
			(end -1.143 0.5588)
			(stroke
				(width 0)
				(type default)
			)
			(fill no)
			(layer "F.CrtYd")
		)
		(fp_line
			(start 0.508 0.3048)
			(end 0.508 -0.3048)
			(stroke
				(width 0.1)
				(type default)
			)
			(layer "F.Fab")
		)
		(fp_line
			(start 0.508 -0.3048)
			(end -0.508 -0.3048)
			(stroke
				(width 0.1)
				(type default)
			)
			(layer "F.Fab")
		)
		(fp_line
			(start -0.508 0.3048)
			(end 0.508 0.3048)
			(stroke
				(width 0.1)
				(type default)
			)
			(layer "F.Fab")
		)
		(fp_line
			(start -0.508 -0.3048)
			(end -0.508 0.3048)
			(stroke
				(width 0.1)
				(type default)
			)
			(layer "F.Fab")
		)
		(pad "1" smd rect
			(at -0.5334 0 180)
			(size 0.7112 0.6096)
			(layers "F.Cu" "F.Mask" "F.Paste")
			(net "XP3R3V_FPGA")
		)
		(pad "2" smd rect
			(at 0.5334 0 180)
			(size 0.7112 0.6096)
			(layers "F.Cu" "F.Mask" "F.Paste")
			(net "UNNAMED_6_LM75BDPTSSOP8_I81_A0")
		)
		(zone
			(layer "F.Cu")
			(hatch none 0.5)
			(connect_pads
				(clearance 0)
			)
			(min_thickness 0.25)
			(keepout
				(tracks not_allowed)
				(vias allowed)
				(pads allowed)
				(copperpour not_allowed)
				(footprints allowed)
			)
			(placement
				(enabled no)
				(sheetname "")
			)
			(fill
				(thermal_gap 0.5)
				(thermal_bridge_width 0.5)
				(island_removal_mode 0)
			)
			(polygon
				(pts
					(xy 162.4838 -27.1272) (xy 162.6362 -27.1272) (xy 162.6362 -27.7368) (xy 162.4838 -27.7368)
				)
			)
		)
		(zone
			(layer "F.Cu")
			(hatch none 0.5)
			(connect_pads
				(clearance 0)
			)
			(min_thickness 0.25)
			(keepout
				(tracks allowed)
				(vias not_allowed)
				(pads allowed)
				(copperpour not_allowed)
				(footprints allowed)
			)
			(placement
				(enabled no)
				(sheetname "")
			)
			(fill
				(thermal_gap 0.5)
				(thermal_bridge_width 0.5)
				(island_removal_mode 0)
			)
			(polygon
				(pts
					(xy 162.4838 -27.1272) (xy 162.6362 -27.1272) (xy 162.6362 -27.7368) (xy 162.4838 -27.7368)
				)
			)
		)
	)
	(footprint ""
		(layer "F.Cu")
		(at 133.858 -19.304 180)
		(property "Reference" "R476"
			(at 0.127 5.04063 0)
			(unlocked yes)
			(layer "F.SilkS")
			(effects
				(font
					(size 0.7874 0.5842)
					(thickness 0.1524)
				)
			)
		)
		(property "Value" "VAL*"
			(at 0.02032 2.13233 180)
			(unlocked yes)
			(layer "F.Fab")
			(hide yes)
			(effects
				(font
					(size 0.7874 0.5842)
					(thickness 0.1524)
				)
			)
		)
		(property "Tolerance" "TOL*"
			(at 0.044704 3.05435 180)
			(unlocked yes)
			(layer "Cmts.User")
			(hide yes)
			(effects
				(font
					(size 0.7874 0.5842)
					(thickness 0.1524)
				)
			)
		)
		(property "User Part Number" "PARTNUM*"
			(at 0.02032 4.024884 180)
			(unlocked yes)
			(layer "Cmts.User")
			(hide yes)
			(effects
				(font
					(size 0.7874 0.5842)
					(thickness 0.1524)
				)
			)
		)
		(property "Device Type" "RESISTOR-G155-11003-01,100KOHMA"
			(at 0.008382 1.210564 180)
			(unlocked yes)
			(layer "F.Fab")
			(hide yes)
			(effects
				(font
					(size 0.7874 0.5842)
					(thickness 0.1524)
				)
			)
		)
		(duplicate_pad_numbers_are_jumpers no)
		(fp_line
			(start 1.143 0.5588)
			(end 1.143 -0.5588)
			(stroke
				(width 0.1)
				(type default)
			)
			(layer "F.SilkS")
		)
		(fp_line
			(start 1.143 -0.5588)
			(end -1.143 -0.5588)
			(stroke
				(width 0.1)
				(type default)
			)
			(layer "F.SilkS")
		)
		(fp_line
			(start -1.143 0.5588)
			(end 1.143 0.5588)
			(stroke
				(width 0.1)
				(type default)
			)
			(layer "F.SilkS")
		)
		(fp_line
			(start -1.143 -0.5588)
			(end -1.143 0.5588)
			(stroke
				(width 0.1)
				(type default)
			)
			(layer "F.SilkS")
		)
		(fp_poly
			(pts
				(xy -1.143 0.5588) (xy 1.143 0.5588) (xy 1.143 -0.5588) (xy -1.143 -0.5588)
			)
			(stroke
				(width 0)
				(type default)
			)
			(fill no)
			(layer "F.CrtYd")
		)
		(fp_line
			(start 0.508 0.3048)
			(end 0.508 -0.3048)
			(stroke
				(width 0.1)
				(type default)
			)
			(layer "F.Fab")
		)
		(fp_line
			(start 0.508 -0.3048)
			(end -0.508 -0.3048)
			(stroke
				(width 0.1)
				(type default)
			)
			(layer "F.Fab")
		)
		(fp_line
			(start -0.508 0.3048)
			(end 0.508 0.3048)
			(stroke
				(width 0.1)
				(type default)
			)
			(layer "F.Fab")
		)
		(fp_line
			(start -0.508 -0.3048)
			(end -0.508 0.3048)
			(stroke
				(width 0.1)
				(type default)
			)
			(layer "F.Fab")
		)
		(pad "1" smd rect
			(at -0.5334 0 180)
			(size 0.7112 0.6096)
			(layers "F.Cu" "F.Mask" "F.Paste")
			(net "XP3R3V_FPGA")
		)
		(pad "2" smd rect
			(at 0.5334 0 180)
			(size 0.7112 0.6096)
			(layers "F.Cu" "F.Mask" "F.Paste")
			(net "FPGA_EEPROM_I2C_SDA")
		)
		(zone
			(layer "F.Cu")
			(hatch none 0.5)
			(connect_pads
				(clearance 0)
			)
			(min_thickness 0.25)
			(keepout
				(tracks allowed)
				(vias not_allowed)
				(pads allowed)
				(copperpour not_allowed)
				(footprints allowed)
			)
			(placement
				(enabled no)
				(sheetname "")
			)
			(fill
				(thermal_gap 0.5)
				(thermal_bridge_width 0.5)
				(island_removal_mode 0)
			)
			(polygon
				(pts
					(xy 133.9342 -19.6088) (xy 133.7818 -19.6088) (xy 133.7818 -18.9992) (xy 133.9342 -18.9992)
				)
			)
		)
		(zone
			(layer "F.Cu")
			(hatch none 0.5)
			(connect_pads
				(clearance 0)
			)
			(min_thickness 0.25)
			(keepout
				(tracks not_allowed)
				(vias allowed)
				(pads allowed)
				(copperpour not_allowed)
				(footprints allowed)
			)
			(placement
				(enabled no)
				(sheetname "")
			)
			(fill
				(thermal_gap 0.5)
				(thermal_bridge_width 0.5)
				(island_removal_mode 0)
			)
			(polygon
				(pts
					(xy 133.9342 -19.6088) (xy 133.7818 -19.6088) (xy 133.7818 -18.9992) (xy 133.9342 -18.9992)
				)
			)
		)
	)
	(footprint ""
		(layer "F.Cu")
		(at 146.685 -19.685 -90)
		(property "Reference" "R228"
			(at 3.21437 -2.667 0)
			(unlocked yes)
			(layer "F.SilkS")
			(effects
				(font
					(size 0.7874 0.5842)
					(thickness 0.1524)
				)
			)
		)
		(property "Value" "VAL*"
			(at 0.0508 2.245106 270)
			(unlocked yes)
			(layer "F.Fab")
			(hide yes)
			(effects
				(font
					(size 0.7874 0.5842)
					(thickness 0.1524)
				)
			)
		)
		(property "User Part Number" "PARTNUM*"
			(at 0.0762 4.302506 270)
			(unlocked yes)
			(layer "Cmts.User")
			(hide yes)
			(effects
				(font
					(size 0.7874 0.5842)
					(thickness 0.1524)
				)
			)
		)
		(property "Device Type" "RESISTOR-G152-00055-01,1.13KOHA"
			(at 0.0762 1.254506 270)
			(unlocked yes)
			(layer "F.Fab")
			(hide yes)
			(effects
				(font
					(size 0.7874 0.5842)
					(thickness 0.1524)
				)
			)
		)
		(property "Tolerance" "TOL*"
			(at 0.0508 3.261106 270)
			(unlocked yes)
			(layer "Cmts.User")
			(hide yes)
			(effects
				(font
					(size 0.7874 0.5842)
					(thickness 0.1524)
				)
			)
		)
		(duplicate_pad_numbers_are_jumpers no)
		(fp_line
			(start -1.143 0.5588)
			(end 1.143 0.5588)
			(stroke
				(width 0.1)
				(type default)
			)
			(layer "F.SilkS")
		)
		(fp_line
			(start 1.143 0.5588)
			(end 1.143 -0.5588)
			(stroke
				(width 0.1)
				(type default)
			)
			(layer "F.SilkS")
		)
		(fp_line
			(start -1.143 -0.5588)
			(end -1.143 0.5588)
			(stroke
				(width 0.1)
				(type default)
			)
			(layer "F.SilkS")
		)
		(fp_line
			(start 1.143 -0.5588)
			(end -1.143 -0.5588)
			(stroke
				(width 0.1)
				(type default)
			)
			(layer "F.SilkS")
		)
		(fp_rect
			(start -1.143 0.5588)
			(end 1.143 -0.5588)
			(stroke
				(width 0)
				(type default)
			)
			(fill no)
			(layer "F.CrtYd")
		)
		(fp_line
			(start -0.508 0.3048)
			(end 0.508 0.3048)
			(stroke
				(width 0.1)
				(type default)
			)
			(layer "F.Fab")
		)
		(fp_line
			(start 0.508 0.3048)
			(end 0.508 -0.3048)
			(stroke
				(width 0.1)
				(type default)
			)
			(layer "F.Fab")
		)
		(fp_line
			(start -0.508 -0.3048)
			(end -0.508 0.3048)
			(stroke
				(width 0.1)
				(type default)
			)
			(layer "F.Fab")
		)
		(fp_line
			(start 0.508 -0.3048)
			(end -0.508 -0.3048)
			(stroke
				(width 0.1)
				(type default)
			)
			(layer "F.Fab")
		)
		(pad "1" smd rect
			(at -0.5334 0 270)
			(size 0.7112 0.6096)
			(layers "F.Cu" "F.Mask" "F.Paste")
			(net "UNNAMED_515_CAPACITOR_I130_1")
		)
		(pad "2" smd rect
			(at 0.5334 0 270)
			(size 0.7112 0.6096)
			(layers "F.Cu" "F.Mask" "F.Paste")
			(net "UNNAMED_515_CAPACITOR_I128_1")
		)
		(zone
			(layer "F.Cu")
			(hatch none 0.5)
			(connect_pads
				(clearance 0)
			)
			(min_thickness 0.25)
			(keepout
				(tracks allowed)
				(vias not_allowed)
				(pads allowed)
				(copperpour not_allowed)
				(footprints allowed)
			)
			(placement
				(enabled no)
				(sheetname "")
			)
			(fill
				(thermal_gap 0.5)
				(thermal_bridge_width 0.5)
				(island_removal_mode 0)
			)
			(polygon
				(pts
					(xy 146.3802 -19.7612) (xy 146.3802 -19.6088) (xy 146.9898 -19.6088) (xy 146.9898 -19.7612)
				)
			)
		)
	)
	(footprint ""
		(layer "F.Cu")
		(at 22.479 -76.962 90)
		(property "Reference" "TP8"
			(at 0 0 90)
			(layer "F.SilkS")
			(hide yes)
			(effects
				(font
					(size 1.27 1.27)
				)
			)
		)
		(property "Value" ""
			(at 0 0 90)
			(layer "F.Fab")
			(effects
				(font
					(size 1.27 1.27)
				)
			)
		)
		(property "Device Type" "TP_PIONT-TP010CT020B030_PTH-TPA"
			(at -1.341882 0.996696 90)
			(unlocked yes)
			(layer "F.Fab")
			(hide yes)
			(effects
				(font
					(size 0.7874 0.5842)
					(thickness 0.1524)
				)
				(justify left)
			)
		)
		(duplicate_pad_numbers_are_jumpers no)
		(fp_poly
			(pts
				(arc
					(start 0 0.889)
					(mid 0 -0.889)
					(end 0 0.889)
				)
			)
			(stroke
				(width 0)
				(type default)
			)
			(fill no)
			(layer "B.CrtYd")
		)
		(fp_poly
			(pts
				(arc
					(start 0 0.889)
					(mid 0 -0.889)
					(end 0 0.889)
				)
			)
			(stroke
				(width 0)
				(type default)
			)
			(fill no)
			(layer "F.CrtYd")
		)
		(pad "1" thru_hole circle
			(at 0 0 90)
			(size 0.508 0.508)
			(drill 0.254)
			(layers "*.Cu" "*.Mask")
			(remove_unused_layers no)
			(net "UNNAMED_524_FT4232HLREELQFP64_3")
			(clearance 0.1016)
			(padstack
				(mode front_inner_back)
				(layer "Inner"
					(shape circle)
					(size 0.508 0.508)
					(clearance 0.1016)
				)
				(layer "B.Cu"
					(shape circle)
					(size 0.762 0.762)
					(clearance -0.0254)
				)
			)
		)
	)
	(footprint ""
		(layer "F.Cu")
		(at 43.942 -126.111)
		(property "Reference" "SP34"
			(at 0 0 0)
			(layer "F.SilkS")
			(hide yes)
			(effects
				(font
					(size 1.27 1.27)
				)
			)
		)
		(property "Value" ""
			(at 0 0 0)
			(layer "F.Fab")
			(effects
				(font
					(size 1.27 1.27)
				)
			)
		)
		(duplicate_pad_numbers_are_jumpers no)
	)
	(footprint ""
		(layer "F.Cu")
		(at 146.05 -57.023)
		(property "Reference" "R248"
			(at 2.794 2.32537 0)
			(unlocked yes)
			(layer "F.SilkS")
			(effects
				(font
					(size 0.7874 0.5842)
					(thickness 0.1524)
				)
			)
		)
		(property "Value" "VAL*"
			(at 0.02032 2.13233 0)
			(unlocked yes)
			(layer "F.Fab")
			(hide yes)
			(effects
				(font
					(size 0.7874 0.5842)
					(thickness 0.1524)
				)
			)
		)
		(property "Device Type" "RESISTOR-G155-11003-01,100KOHMA"
			(at 0.008382 1.210564 0)
			(unlocked yes)
			(layer "F.Fab")
			(hide yes)
			(effects
				(font
					(size 0.7874 0.5842)
					(thickness 0.1524)
				)
			)
		)
		(property "User Part Number" "PARTNUM*"
			(at 0.02032 4.024884 0)
			(unlocked yes)
			(layer "Cmts.User")
			(hide yes)
			(effects
				(font
					(size 0.7874 0.5842)
					(thickness 0.1524)
				)
			)
		)
		(property "Tolerance" "TOL*"
			(at 0.044704 3.05435 0)
			(unlocked yes)
			(layer "Cmts.User")
			(hide yes)
			(effects
				(font
					(size 0.7874 0.5842)
					(thickness 0.1524)
				)
			)
		)
		(duplicate_pad_numbers_are_jumpers no)
		(fp_line
			(start -1.143 -0.5588)
			(end -1.143 0.5588)
			(stroke
				(width 0.1)
				(type default)
			)
			(layer "F.SilkS")
		)
		(fp_line
			(start -1.143 0.5588)
			(end 1.143 0.5588)
			(stroke
				(width 0.1)
				(type default)
			)
			(layer "F.SilkS")
		)
		(fp_line
			(start 1.143 -0.5588)
			(end -1.143 -0.5588)
			(stroke
				(width 0.1)
				(type default)
			)
			(layer "F.SilkS")
		)
		(fp_line
			(start 1.143 0.5588)
			(end 1.143 -0.5588)
			(stroke
				(width 0.1)
				(type default)
			)
			(layer "F.SilkS")
		)
		(fp_rect
			(start -1.143 0.5588)
			(end 1.143 -0.5588)
			(stroke
				(width 0)
				(type default)
			)
			(fill no)
			(layer "F.CrtYd")
		)
		(fp_line
			(start -0.508 -0.3048)
			(end -0.508 0.3048)
			(stroke
				(width 0.1)
				(type default)
			)
			(layer "F.Fab")
		)
		(fp_line
			(start -0.508 0.3048)
			(end 0.508 0.3048)
			(stroke
				(width 0.1)
				(type default)
			)
			(layer "F.Fab")
		)
		(fp_line
			(start 0.508 -0.3048)
			(end -0.508 -0.3048)
			(stroke
				(width 0.1)
				(type default)
			)
			(layer "F.Fab")
		)
		(fp_line
			(start 0.508 0.3048)
			(end 0.508 -0.3048)
			(stroke
				(width 0.1)
				(type default)
			)
			(layer "F.Fab")
		)
		(pad "1" smd rect
			(at -0.5334 0)
			(size 0.7112 0.6096)
			(layers "F.Cu" "F.Mask" "F.Paste")
			(net "XP1R0V_RT")
		)
		(pad "2" smd rect
			(at 0.5334 0)
			(size 0.7112 0.6096)
			(layers "F.Cu" "F.Mask" "F.Paste")
			(net "XP1R0V_AGND")
		)
		(zone
			(layer "F.Cu")
			(hatch none 0.5)
			(connect_pads
				(clearance 0)
			)
			(min_thickness 0.25)
			(keepout
				(tracks allowed)
				(vias not_allowed)
				(pads allowed)
				(copperpour not_allowed)
				(footprints allowed)
			)
			(placement
				(enabled no)
				(sheetname "")
			)
			(fill
				(thermal_gap 0.5)
				(thermal_bridge_width 0.5)
				(island_removal_mode 0)
			)
			(polygon
				(pts
					(xy 145.9738 -56.7182) (xy 146.1262 -56.7182) (xy 146.1262 -57.3278) (xy 145.9738 -57.3278)
				)
			)
		)
	)
	(footprint ""
		(layer "F.Cu")
		(at 10.7188 -68.201032 90)
		(property "Reference" "R375"
			(at 3.426968 -0.39243 90)
			(unlocked yes)
			(layer "F.SilkS")
			(effects
				(font
					(size 0.7874 0.5842)
					(thickness 0.1524)
				)
			)
		)
		(property "Value" "VAL*"
			(at 0.02032 2.13233 90)
			(unlocked yes)
			(layer "F.Fab")
			(hide yes)
			(effects
				(font
					(size 0.7874 0.5842)
					(thickness 0.1524)
				)
			)
		)
		(property "Device Type" "RESISTOR-G155-11000-01,100OHM,A"
			(at 0.008382 1.210564 90)
			(unlocked yes)
			(layer "F.Fab")
			(hide yes)
			(effects
				(font
					(size 0.7874 0.5842)
					(thickness 0.1524)
				)
			)
		)
		(property "User Part Number" "PARTNUM*"
			(at 0.02032 4.024884 90)
			(unlocked yes)
			(layer "Cmts.User")
			(hide yes)
			(effects
				(font
					(size 0.7874 0.5842)
					(thickness 0.1524)
				)
			)
		)
		(property "Tolerance" "TOL*"
			(at 0.044704 3.05435 90)
			(unlocked yes)
			(layer "Cmts.User")
			(hide yes)
			(effects
				(font
					(size 0.7874 0.5842)
					(thickness 0.1524)
				)
			)
		)
		(duplicate_pad_numbers_are_jumpers no)
		(fp_line
			(start 1.143 -0.5588)
			(end -1.143 -0.5588)
			(stroke
				(width 0.1)
				(type default)
			)
			(layer "F.SilkS")
		)
		(fp_line
			(start -1.143 -0.5588)
			(end -1.143 0.5588)
			(stroke
				(width 0.1)
				(type default)
			)
			(layer "F.SilkS")
		)
		(fp_line
			(start 1.143 0.5588)
			(end 1.143 -0.5588)
			(stroke
				(width 0.1)
				(type default)
			)
			(layer "F.SilkS")
		)
		(fp_line
			(start -1.143 0.5588)
			(end 1.143 0.5588)
			(stroke
				(width 0.1)
				(type default)
			)
			(layer "F.SilkS")
		)
		(fp_poly
			(pts
				(xy -1.143 0.5588) (xy 1.143 0.5588) (xy 1.143 -0.5588) (xy -1.143 -0.5588)
			)
			(stroke
				(width 0)
				(type default)
			)
			(fill no)
			(layer "F.CrtYd")
		)
		(fp_line
			(start 0.508 -0.3048)
			(end -0.508 -0.3048)
			(stroke
				(width 0.1)
				(type default)
			)
			(layer "F.Fab")
		)
		(fp_line
			(start -0.508 -0.3048)
			(end -0.508 0.3048)
			(stroke
				(width 0.1)
				(type default)
			)
			(layer "F.Fab")
		)
		(fp_line
			(start 0.508 0.3048)
			(end 0.508 -0.3048)
			(stroke
				(width 0.1)
				(type default)
			)
			(layer "F.Fab")
		)
		(fp_line
			(start -0.508 0.3048)
			(end 0.508 0.3048)
			(stroke
				(width 0.1)
				(type default)
			)
			(layer "F.Fab")
		)
		(pad "1" smd rect
			(at -0.5334 0 90)
			(size 0.7112 0.6096)
			(layers "F.Cu" "F.Mask" "F.Paste")
			(net "FPGA_OUT_SMA3_LED_GREEN_N")
		)
		(pad "2" smd rect
			(at 0.5334 0 90)
			(size 0.7112 0.6096)
			(layers "F.Cu" "F.Mask" "F.Paste")
			(net "UNNAMED_14_LED4PV14_I267_4")
		)
		(zone
			(layer "F.Cu")
			(hatch none 0.5)
			(connect_pads
				(clearance 0)
			)
			(min_thickness 0.25)
			(keepout
				(tracks allowed)
				(vias not_allowed)
				(pads allowed)
				(copperpour not_allowed)
				(footprints allowed)
			)
			(placement
				(enabled no)
				(sheetname "")
			)
			(fill
				(thermal_gap 0.5)
				(thermal_bridge_width 0.5)
				(island_removal_mode 0)
			)
			(polygon
				(pts
					(xy 11.0236 -68.124832) (xy 11.0236 -68.277232) (xy 10.414 -68.277232) (xy 10.414 -68.124832)
				)
			)
		)
		(zone
			(layer "F.Cu")
			(hatch none 0.5)
			(connect_pads
				(clearance 0)
			)
			(min_thickness 0.25)
			(keepout
				(tracks not_allowed)
				(vias allowed)
				(pads allowed)
				(copperpour not_allowed)
				(footprints allowed)
			)
			(placement
				(enabled no)
				(sheetname "")
			)
			(fill
				(thermal_gap 0.5)
				(thermal_bridge_width 0.5)
				(island_removal_mode 0)
			)
			(polygon
				(pts
					(xy 11.0236 -68.124832) (xy 11.0236 -68.277232) (xy 10.414 -68.277232) (xy 10.414 -68.124832)
				)
			)
		)
	)
	(footprint ""
		(layer "F.Cu")
		(at 64.897 -120.269)
		(property "Reference" "SP30"
			(at 0 0 0)
			(layer "F.SilkS")
			(hide yes)
			(effects
				(font
					(size 1.27 1.27)
				)
			)
		)
		(property "Value" ""
			(at 0 0 0)
			(layer "F.Fab")
			(effects
				(font
					(size 1.27 1.27)
				)
			)
		)
		(duplicate_pad_numbers_are_jumpers no)
	)
	(footprint ""
		(layer "F.Cu")
		(at 36.7284 -97.8154 180)
		(property "Reference" "R294"
			(at -2.43586 -5.93725 0)
			(unlocked yes)
			(layer "F.SilkS")
			(effects
				(font
					(size 0.7874 0.5842)
					(thickness 0.1524)
				)
			)
		)
		(property "Value" "VAL*"
			(at 0.02032 2.13233 180)
			(unlocked yes)
			(layer "F.Fab")
			(hide yes)
			(effects
				(font
					(size 0.7874 0.5842)
					(thickness 0.1524)
				)
			)
		)
		(property "Device Type" "RESISTOR-G155-133R0-01,33OHM,1%"
			(at 0.008382 1.210564 180)
			(unlocked yes)
			(layer "F.Fab")
			(hide yes)
			(effects
				(font
					(size 0.7874 0.5842)
					(thickness 0.1524)
				)
			)
		)
		(property "User Part Number" "PARTNUM*"
			(at 0.02032 4.024884 180)
			(unlocked yes)
			(layer "Cmts.User")
			(hide yes)
			(effects
				(font
					(size 0.7874 0.5842)
					(thickness 0.1524)
				)
			)
		)
		(property "Tolerance" "TOL*"
			(at 0.044704 3.05435 180)
			(unlocked yes)
			(layer "Cmts.User")
			(hide yes)
			(effects
				(font
					(size 0.7874 0.5842)
					(thickness 0.1524)
				)
			)
		)
		(duplicate_pad_numbers_are_jumpers no)
		(fp_line
			(start 1.143 0.5588)
			(end 1.143 -0.5588)
			(stroke
				(width 0.1)
				(type default)
			)
			(layer "F.SilkS")
		)
		(fp_line
			(start 1.143 -0.5588)
			(end -1.143 -0.5588)
			(stroke
				(width 0.1)
				(type default)
			)
			(layer "F.SilkS")
		)
		(fp_line
			(start -1.143 0.5588)
			(end 1.143 0.5588)
			(stroke
				(width 0.1)
				(type default)
			)
			(layer "F.SilkS")
		)
		(fp_line
			(start -1.143 -0.5588)
			(end -1.143 0.5588)
			(stroke
				(width 0.1)
				(type default)
			)
			(layer "F.SilkS")
		)
		(fp_rect
			(start -1.143 0.5588)
			(end 1.143 -0.5588)
			(stroke
				(width 0)
				(type default)
			)
			(fill no)
			(layer "F.CrtYd")
		)
		(fp_line
			(start 0.508 0.3048)
			(end 0.508 -0.3048)
			(stroke
				(width 0.1)
				(type default)
			)
			(layer "F.Fab")
		)
		(fp_line
			(start 0.508 -0.3048)
			(end -0.508 -0.3048)
			(stroke
				(width 0.1)
				(type default)
			)
			(layer "F.Fab")
		)
		(fp_line
			(start -0.508 0.3048)
			(end 0.508 0.3048)
			(stroke
				(width 0.1)
				(type default)
			)
			(layer "F.Fab")
		)
		(fp_line
			(start -0.508 -0.3048)
			(end -0.508 0.3048)
			(stroke
				(width 0.1)
				(type default)
			)
			(layer "F.Fab")
		)
		(pad "1" smd rect
			(at -0.5334 0 180)
			(size 0.7112 0.6096)
			(layers "F.Cu" "F.Mask" "F.Paste")
			(net "XP5R0V_PG")
		)
		(pad "2" smd rect
			(at 0.5334 0 180)
			(size 0.7112 0.6096)
			(layers "F.Cu" "F.Mask" "F.Paste")
			(net "FPGA_CFG_INIT_N")
		)
		(zone
			(layer "F.Cu")
			(hatch none 0.5)
			(connect_pads
				(clearance 0)
			)
			(min_thickness 0.25)
			(keepout
				(tracks allowed)
				(vias not_allowed)
				(pads allowed)
				(copperpour not_allowed)
				(footprints allowed)
			)
			(placement
				(enabled no)
				(sheetname "")
			)
			(fill
				(thermal_gap 0.5)
				(thermal_bridge_width 0.5)
				(island_removal_mode 0)
			)
			(polygon
				(pts
					(xy 36.8046 -98.1202) (xy 36.6522 -98.1202) (xy 36.6522 -97.5106) (xy 36.8046 -97.5106)
				)
			)
		)
	)
	(footprint ""
		(layer "F.Cu")
		(at 30.34538 -17.99844 180)
		(property "Reference" "R19"
			(at 1.27 5.04063 0)
			(unlocked yes)
			(layer "F.SilkS")
			(effects
				(font
					(size 0.7874 0.5842)
					(thickness 0.1524)
				)
			)
		)
		(property "Value" "VAL*"
			(at 0.02032 2.13233 180)
			(unlocked yes)
			(layer "F.Fab")
			(hide yes)
			(effects
				(font
					(size 0.7874 0.5842)
					(thickness 0.1524)
				)
			)
		)
		(property "Tolerance" "TOL*"
			(at 0.044704 3.05435 180)
			(unlocked yes)
			(layer "Cmts.User")
			(hide yes)
			(effects
				(font
					(size 0.7874 0.5842)
					(thickness 0.1524)
				)
			)
		)
		(property "User Part Number" "PARTNUM*"
			(at 0.02032 4.024884 180)
			(unlocked yes)
			(layer "Cmts.User")
			(hide yes)
			(effects
				(font
					(size 0.7874 0.5842)
					(thickness 0.1524)
				)
			)
		)
		(property "Device Type" "RESISTOR-G155-11002-01,10KOHM,A"
			(at 0.008382 1.210564 180)
			(unlocked yes)
			(layer "F.Fab")
			(hide yes)
			(effects
				(font
					(size 0.7874 0.5842)
					(thickness 0.1524)
				)
			)
		)
		(duplicate_pad_numbers_are_jumpers no)
		(fp_line
			(start 1.143 0.5588)
			(end 1.143 -0.5588)
			(stroke
				(width 0.1)
				(type default)
			)
			(layer "F.SilkS")
		)
		(fp_line
			(start 1.143 -0.5588)
			(end -1.143 -0.5588)
			(stroke
				(width 0.1)
				(type default)
			)
			(layer "F.SilkS")
		)
		(fp_line
			(start -1.143 0.5588)
			(end 1.143 0.5588)
			(stroke
				(width 0.1)
				(type default)
			)
			(layer "F.SilkS")
		)
		(fp_line
			(start -1.143 -0.5588)
			(end -1.143 0.5588)
			(stroke
				(width 0.1)
				(type default)
			)
			(layer "F.SilkS")
		)
		(fp_rect
			(start 1.143 -0.5588)
			(end -1.143 0.5588)
			(stroke
				(width 0)
				(type default)
			)
			(fill no)
			(layer "F.CrtYd")
		)
		(fp_line
			(start 0.508 0.3048)
			(end 0.508 -0.3048)
			(stroke
				(width 0.1)
				(type default)
			)
			(layer "F.Fab")
		)
		(fp_line
			(start 0.508 -0.3048)
			(end -0.508 -0.3048)
			(stroke
				(width 0.1)
				(type default)
			)
			(layer "F.Fab")
		)
		(fp_line
			(start -0.508 0.3048)
			(end 0.508 0.3048)
			(stroke
				(width 0.1)
				(type default)
			)
			(layer "F.Fab")
		)
		(fp_line
			(start -0.508 -0.3048)
			(end -0.508 0.3048)
			(stroke
				(width 0.1)
				(type default)
			)
			(layer "F.Fab")
		)
		(pad "1" smd rect
			(at -0.5334 0 180)
			(size 0.7112 0.6096)
			(layers "F.Cu" "F.Mask" "F.Paste")
			(net "XP3R3V_FPGA")
		)
		(pad "2" smd rect
			(at 0.5334 0 180)
			(size 0.7112 0.6096)
			(layers "F.Cu" "F.Mask" "F.Paste")
			(net "EEPROM_SCL")
		)
		(zone
			(layer "F.Cu")
			(hatch none 0.5)
			(connect_pads
				(clearance 0)
			)
			(min_thickness 0.25)
			(keepout
				(tracks allowed)
				(vias not_allowed)
				(pads allowed)
				(copperpour not_allowed)
				(footprints allowed)
			)
			(placement
				(enabled no)
				(sheetname "")
			)
			(fill
				(thermal_gap 0.5)
				(thermal_bridge_width 0.5)
				(island_removal_mode 0)
			)
			(polygon
				(pts
					(xy 30.26918 -17.69364) (xy 30.42158 -17.69364) (xy 30.42158 -18.30324) (xy 30.26918 -18.30324)
				)
			)
		)
	)
	(footprint ""
		(layer "F.Cu")
		(at 92.075 -84.074 180)
		(property "Reference" "U23"
			(at -0.5334 -3.79857 0)
			(unlocked yes)
			(layer "F.SilkS")
			(effects
				(font
					(size 0.7874 0.5842)
					(thickness 0.1524)
				)
			)
		)
		(property "Value" ""
			(at 0 0 180)
			(layer "F.Fab")
			(effects
				(font
					(size 1.27 1.27)
				)
			)
		)
		(property "User Part Number" "PARTNUM*"
			(at 0 5.133848 180)
			(unlocked yes)
			(layer "Cmts.User")
			(hide yes)
			(effects
				(font
					(size 0.7874 0.5842)
					(thickness 0.1524)
				)
			)
		)
		(property "Device Type" "MT25QL128ABA1ESE_SOP8-G221-102A"
			(at 0 4.092448 180)
			(unlocked yes)
			(layer "F.Fab")
			(hide yes)
			(effects
				(font
					(size 0.7874 0.5842)
					(thickness 0.1524)
				)
			)
		)
		(duplicate_pad_numbers_are_jumpers no)
		(fp_line
			(start 4.826 2.998978)
			(end 4.826 -2.998978)
			(stroke
				(width 0.1)
				(type default)
			)
			(layer "F.SilkS")
		)
		(fp_line
			(start 4.826 -2.998978)
			(end -4.826 -2.998978)
			(stroke
				(width 0.1)
				(type default)
			)
			(layer "F.SilkS")
		)
		(fp_line
			(start -4.826 2.998978)
			(end 4.826 2.998978)
			(stroke
				(width 0.1)
				(type default)
			)
			(layer "F.SilkS")
		)
		(fp_line
			(start -4.826 -2.998978)
			(end -4.826 2.998978)
			(stroke
				(width 0.1)
				(type default)
			)
			(layer "F.SilkS")
		)
		(fp_poly
			(pts
				(arc
					(start -5.969 -3.429)
					(mid -5.207 -3.429)
					(end -5.969 -3.429)
				)
			)
			(stroke
				(width 0)
				(type default)
			)
			(fill yes)
			(layer "F.SilkS")
		)
		(fp_rect
			(start 5.08 -3.252978)
			(end -5.08 3.252978)
			(stroke
				(width 0)
				(type default)
			)
			(fill no)
			(layer "F.CrtYd")
		)
		(fp_line
			(start 2.744978 2.744978)
			(end 2.744978 -2.744978)
			(stroke
				(width 0.1)
				(type default)
			)
			(layer "F.Fab")
		)
		(fp_line
			(start 2.744978 -2.744978)
			(end -2.744978 -2.744978)
			(stroke
				(width 0.1)
				(type default)
			)
			(layer "F.Fab")
		)
		(fp_line
			(start -2.744978 2.744978)
			(end 2.744978 2.744978)
			(stroke
				(width 0.1)
				(type default)
			)
			(layer "F.Fab")
		)
		(fp_line
			(start -2.744978 -2.744978)
			(end -2.744978 2.744978)
			(stroke
				(width 0.1)
				(type default)
			)
			(layer "F.Fab")
		)
		(fp_circle
			(center -4.133342 -2.39014)
			(end -4.514342 -2.39014)
			(stroke
				(width 0.1)
				(type default)
			)
			(fill no)
			(layer "F.Fab")
		)
		(fp_text user "5"
			(at 4.1656 3.82143 0)
			(unlocked yes)
			(layer "F.SilkS")
			(effects
				(font
					(size 0.7874 0.5842)
					(thickness 0.1524)
				)
			)
		)
		(fp_text user "8"
			(at 3.9116 -3.92557 0)
			(unlocked yes)
			(layer "F.SilkS")
			(effects
				(font
					(size 0.7874 0.5842)
					(thickness 0.1524)
				)
			)
		)
		(fp_text user "4"
			(at -5.3594 1.84785 0)
			(unlocked yes)
			(layer "F.SilkS")
			(effects
				(font
					(size 0.635 0.4064)
					(thickness 0.1524)
				)
			)
		)
		(fp_text user "5"
			(at 3.683 1.49733 0)
			(unlocked yes)
			(layer "F.Fab")
			(effects
				(font
					(size 0.7874 0.5842)
					(thickness 0.1524)
				)
			)
		)
		(fp_text user "8"
			(at 3.683 -2.31267 0)
			(unlocked yes)
			(layer "F.Fab")
			(effects
				(font
					(size 0.7874 0.5842)
					(thickness 0.1524)
				)
			)
		)
		(fp_text user "4"
			(at -3.4544 2.31013 0)
			(unlocked yes)
			(layer "F.Fab")
			(effects
				(font
					(size 0.7874 0.5842)
					(thickness 0.1524)
				)
			)
		)
		(pad "1" smd rect
			(at -3.6576 -1.905 180)
			(size 1.8288 0.508)
			(layers "F.Cu" "F.Mask" "F.Paste")
			(net "FLASH_CS_N")
		)
		(pad "2" smd rect
			(at -3.6576 -0.635 180)
			(size 1.8288 0.508)
			(layers "F.Cu" "F.Mask" "F.Paste")
			(net "UNNAMED_127_MT25QL128ABA1ESES_1")
		)
		(pad "3" smd rect
			(at -3.6576 0.635 180)
			(size 1.8288 0.508)
			(layers "F.Cu" "F.Mask" "F.Paste")
			(net "UNNAMED_127_MT25QL128ABA1ESES_3")
		)
		(pad "4" smd rect
			(at -3.6576 1.905 180)
			(size 1.8288 0.508)
			(layers "F.Cu" "F.Mask" "F.Paste")
			(net "SG")
		)
		(pad "5" smd rect
			(at 3.6576 1.905 180)
			(size 1.8288 0.508)
			(layers "F.Cu" "F.Mask" "F.Paste")
			(net "UNNAMED_127_MT25QL128ABA1ESESOP")
		)
		(pad "6" smd rect
			(at 3.6576 0.635 180)
			(size 1.8288 0.508)
			(layers "F.Cu" "F.Mask" "F.Paste")
			(net "FLASH_CLK")
		)
		(pad "7" smd rect
			(at 3.6576 -0.635 180)
			(size 1.8288 0.508)
			(layers "F.Cu" "F.Mask" "F.Paste")
			(net "UNNAMED_127_MT25QL128ABA1ESES_2")
		)
		(pad "8" smd rect
			(at 3.6576 -1.905 180)
			(size 1.8288 0.508)
			(layers "F.Cu" "F.Mask" "F.Paste")
			(net "XP3R3V_FPGA")
		)
	)
	(footprint ""
		(layer "F.Cu")
		(at 124.587 -51.435 180)
		(property "Reference" "R95"
			(at -0.127 -2.45237 0)
			(unlocked yes)
			(layer "F.SilkS")
			(effects
				(font
					(size 0.7874 0.5842)
					(thickness 0.1524)
				)
			)
		)
		(property "Value" "VAL*"
			(at 0.02032 2.13233 180)
			(unlocked yes)
			(layer "F.Fab")
			(hide yes)
			(effects
				(font
					(size 0.7874 0.5842)
					(thickness 0.1524)
				)
			)
		)
		(property "Tolerance" "TOL*"
			(at 0.044704 3.05435 180)
			(unlocked yes)
			(layer "Cmts.User")
			(hide yes)
			(effects
				(font
					(size 0.7874 0.5842)
					(thickness 0.1524)
				)
			)
		)
		(property "User Part Number" "PARTNUM*"
			(at 0.02032 4.024884 180)
			(unlocked yes)
			(layer "Cmts.User")
			(hide yes)
			(effects
				(font
					(size 0.7874 0.5842)
					(thickness 0.1524)
				)
			)
		)
		(property "Device Type" "RESISTOR-G155-133R0-01,33OHM,1%"
			(at 0.008382 1.210564 180)
			(unlocked yes)
			(layer "F.Fab")
			(hide yes)
			(effects
				(font
					(size 0.7874 0.5842)
					(thickness 0.1524)
				)
			)
		)
		(duplicate_pad_numbers_are_jumpers no)
		(fp_line
			(start 1.143 0.5588)
			(end 1.143 -0.5588)
			(stroke
				(width 0.1)
				(type default)
			)
			(layer "F.SilkS")
		)
		(fp_line
			(start 1.143 -0.5588)
			(end -1.143 -0.5588)
			(stroke
				(width 0.1)
				(type default)
			)
			(layer "F.SilkS")
		)
		(fp_line
			(start -1.143 0.5588)
			(end 1.143 0.5588)
			(stroke
				(width 0.1)
				(type default)
			)
			(layer "F.SilkS")
		)
		(fp_line
			(start -1.143 -0.5588)
			(end -1.143 0.5588)
			(stroke
				(width 0.1)
				(type default)
			)
			(layer "F.SilkS")
		)
		(fp_rect
			(start 1.143 -0.5588)
			(end -1.143 0.5588)
			(stroke
				(width 0)
				(type default)
			)
			(fill no)
			(layer "F.CrtYd")
		)
		(fp_line
			(start 0.508 0.3048)
			(end 0.508 -0.3048)
			(stroke
				(width 0.1)
				(type default)
			)
			(layer "F.Fab")
		)
		(fp_line
			(start 0.508 -0.3048)
			(end -0.508 -0.3048)
			(stroke
				(width 0.1)
				(type default)
			)
			(layer "F.Fab")
		)
		(fp_line
			(start -0.508 0.3048)
			(end 0.508 0.3048)
			(stroke
				(width 0.1)
				(type default)
			)
			(layer "F.Fab")
		)
		(fp_line
			(start -0.508 -0.3048)
			(end -0.508 0.3048)
			(stroke
				(width 0.1)
				(type default)
			)
			(layer "F.Fab")
		)
		(pad "1" smd rect
			(at -0.5334 0 180)
			(size 0.7112 0.6096)
			(layers "F.Cu" "F.Mask" "F.Paste")
			(net "R_MAC_UART_RX_FPGA_TX")
		)
		(pad "2" smd rect
			(at 0.5334 0 180)
			(size 0.7112 0.6096)
			(layers "F.Cu" "F.Mask" "F.Paste")
			(net "UART_MAC_RX_FPGA_TX")
		)
		(zone
			(layer "F.Cu")
			(hatch none 0.5)
			(connect_pads
				(clearance 0)
			)
			(min_thickness 0.25)
			(keepout
				(tracks allowed)
				(vias not_allowed)
				(pads allowed)
				(copperpour not_allowed)
				(footprints allowed)
			)
			(placement
				(enabled no)
				(sheetname "")
			)
			(fill
				(thermal_gap 0.5)
				(thermal_bridge_width 0.5)
				(island_removal_mode 0)
			)
			(polygon
				(pts
					(xy 124.5108 -51.1302) (xy 124.6632 -51.1302) (xy 124.6632 -51.7398) (xy 124.5108 -51.7398)
				)
			)
		)
	)
	(footprint ""
		(layer "F.Cu")
		(at 79.8576 -45.72 180)
		(property "Reference" "R87"
			(at -0.0254 -14.13637 0)
			(unlocked yes)
			(layer "F.SilkS")
			(effects
				(font
					(size 0.7874 0.5842)
					(thickness 0.1524)
				)
			)
		)
		(property "Value" "VAL*"
			(at 0.02032 2.13233 180)
			(unlocked yes)
			(layer "F.Fab")
			(hide yes)
			(effects
				(font
					(size 0.7874 0.5842)
					(thickness 0.1524)
				)
			)
		)
		(property "Device Type" "RESISTOR-G155-100R0-J0,0OHM,-"
			(at 0.008382 1.210564 180)
			(unlocked yes)
			(layer "F.Fab")
			(hide yes)
			(effects
				(font
					(size 0.7874 0.5842)
					(thickness 0.1524)
				)
			)
		)
		(property "User Part Number" "PARTNUM*"
			(at 0.02032 4.024884 180)
			(unlocked yes)
			(layer "Cmts.User")
			(hide yes)
			(effects
				(font
					(size 0.7874 0.5842)
					(thickness 0.1524)
				)
			)
		)
		(property "Tolerance" "TOL*"
			(at 0.044704 3.05435 180)
			(unlocked yes)
			(layer "Cmts.User")
			(hide yes)
			(effects
				(font
					(size 0.7874 0.5842)
					(thickness 0.1524)
				)
			)
		)
		(duplicate_pad_numbers_are_jumpers no)
		(fp_line
			(start 1.143 0.5588)
			(end 1.143 -0.5588)
			(stroke
				(width 0.1)
				(type default)
			)
			(layer "F.SilkS")
		)
		(fp_line
			(start 1.143 -0.5588)
			(end -1.143 -0.5588)
			(stroke
				(width 0.1)
				(type default)
			)
			(layer "F.SilkS")
		)
		(fp_line
			(start -1.143 0.5588)
			(end 1.143 0.5588)
			(stroke
				(width 0.1)
				(type default)
			)
			(layer "F.SilkS")
		)
		(fp_line
			(start -1.143 -0.5588)
			(end -1.143 0.5588)
			(stroke
				(width 0.1)
				(type default)
			)
			(layer "F.SilkS")
		)
		(fp_rect
			(start 1.143 -0.5588)
			(end -1.143 0.5588)
			(stroke
				(width 0)
				(type default)
			)
			(fill no)
			(layer "F.CrtYd")
		)
		(fp_line
			(start 0.508 0.3048)
			(end 0.508 -0.3048)
			(stroke
				(width 0.1)
				(type default)
			)
			(layer "F.Fab")
		)
		(fp_line
			(start 0.508 -0.3048)
			(end -0.508 -0.3048)
			(stroke
				(width 0.1)
				(type default)
			)
			(layer "F.Fab")
		)
		(fp_line
			(start -0.508 0.3048)
			(end 0.508 0.3048)
			(stroke
				(width 0.1)
				(type default)
			)
			(layer "F.Fab")
		)
		(fp_line
			(start -0.508 -0.3048)
			(end -0.508 0.3048)
			(stroke
				(width 0.1)
				(type default)
			)
			(layer "F.Fab")
		)
		(pad "1" smd rect
			(at -0.5334 0 180)
			(size 0.7112 0.6096)
			(layers "F.Cu" "F.Mask" "F.Paste")
			(net "FPGA_IN_MAC_PPS_OUTP")
		)
		(pad "2" smd rect
			(at 0.5334 0 180)
			(size 0.7112 0.6096)
			(layers "F.Cu" "F.Mask" "F.Paste")
			(net "R_MAC_PPS_OUTP")
		)
		(zone
			(layer "F.Cu")
			(hatch none 0.5)
			(connect_pads
				(clearance 0)
			)
			(min_thickness 0.25)
			(keepout
				(tracks allowed)
				(vias not_allowed)
				(pads allowed)
				(copperpour not_allowed)
				(footprints allowed)
			)
			(placement
				(enabled no)
				(sheetname "")
			)
			(fill
				(thermal_gap 0.5)
				(thermal_bridge_width 0.5)
				(island_removal_mode 0)
			)
			(polygon
				(pts
					(xy 79.7814 -45.4152) (xy 79.9338 -45.4152) (xy 79.9338 -46.0248) (xy 79.7814 -46.0248)
				)
			)
		)
	)
	(footprint ""
		(layer "F.Cu")
		(at 55.245 -123.698)
		(property "Reference" "SP79"
			(at 0 0 0)
			(layer "F.SilkS")
			(hide yes)
			(effects
				(font
					(size 1.27 1.27)
				)
			)
		)
		(property "Value" ""
			(at 0 0 0)
			(layer "F.Fab")
			(effects
				(font
					(size 1.27 1.27)
				)
			)
		)
		(duplicate_pad_numbers_are_jumpers no)
	)
	(footprint ""
		(layer "F.Cu")
		(at 7.2898 -68.201032 90)
		(property "Reference" "R376"
			(at 3.553968 -0.39243 90)
			(unlocked yes)
			(layer "F.SilkS")
			(effects
				(font
					(size 0.7874 0.5842)
					(thickness 0.1524)
				)
			)
		)
		(property "Value" "VAL*"
			(at 0.02032 2.13233 90)
			(unlocked yes)
			(layer "F.Fab")
			(hide yes)
			(effects
				(font
					(size 0.7874 0.5842)
					(thickness 0.1524)
				)
			)
		)
		(property "Device Type" "RESISTOR-G155-11000-01,100OHM,A"
			(at 0.008382 1.210564 90)
			(unlocked yes)
			(layer "F.Fab")
			(hide yes)
			(effects
				(font
					(size 0.7874 0.5842)
					(thickness 0.1524)
				)
			)
		)
		(property "User Part Number" "PARTNUM*"
			(at 0.02032 4.024884 90)
			(unlocked yes)
			(layer "Cmts.User")
			(hide yes)
			(effects
				(font
					(size 0.7874 0.5842)
					(thickness 0.1524)
				)
			)
		)
		(property "Tolerance" "TOL*"
			(at 0.044704 3.05435 90)
			(unlocked yes)
			(layer "Cmts.User")
			(hide yes)
			(effects
				(font
					(size 0.7874 0.5842)
					(thickness 0.1524)
				)
			)
		)
		(duplicate_pad_numbers_are_jumpers no)
		(fp_line
			(start 1.143 -0.5588)
			(end -1.143 -0.5588)
			(stroke
				(width 0.1)
				(type default)
			)
			(layer "F.SilkS")
		)
		(fp_line
			(start -1.143 -0.5588)
			(end -1.143 0.5588)
			(stroke
				(width 0.1)
				(type default)
			)
			(layer "F.SilkS")
		)
		(fp_line
			(start 1.143 0.5588)
			(end 1.143 -0.5588)
			(stroke
				(width 0.1)
				(type default)
			)
			(layer "F.SilkS")
		)
		(fp_line
			(start -1.143 0.5588)
			(end 1.143 0.5588)
			(stroke
				(width 0.1)
				(type default)
			)
			(layer "F.SilkS")
		)
		(fp_poly
			(pts
				(xy -1.143 0.5588) (xy 1.143 0.5588) (xy 1.143 -0.5588) (xy -1.143 -0.5588)
			)
			(stroke
				(width 0)
				(type default)
			)
			(fill no)
			(layer "F.CrtYd")
		)
		(fp_line
			(start 0.508 -0.3048)
			(end -0.508 -0.3048)
			(stroke
				(width 0.1)
				(type default)
			)
			(layer "F.Fab")
		)
		(fp_line
			(start -0.508 -0.3048)
			(end -0.508 0.3048)
			(stroke
				(width 0.1)
				(type default)
			)
			(layer "F.Fab")
		)
		(fp_line
			(start 0.508 0.3048)
			(end 0.508 -0.3048)
			(stroke
				(width 0.1)
				(type default)
			)
			(layer "F.Fab")
		)
		(fp_line
			(start -0.508 0.3048)
			(end 0.508 0.3048)
			(stroke
				(width 0.1)
				(type default)
			)
			(layer "F.Fab")
		)
		(pad "1" smd rect
			(at -0.5334 0 90)
			(size 0.7112 0.6096)
			(layers "F.Cu" "F.Mask" "F.Paste")
			(net "FPGA_OUT_SMA3_LED_RED_N")
		)
		(pad "2" smd rect
			(at 0.5334 0 90)
			(size 0.7112 0.6096)
			(layers "F.Cu" "F.Mask" "F.Paste")
			(net "UNNAMED_14_LED4PV14_I267_3")
		)
		(zone
			(layer "F.Cu")
			(hatch none 0.5)
			(connect_pads
				(clearance 0)
			)
			(min_thickness 0.25)
			(keepout
				(tracks not_allowed)
				(vias allowed)
				(pads allowed)
				(copperpour not_allowed)
				(footprints allowed)
			)
			(placement
				(enabled no)
				(sheetname "")
			)
			(fill
				(thermal_gap 0.5)
				(thermal_bridge_width 0.5)
				(island_removal_mode 0)
			)
			(polygon
				(pts
					(xy 7.5946 -68.124832) (xy 7.5946 -68.277232) (xy 6.985 -68.277232) (xy 6.985 -68.124832)
				)
			)
		)
		(zone
			(layer "F.Cu")
			(hatch none 0.5)
			(connect_pads
				(clearance 0)
			)
			(min_thickness 0.25)
			(keepout
				(tracks allowed)
				(vias not_allowed)
				(pads allowed)
				(copperpour not_allowed)
				(footprints allowed)
			)
			(placement
				(enabled no)
				(sheetname "")
			)
			(fill
				(thermal_gap 0.5)
				(thermal_bridge_width 0.5)
				(island_removal_mode 0)
			)
			(polygon
				(pts
					(xy 7.5946 -68.124832) (xy 7.5946 -68.277232) (xy 6.985 -68.277232) (xy 6.985 -68.124832)
				)
			)
		)
	)
	(footprint ""
		(layer "F.Cu")
		(at 66.04 -126.873)
		(property "Reference" "SP49"
			(at 0 0 0)
			(layer "F.SilkS")
			(hide yes)
			(effects
				(font
					(size 1.27 1.27)
				)
			)
		)
		(property "Value" ""
			(at 0 0 0)
			(layer "F.Fab")
			(effects
				(font
					(size 1.27 1.27)
				)
			)
		)
		(duplicate_pad_numbers_are_jumpers no)
	)
	(footprint ""
		(layer "F.Cu")
		(at 13.899896 -61.60008 -90)
		(property "Reference" "U15"
			(at -0.88392 2.430526 90)
			(unlocked yes)
			(layer "F.SilkS")
			(effects
				(font
					(size 0.7874 0.5842)
					(thickness 0.1524)
				)
			)
		)
		(property "Value" ""
			(at 0 0 270)
			(layer "F.Fab")
			(effects
				(font
					(size 1.27 1.27)
				)
			)
		)
		(property "User Part Number" "PARTNUM*"
			(at 0 3.6068 270)
			(unlocked yes)
			(layer "Cmts.User")
			(hide yes)
			(effects
				(font
					(size 0.7874 0.5842)
					(thickness 0.1524)
				)
			)
		)
		(property "Device Type" "74HCT2G125DP_TSSOP8-G220-00055A"
			(at 0 2.413 270)
			(unlocked yes)
			(layer "F.Fab")
			(hide yes)
			(effects
				(font
					(size 0.7874 0.5842)
					(thickness 0.1524)
				)
			)
		)
		(duplicate_pad_numbers_are_jumpers no)
		(fp_line
			(start -2.426716 1.304036)
			(end -2.426716 -1.304036)
			(stroke
				(width 0.1)
				(type default)
			)
			(layer "F.SilkS")
		)
		(fp_line
			(start 2.426716 1.304036)
			(end -2.426716 1.304036)
			(stroke
				(width 0.1)
				(type default)
			)
			(layer "F.SilkS")
		)
		(fp_line
			(start -2.426716 -1.304036)
			(end 2.426716 -1.304036)
			(stroke
				(width 0.1)
				(type default)
			)
			(layer "F.SilkS")
		)
		(fp_line
			(start 2.426716 -1.304036)
			(end 2.426716 1.304036)
			(stroke
				(width 0.1)
				(type default)
			)
			(layer "F.SilkS")
		)
		(fp_poly
			(pts
				(arc
					(start -3.21437 -1.465326)
					(mid -3.21437 -0.703326)
					(end -3.21437 -1.465326)
				)
			)
			(stroke
				(width 0)
				(type default)
			)
			(fill yes)
			(layer "F.SilkS")
		)
		(fp_poly
			(pts
				(xy -2.680716 1.558036) (xy 2.680716 1.558036) (xy 2.680716 -1.558036) (xy -2.680716 -1.558036)
			)
			(stroke
				(width 0)
				(type default)
			)
			(fill no)
			(layer "F.CrtYd")
		)
		(fp_line
			(start -1.199896 1.050036)
			(end 1.199896 1.050036)
			(stroke
				(width 0.1)
				(type default)
			)
			(layer "F.Fab")
		)
		(fp_line
			(start 1.199896 1.050036)
			(end 1.199896 -1.050036)
			(stroke
				(width 0.1)
				(type default)
			)
			(layer "F.Fab")
		)
		(fp_line
			(start -1.199896 -1.050036)
			(end -1.199896 1.050036)
			(stroke
				(width 0.1)
				(type default)
			)
			(layer "F.Fab")
		)
		(fp_line
			(start 1.199896 -1.050036)
			(end -1.199896 -1.050036)
			(stroke
				(width 0.1)
				(type default)
			)
			(layer "F.Fab")
		)
		(fp_poly
			(pts
				(arc
					(start -2.02692 -1.721104)
					(mid -2.02692 -0.959104)
					(end -2.02692 -1.721104)
				)
			)
			(stroke
				(width 0)
				(type default)
			)
			(fill yes)
			(layer "F.Fab")
		)
		(fp_text user "4"
			(at -1.53797 1.707896 0)
			(unlocked yes)
			(layer "F.SilkS")
			(effects
				(font
					(size 0.635 0.4064)
					(thickness 0.1524)
				)
			)
		)
		(fp_text user "5"
			(at 2.78003 1.580896 0)
			(unlocked yes)
			(layer "F.SilkS")
			(effects
				(font
					(size 0.635 0.4064)
					(thickness 0.1524)
				)
			)
		)
		(fp_text user "8"
			(at 2.70383 -1.594104 0)
			(unlocked yes)
			(layer "F.SilkS")
			(effects
				(font
					(size 0.635 0.4064)
					(thickness 0.1524)
				)
			)
		)
		(fp_text user "5"
			(at 1.816608 1.326896 0)
			(unlocked yes)
			(layer "F.Fab")
			(effects
				(font
					(size 0.7874 0.5842)
					(thickness 0.1524)
				)
			)
		)
		(fp_text user "4"
			(at -1.993392 1.199896 0)
			(unlocked yes)
			(layer "F.Fab")
			(effects
				(font
					(size 0.7874 0.5842)
					(thickness 0.1524)
				)
			)
		)
		(fp_text user "8"
			(at 1.94945 -1.340104 0)
			(unlocked yes)
			(layer "F.Fab")
			(effects
				(font
					(size 0.7874 0.5842)
					(thickness 0.1524)
				)
			)
		)
		(pad "1" smd rect
			(at -1.690116 -0.749808 270)
			(size 0.9652 0.3048)
			(layers "F.Cu" "F.Mask" "F.Paste")
			(net "SMA1_SIG_OUT_BF_EN_N")
		)
		(pad "2" smd rect
			(at -1.690116 -0.249936 270)
			(size 0.9652 0.3048)
			(layers "F.Cu" "F.Mask" "F.Paste")
			(net "UNNAMED_12_74HCT2G125DPTSSOP8_6")
		)
		(pad "3" smd rect
			(at -1.690116 0.249936 270)
			(size 0.9652 0.3048)
			(layers "F.Cu" "F.Mask" "F.Paste")
			(net "BF_ANT1_IN")
		)
		(pad "4" smd rect
			(at -1.690116 0.749808 270)
			(size 0.9652 0.3048)
			(layers "F.Cu" "F.Mask" "F.Paste")
			(net "SG")
		)
		(pad "5" smd rect
			(at 1.690116 0.749808 270)
			(size 0.9652 0.3048)
			(layers "F.Cu" "F.Mask" "F.Paste")
			(net "BF_SMA1_SIG_IO_CONN")
		)
		(pad "6" smd rect
			(at 1.690116 0.249936 270)
			(size 0.9652 0.3048)
			(layers "F.Cu" "F.Mask" "F.Paste")
			(net "BF_SMA1_SIG_IO_CONN")
		)
		(pad "7" smd rect
			(at 1.690116 -0.249936 270)
			(size 0.9652 0.3048)
			(layers "F.Cu" "F.Mask" "F.Paste")
			(net "SMA1_SIG_IN_BF_EN_N")
		)
		(pad "8" smd rect
			(at 1.690116 -0.749808 270)
			(size 0.9652 0.3048)
			(layers "F.Cu" "F.Mask" "F.Paste")
			(net "XP3R3V_FPGA")
		)
	)
	(footprint ""
		(layer "F.Cu")
		(at 57.15 -122.047)
		(property "Reference" "SP44"
			(at 0 0 0)
			(layer "F.SilkS")
			(hide yes)
			(effects
				(font
					(size 1.27 1.27)
				)
			)
		)
		(property "Value" ""
			(at 0 0 0)
			(layer "F.Fab")
			(effects
				(font
					(size 1.27 1.27)
				)
			)
		)
		(duplicate_pad_numbers_are_jumpers no)
	)
	(footprint ""
		(layer "F.Cu")
		(at 141.732 -41.021)
		(property "Reference" "TP54"
			(at -1.8542 1.18237 0)
			(unlocked yes)
			(layer "F.SilkS")
			(effects
				(font
					(size 0.7874 0.5842)
					(thickness 0.1524)
				)
				(justify left)
			)
		)
		(property "Value" ""
			(at 0 0 0)
			(layer "F.Fab")
			(effects
				(font
					(size 1.27 1.27)
				)
			)
		)
		(property "Device Type" "TP_PIONT-TP010CT020B030_PTH-TPA"
			(at -1.341882 0.996696 0)
			(unlocked yes)
			(layer "F.Fab")
			(hide yes)
			(effects
				(font
					(size 0.7874 0.5842)
					(thickness 0.1524)
				)
				(justify left)
			)
		)
		(duplicate_pad_numbers_are_jumpers no)
		(fp_poly
			(pts
				(arc
					(start 0.889 0)
					(mid -0.889 0)
					(end 0.889 0)
				)
			)
			(stroke
				(width 0)
				(type default)
			)
			(fill no)
			(layer "B.CrtYd")
		)
		(fp_poly
			(pts
				(arc
					(start 0.889 0)
					(mid -0.889 0)
					(end 0.889 0)
				)
			)
			(stroke
				(width 0)
				(type default)
			)
			(fill no)
			(layer "F.CrtYd")
		)
		(pad "1" thru_hole circle
			(at 0 0)
			(size 0.508 0.508)
			(drill 0.254)
			(layers "*.Cu" "*.Mask")
			(remove_unused_layers no)
			(net "XP1R0V_FPGA")
			(clearance 0.1016)
			(padstack
				(mode front_inner_back)
				(layer "Inner"
					(shape circle)
					(size 0.508 0.508)
					(clearance 0.1016)
				)
				(layer "B.Cu"
					(shape circle)
					(size 0.762 0.762)
					(clearance -0.0254)
				)
			)
		)
	)
	(footprint ""
		(layer "F.Cu")
		(at 26.797 -94.234 -90)
		(property "Reference" "R456"
			(at -4.953 0.34163 90)
			(unlocked yes)
			(layer "F.SilkS")
			(effects
				(font
					(size 0.7874 0.5842)
					(thickness 0.1524)
				)
			)
		)
		(property "Value" "VAL*"
			(at 0.02032 2.13233 270)
			(unlocked yes)
			(layer "F.Fab")
			(hide yes)
			(effects
				(font
					(size 0.7874 0.5842)
					(thickness 0.1524)
				)
			)
		)
		(property "Tolerance" "TOL*"
			(at 0.044704 3.05435 270)
			(unlocked yes)
			(layer "Cmts.User")
			(hide yes)
			(effects
				(font
					(size 0.7874 0.5842)
					(thickness 0.1524)
				)
			)
		)
		(property "User Part Number" "PARTNUM*"
			(at 0.02032 4.024884 270)
			(unlocked yes)
			(layer "Cmts.User")
			(hide yes)
			(effects
				(font
					(size 0.7874 0.5842)
					(thickness 0.1524)
				)
			)
		)
		(property "Device Type" "RESISTOR-G155-11000-01,100OHM,A"
			(at 0.008382 1.210564 270)
			(unlocked yes)
			(layer "F.Fab")
			(hide yes)
			(effects
				(font
					(size 0.7874 0.5842)
					(thickness 0.1524)
				)
			)
		)
		(duplicate_pad_numbers_are_jumpers no)
		(fp_line
			(start -1.143 0.5588)
			(end 1.143 0.5588)
			(stroke
				(width 0.1)
				(type default)
			)
			(layer "F.SilkS")
		)
		(fp_line
			(start 1.143 0.5588)
			(end 1.143 -0.5588)
			(stroke
				(width 0.1)
				(type default)
			)
			(layer "F.SilkS")
		)
		(fp_line
			(start -1.143 -0.5588)
			(end -1.143 0.5588)
			(stroke
				(width 0.1)
				(type default)
			)
			(layer "F.SilkS")
		)
		(fp_line
			(start 1.143 -0.5588)
			(end -1.143 -0.5588)
			(stroke
				(width 0.1)
				(type default)
			)
			(layer "F.SilkS")
		)
		(fp_poly
			(pts
				(xy -1.143 0.5588) (xy 1.143 0.5588) (xy 1.143 -0.5588) (xy -1.143 -0.5588)
			)
			(stroke
				(width 0)
				(type default)
			)
			(fill no)
			(layer "F.CrtYd")
		)
		(fp_line
			(start -0.508 0.3048)
			(end 0.508 0.3048)
			(stroke
				(width 0.1)
				(type default)
			)
			(layer "F.Fab")
		)
		(fp_line
			(start 0.508 0.3048)
			(end 0.508 -0.3048)
			(stroke
				(width 0.1)
				(type default)
			)
			(layer "F.Fab")
		)
		(fp_line
			(start -0.508 -0.3048)
			(end -0.508 0.3048)
			(stroke
				(width 0.1)
				(type default)
			)
			(layer "F.Fab")
		)
		(fp_line
			(start 0.508 -0.3048)
			(end -0.508 -0.3048)
			(stroke
				(width 0.1)
				(type default)
			)
			(layer "F.Fab")
		)
		(pad "1" smd rect
			(at -0.5334 0 270)
			(size 0.7112 0.6096)
			(layers "F.Cu" "F.Mask" "F.Paste")
			(net "XP3R3V_FT_PG")
		)
		(pad "2" smd rect
			(at 0.5334 0 270)
			(size 0.7112 0.6096)
			(layers "F.Cu" "F.Mask" "F.Paste")
			(net "FT_USB_DETECT")
		)
		(zone
			(layer "F.Cu")
			(hatch none 0.5)
			(connect_pads
				(clearance 0)
			)
			(min_thickness 0.25)
			(keepout
				(tracks allowed)
				(vias not_allowed)
				(pads allowed)
				(copperpour not_allowed)
				(footprints allowed)
			)
			(placement
				(enabled no)
				(sheetname "")
			)
			(fill
				(thermal_gap 0.5)
				(thermal_bridge_width 0.5)
				(island_removal_mode 0)
			)
			(polygon
				(pts
					(xy 26.4922 -94.3102) (xy 26.4922 -94.1578) (xy 27.1018 -94.1578) (xy 27.1018 -94.3102)
				)
			)
		)
		(zone
			(layer "F.Cu")
			(hatch none 0.5)
			(connect_pads
				(clearance 0)
			)
			(min_thickness 0.25)
			(keepout
				(tracks not_allowed)
				(vias allowed)
				(pads allowed)
				(copperpour not_allowed)
				(footprints allowed)
			)
			(placement
				(enabled no)
				(sheetname "")
			)
			(fill
				(thermal_gap 0.5)
				(thermal_bridge_width 0.5)
				(island_removal_mode 0)
			)
			(polygon
				(pts
					(xy 26.4922 -94.3102) (xy 26.4922 -94.1578) (xy 27.1018 -94.1578) (xy 27.1018 -94.3102)
				)
			)
		)
	)
	(footprint ""
		(layer "F.Cu")
		(at 23.5712 -65.544192 180)
		(property "Reference" "C276"
			(at -3.4798 -0.051562 0)
			(unlocked yes)
			(layer "F.SilkS")
			(effects
				(font
					(size 0.7874 0.5842)
					(thickness 0.1524)
				)
			)
		)
		(property "Value" "VAL*"
			(at 0.0762 2.067306 180)
			(unlocked yes)
			(layer "F.Fab")
			(hide yes)
			(effects
				(font
					(size 0.7874 0.5842)
					(thickness 0.1524)
				)
			)
		)
		(property "Tolerance" "TOL*"
			(at 0.0762 3.032506 180)
			(unlocked yes)
			(layer "Cmts.User")
			(hide yes)
			(effects
				(font
					(size 0.7874 0.5842)
					(thickness 0.1524)
				)
			)
		)
		(property "User Part Number" "PARTNUM*"
			(at 0.1016 4.023106 180)
			(unlocked yes)
			(layer "Cmts.User")
			(hide yes)
			(effects
				(font
					(size 0.7874 0.5842)
					(thickness 0.1524)
				)
			)
		)
		(property "Device Type" "CAPACITOR-G105-0B104-EK,0.1UF,A"
			(at 0.0508 1.127506 180)
			(unlocked yes)
			(layer "F.Fab")
			(hide yes)
			(effects
				(font
					(size 0.7874 0.5842)
					(thickness 0.1524)
				)
			)
		)
		(duplicate_pad_numbers_are_jumpers no)
		(fp_line
			(start 1.143 0.5588)
			(end 1.143 -0.5588)
			(stroke
				(width 0.1)
				(type default)
			)
			(layer "F.SilkS")
		)
		(fp_line
			(start 1.143 -0.5588)
			(end -1.143 -0.5588)
			(stroke
				(width 0.1)
				(type default)
			)
			(layer "F.SilkS")
		)
		(fp_line
			(start -1.143 0.5588)
			(end 1.143 0.5588)
			(stroke
				(width 0.1)
				(type default)
			)
			(layer "F.SilkS")
		)
		(fp_line
			(start -1.143 -0.5588)
			(end -1.143 0.5588)
			(stroke
				(width 0.1)
				(type default)
			)
			(layer "F.SilkS")
		)
		(fp_rect
			(start 1.143 0.5588)
			(end -1.143 -0.5588)
			(stroke
				(width 0)
				(type default)
			)
			(fill no)
			(layer "F.CrtYd")
		)
		(fp_line
			(start 0.508 0.3048)
			(end 0.508 -0.3048)
			(stroke
				(width 0.1)
				(type default)
			)
			(layer "F.Fab")
		)
		(fp_line
			(start 0.508 -0.3048)
			(end -0.508 -0.3048)
			(stroke
				(width 0.1)
				(type default)
			)
			(layer "F.Fab")
		)
		(fp_line
			(start -0.508 0.3048)
			(end 0.508 0.3048)
			(stroke
				(width 0.1)
				(type default)
			)
			(layer "F.Fab")
		)
		(fp_line
			(start -0.508 -0.3048)
			(end -0.508 0.3048)
			(stroke
				(width 0.1)
				(type default)
			)
			(layer "F.Fab")
		)
		(pad "1" smd rect
			(at -0.5334 0 180)
			(size 0.7112 0.6096)
			(layers "F.Cu" "F.Mask" "F.Paste")
			(net "XP1R8V_FPGA")
		)
		(pad "2" smd rect
			(at 0.5334 0 180)
			(size 0.7112 0.6096)
			(layers "F.Cu" "F.Mask" "F.Paste")
			(net "SG")
		)
		(zone
			(layer "F.Cu")
			(hatch none 0.5)
			(connect_pads
				(clearance 0)
			)
			(min_thickness 0.25)
			(keepout
				(tracks allowed)
				(vias not_allowed)
				(pads allowed)
				(copperpour not_allowed)
				(footprints allowed)
			)
			(placement
				(enabled no)
				(sheetname "")
			)
			(fill
				(thermal_gap 0.5)
				(thermal_bridge_width 0.5)
				(island_removal_mode 0)
			)
			(polygon
				(pts
					(xy 23.495 -65.848992) (xy 23.495 -65.239392) (xy 23.6474 -65.239392) (xy 23.6474 -65.848992)
				)
			)
		)
	)
	(footprint ""
		(layer "F.Cu")
		(at 6.1468 -68.201032 90)
		(property "Reference" "R374"
			(at 3.553968 -0.26543 90)
			(unlocked yes)
			(layer "F.SilkS")
			(effects
				(font
					(size 0.7874 0.5842)
					(thickness 0.1524)
				)
			)
		)
		(property "Value" "VAL*"
			(at 0.02032 2.13233 90)
			(unlocked yes)
			(layer "F.Fab")
			(hide yes)
			(effects
				(font
					(size 0.7874 0.5842)
					(thickness 0.1524)
				)
			)
		)
		(property "Device Type" "RESISTOR-G155-11000-01,100OHM,A"
			(at 0.008382 1.210564 90)
			(unlocked yes)
			(layer "F.Fab")
			(hide yes)
			(effects
				(font
					(size 0.7874 0.5842)
					(thickness 0.1524)
				)
			)
		)
		(property "User Part Number" "PARTNUM*"
			(at 0.02032 4.024884 90)
			(unlocked yes)
			(layer "Cmts.User")
			(hide yes)
			(effects
				(font
					(size 0.7874 0.5842)
					(thickness 0.1524)
				)
			)
		)
		(property "Tolerance" "TOL*"
			(at 0.044704 3.05435 90)
			(unlocked yes)
			(layer "Cmts.User")
			(hide yes)
			(effects
				(font
					(size 0.7874 0.5842)
					(thickness 0.1524)
				)
			)
		)
		(duplicate_pad_numbers_are_jumpers no)
		(fp_line
			(start 1.143 -0.5588)
			(end -1.143 -0.5588)
			(stroke
				(width 0.1)
				(type default)
			)
			(layer "F.SilkS")
		)
		(fp_line
			(start -1.143 -0.5588)
			(end -1.143 0.5588)
			(stroke
				(width 0.1)
				(type default)
			)
			(layer "F.SilkS")
		)
		(fp_line
			(start 1.143 0.5588)
			(end 1.143 -0.5588)
			(stroke
				(width 0.1)
				(type default)
			)
			(layer "F.SilkS")
		)
		(fp_line
			(start -1.143 0.5588)
			(end 1.143 0.5588)
			(stroke
				(width 0.1)
				(type default)
			)
			(layer "F.SilkS")
		)
		(fp_poly
			(pts
				(xy -1.143 0.5588) (xy 1.143 0.5588) (xy 1.143 -0.5588) (xy -1.143 -0.5588)
			)
			(stroke
				(width 0)
				(type default)
			)
			(fill no)
			(layer "F.CrtYd")
		)
		(fp_line
			(start 0.508 -0.3048)
			(end -0.508 -0.3048)
			(stroke
				(width 0.1)
				(type default)
			)
			(layer "F.Fab")
		)
		(fp_line
			(start -0.508 -0.3048)
			(end -0.508 0.3048)
			(stroke
				(width 0.1)
				(type default)
			)
			(layer "F.Fab")
		)
		(fp_line
			(start 0.508 0.3048)
			(end 0.508 -0.3048)
			(stroke
				(width 0.1)
				(type default)
			)
			(layer "F.Fab")
		)
		(fp_line
			(start -0.508 0.3048)
			(end 0.508 0.3048)
			(stroke
				(width 0.1)
				(type default)
			)
			(layer "F.Fab")
		)
		(pad "1" smd rect
			(at -0.5334 0 90)
			(size 0.7112 0.6096)
			(layers "F.Cu" "F.Mask" "F.Paste")
			(net "FPGA_OUT_SMA3_LED_BLUE_N")
		)
		(pad "2" smd rect
			(at 0.5334 0 90)
			(size 0.7112 0.6096)
			(layers "F.Cu" "F.Mask" "F.Paste")
			(net "UNNAMED_14_LED4PV14_I267_1")
		)
		(zone
			(layer "F.Cu")
			(hatch none 0.5)
			(connect_pads
				(clearance 0)
			)
			(min_thickness 0.25)
			(keepout
				(tracks allowed)
				(vias not_allowed)
				(pads allowed)
				(copperpour not_allowed)
				(footprints allowed)
			)
			(placement
				(enabled no)
				(sheetname "")
			)
			(fill
				(thermal_gap 0.5)
				(thermal_bridge_width 0.5)
				(island_removal_mode 0)
			)
			(polygon
				(pts
					(xy 6.4516 -68.124832) (xy 6.4516 -68.277232) (xy 5.842 -68.277232) (xy 5.842 -68.124832)
				)
			)
		)
		(zone
			(layer "F.Cu")
			(hatch none 0.5)
			(connect_pads
				(clearance 0)
			)
			(min_thickness 0.25)
			(keepout
				(tracks not_allowed)
				(vias allowed)
				(pads allowed)
				(copperpour not_allowed)
				(footprints allowed)
			)
			(placement
				(enabled no)
				(sheetname "")
			)
			(fill
				(thermal_gap 0.5)
				(thermal_bridge_width 0.5)
				(island_removal_mode 0)
			)
			(polygon
				(pts
					(xy 6.4516 -68.124832) (xy 6.4516 -68.277232) (xy 5.842 -68.277232) (xy 5.842 -68.124832)
				)
			)
		)
	)
	(footprint ""
		(layer "F.Cu")
		(at 5.969 -25.4 90)
		(property "Reference" "CR5"
			(at -0.508 2.32537 90)
			(unlocked yes)
			(layer "F.SilkS")
			(effects
				(font
					(size 0.7874 0.5842)
					(thickness 0.1524)
				)
			)
		)
		(property "Value" ""
			(at 0 0 90)
			(layer "F.Fab")
			(effects
				(font
					(size 1.27 1.27)
				)
			)
		)
		(property "User Part Number" "PARTNUM*"
			(at 0.254 3.718306 90)
			(unlocked yes)
			(layer "Cmts.User")
			(hide yes)
			(effects
				(font
					(size 0.7874 0.5842)
					(thickness 0.1524)
				)
			)
		)
		(property "Device Type" "DIODE_4_V1-G122-10123-01"
			(at 0.254 2.702306 90)
			(unlocked yes)
			(layer "F.Fab")
			(hide yes)
			(effects
				(font
					(size 0.7874 0.5842)
					(thickness 0.1524)
				)
			)
		)
		(duplicate_pad_numbers_are_jumpers no)
		(fp_line
			(start 2.0828 -1.7018)
			(end 2.0828 1.7018)
			(stroke
				(width 0.1)
				(type default)
			)
			(layer "F.SilkS")
		)
		(fp_line
			(start -2.0828 -1.7018)
			(end 2.0828 -1.7018)
			(stroke
				(width 0.1)
				(type default)
			)
			(layer "F.SilkS")
		)
		(fp_line
			(start 2.0828 1.7018)
			(end -2.0828 1.7018)
			(stroke
				(width 0.1)
				(type default)
			)
			(layer "F.SilkS")
		)
		(fp_line
			(start -2.0828 1.7018)
			(end -2.0828 -1.7018)
			(stroke
				(width 0.1)
				(type default)
			)
			(layer "F.SilkS")
		)
		(fp_poly
			(pts
				(arc
					(start -2.6162 -0.508)
					(mid -2.6162 -1.27)
					(end -2.6162 -0.508)
				)
			)
			(stroke
				(width 0)
				(type default)
			)
			(fill yes)
			(layer "F.SilkS")
		)
		(fp_rect
			(start -2.3368 -1.9304)
			(end 2.3368 1.9304)
			(stroke
				(width 0)
				(type default)
			)
			(fill no)
			(layer "F.CrtYd")
		)
		(fp_line
			(start 0.6477 -1.42875)
			(end 0.6477 1.42875)
			(stroke
				(width 0.1)
				(type default)
			)
			(layer "F.Fab")
		)
		(fp_line
			(start -0.6477 -1.42875)
			(end 0.6477 -1.42875)
			(stroke
				(width 0.1)
				(type default)
			)
			(layer "F.Fab")
		)
		(fp_line
			(start 1.143 -1.1811)
			(end 1.143 -0.7239)
			(stroke
				(width 0.1)
				(type default)
			)
			(layer "F.Fab")
		)
		(fp_line
			(start 0.6477 -1.1811)
			(end 1.143 -1.1811)
			(stroke
				(width 0.1)
				(type default)
			)
			(layer "F.Fab")
		)
		(fp_line
			(start -0.6477 -1.1811)
			(end -0.6477 -0.3175)
			(stroke
				(width 0.1)
				(type default)
			)
			(layer "F.Fab")
		)
		(fp_line
			(start -1.143 -1.1811)
			(end -0.6477 -1.1811)
			(stroke
				(width 0.1)
				(type default)
			)
			(layer "F.Fab")
		)
		(fp_line
			(start 1.143 -0.7239)
			(end 0.6477 -0.7239)
			(stroke
				(width 0.1)
				(type default)
			)
			(layer "F.Fab")
		)
		(fp_line
			(start 0.6477 -0.7239)
			(end 0.6477 -1.1811)
			(stroke
				(width 0.1)
				(type default)
			)
			(layer "F.Fab")
		)
		(fp_line
			(start -0.6477 -0.3175)
			(end -1.143 -0.3175)
			(stroke
				(width 0.1)
				(type default)
			)
			(layer "F.Fab")
		)
		(fp_line
			(start -1.143 -0.3175)
			(end -1.143 -1.1811)
			(stroke
				(width 0.1)
				(type default)
			)
			(layer "F.Fab")
		)
		(fp_line
			(start 1.143 0.7239)
			(end 1.143 1.1811)
			(stroke
				(width 0.1)
				(type default)
			)
			(layer "F.Fab")
		)
		(fp_line
			(start 0.6477 0.7239)
			(end 1.143 0.7239)
			(stroke
				(width 0.1)
				(type default)
			)
			(layer "F.Fab")
		)
		(fp_line
			(start -0.6477 0.7239)
			(end -0.6477 1.1811)
			(stroke
				(width 0.1)
				(type default)
			)
			(layer "F.Fab")
		)
		(fp_line
			(start -1.143 0.7239)
			(end -0.6477 0.7239)
			(stroke
				(width 0.1)
				(type default)
			)
			(layer "F.Fab")
		)
		(fp_line
			(start 1.143 1.1811)
			(end 0.6477 1.1811)
			(stroke
				(width 0.1)
				(type default)
			)
			(layer "F.Fab")
		)
		(fp_line
			(start 0.6477 1.1811)
			(end 0.6477 0.7239)
			(stroke
				(width 0.1)
				(type default)
			)
			(layer "F.Fab")
		)
		(fp_line
			(start -0.6477 1.1811)
			(end -1.143 1.1811)
			(stroke
				(width 0.1)
				(type default)
			)
			(layer "F.Fab")
		)
		(fp_line
			(start -1.143 1.1811)
			(end -1.143 0.7239)
			(stroke
				(width 0.1)
				(type default)
			)
			(layer "F.Fab")
		)
		(fp_line
			(start 0.6477 1.42875)
			(end -0.6477 1.42875)
			(stroke
				(width 0.1)
				(type default)
			)
			(layer "F.Fab")
		)
		(fp_line
			(start -0.6477 1.42875)
			(end -0.6477 -1.42875)
			(stroke
				(width 0.1)
				(type default)
			)
			(layer "F.Fab")
		)
		(fp_poly
			(pts
				(arc
					(start -0.381 -0.5588)
					(mid -0.381 -0.9398)
					(end -0.381 -0.5588)
				)
			)
			(stroke
				(width 0)
				(type default)
			)
			(fill yes)
			(layer "F.Fab")
		)
		(fp_text user "4"
			(at 2.510028 -1.311656 0)
			(unlocked yes)
			(layer "F.SilkS")
			(effects
				(font
					(size 0.635 0.4064)
					(thickness 0.1524)
				)
				(justify left)
			)
		)
		(fp_text user "3"
			(at 2.50825 1.4478 0)
			(unlocked yes)
			(layer "F.SilkS")
			(effects
				(font
					(size 0.635 0.4064)
					(thickness 0.1524)
				)
				(justify left)
			)
		)
		(fp_text user "2"
			(at -2.44475 1.8288 0)
			(unlocked yes)
			(layer "F.SilkS")
			(effects
				(font
					(size 0.635 0.4064)
					(thickness 0.1524)
				)
				(justify left)
			)
		)
		(fp_text user "4"
			(at 1.829308 -1.273556 0)
			(unlocked yes)
			(layer "F.Fab")
			(effects
				(font
					(size 0.7874 0.5842)
					(thickness 0.1524)
				)
				(justify left)
			)
		)
		(fp_text user "2"
			(at -1.81737 0.7239 0)
			(unlocked yes)
			(layer "F.Fab")
			(effects
				(font
					(size 0.7874 0.5842)
					(thickness 0.1524)
				)
				(justify left)
			)
		)
		(fp_text user "3"
			(at 1.829308 0.758444 0)
			(unlocked yes)
			(layer "F.Fab")
			(effects
				(font
					(size 0.7874 0.5842)
					(thickness 0.1524)
				)
				(justify left)
			)
		)
		(pad "1" smd rect
			(at -1.1049 -0.7493 90)
			(size 1.4478 1.0922)
			(layers "F.Cu" "F.Mask" "F.Paste")
			(net "SG")
		)
		(pad "2" smd rect
			(at -1.1049 0.9525 90)
			(size 1.4478 0.9906)
			(layers "F.Cu" "F.Mask" "F.Paste")
			(net "SMA4_SIG_IO_CONN")
		)
		(pad "3" smd rect
			(at 1.1049 0.9525 90)
			(size 1.4478 0.9906)
			(layers "F.Cu" "F.Mask" "F.Paste")
			(net "SMA3_SIG_IO_CONN")
		)
		(pad "4" smd rect
			(at 1.1049 -0.9525 90)
			(size 1.4478 0.9906)
			(layers "F.Cu" "F.Mask" "F.Paste")
			(net "Net_566")
		)
		(zone
			(layer "F.Cu")
			(hatch none 0.5)
			(connect_pads
				(clearance 0)
			)
			(min_thickness 0.25)
			(keepout
				(tracks allowed)
				(vias not_allowed)
				(pads allowed)
				(copperpour not_allowed)
				(footprints allowed)
			)
			(placement
				(enabled no)
				(sheetname "")
			)
			(fill
				(thermal_gap 0.5)
				(thermal_bridge_width 0.5)
				(island_removal_mode 0)
			)
			(polygon
				(pts
					(xy 4.6736 -24.7523) (xy 4.5339 -24.7523) (xy 4.5339 -25.781) (xy 5.5118 -25.781) (xy 5.5118 -26.0477)
					(xy 6.4262 -26.0477) (xy 6.4262 -25.781) (xy 7.4041 -25.781) (xy 7.4041 -25.019) (xy 6.4262 -25.019)
					(xy 6.4262 -24.7523) (xy 5.7658 -24.7523) (xy 5.7658 -25.019) (xy 4.6736 -25.019)
				)
			)
		)
	)
	(footprint ""
		(layer "F.Cu")
		(at 19.468338 -47.879 180)
		(property "Reference" "R396"
			(at -3.518662 -0.03937 0)
			(unlocked yes)
			(layer "F.SilkS")
			(effects
				(font
					(size 0.7874 0.5842)
					(thickness 0.1524)
				)
			)
		)
		(property "Value" "VAL*"
			(at 0.02032 2.13233 180)
			(unlocked yes)
			(layer "F.Fab")
			(hide yes)
			(effects
				(font
					(size 0.7874 0.5842)
					(thickness 0.1524)
				)
			)
		)
		(property "Tolerance" "TOL*"
			(at 0.044704 3.05435 180)
			(unlocked yes)
			(layer "Cmts.User")
			(hide yes)
			(effects
				(font
					(size 0.7874 0.5842)
					(thickness 0.1524)
				)
			)
		)
		(property "User Part Number" "PARTNUM*"
			(at 0.02032 4.024884 180)
			(unlocked yes)
			(layer "Cmts.User")
			(hide yes)
			(effects
				(font
					(size 0.7874 0.5842)
					(thickness 0.1524)
				)
			)
		)
		(property "Device Type" "RESISTOR-G155-133R0-01,33OHM,1%"
			(at 0.008382 1.210564 180)
			(unlocked yes)
			(layer "F.Fab")
			(hide yes)
			(effects
				(font
					(size 0.7874 0.5842)
					(thickness 0.1524)
				)
			)
		)
		(duplicate_pad_numbers_are_jumpers no)
		(fp_line
			(start 1.143 0.5588)
			(end 1.143 -0.5588)
			(stroke
				(width 0.1)
				(type default)
			)
			(layer "F.SilkS")
		)
		(fp_line
			(start 1.143 -0.5588)
			(end -1.143 -0.5588)
			(stroke
				(width 0.1)
				(type default)
			)
			(layer "F.SilkS")
		)
		(fp_line
			(start -1.143 0.5588)
			(end 1.143 0.5588)
			(stroke
				(width 0.1)
				(type default)
			)
			(layer "F.SilkS")
		)
		(fp_line
			(start -1.143 -0.5588)
			(end -1.143 0.5588)
			(stroke
				(width 0.1)
				(type default)
			)
			(layer "F.SilkS")
		)
		(fp_rect
			(start -1.143 -0.5588)
			(end 1.143 0.5588)
			(stroke
				(width 0)
				(type default)
			)
			(fill no)
			(layer "F.CrtYd")
		)
		(fp_line
			(start 0.508 0.3048)
			(end 0.508 -0.3048)
			(stroke
				(width 0.1)
				(type default)
			)
			(layer "F.Fab")
		)
		(fp_line
			(start 0.508 -0.3048)
			(end -0.508 -0.3048)
			(stroke
				(width 0.1)
				(type default)
			)
			(layer "F.Fab")
		)
		(fp_line
			(start -0.508 0.3048)
			(end 0.508 0.3048)
			(stroke
				(width 0.1)
				(type default)
			)
			(layer "F.Fab")
		)
		(fp_line
			(start -0.508 -0.3048)
			(end -0.508 0.3048)
			(stroke
				(width 0.1)
				(type default)
			)
			(layer "F.Fab")
		)
		(pad "1" smd rect
			(at -0.5334 0 180)
			(size 0.7112 0.6096)
			(layers "F.Cu" "F.Mask" "F.Paste")
			(net "SMA4_LED_RED_N")
		)
		(pad "2" smd rect
			(at 0.5334 0 180)
			(size 0.7112 0.6096)
			(layers "F.Cu" "F.Mask" "F.Paste")
			(net "UNNAMED_14_LED4PV14_I268_3")
		)
		(zone
			(layer "F.Cu")
			(hatch none 0.5)
			(connect_pads
				(clearance 0)
			)
			(min_thickness 0.25)
			(keepout
				(tracks not_allowed)
				(vias allowed)
				(pads allowed)
				(copperpour not_allowed)
				(footprints allowed)
			)
			(placement
				(enabled no)
				(sheetname "")
			)
			(fill
				(thermal_gap 0.5)
				(thermal_bridge_width 0.5)
				(island_removal_mode 0)
			)
			(polygon
				(pts
					(xy 19.544538 -47.5742) (xy 19.544538 -48.1838) (xy 19.392138 -48.1838) (xy 19.392138 -47.5742)
				)
			)
		)
		(zone
			(layer "F.Cu")
			(hatch none 0.5)
			(connect_pads
				(clearance 0)
			)
			(min_thickness 0.25)
			(keepout
				(tracks allowed)
				(vias not_allowed)
				(pads allowed)
				(copperpour not_allowed)
				(footprints allowed)
			)
			(placement
				(enabled no)
				(sheetname "")
			)
			(fill
				(thermal_gap 0.5)
				(thermal_bridge_width 0.5)
				(island_removal_mode 0)
			)
			(polygon
				(pts
					(xy 19.544538 -47.5742) (xy 19.544538 -48.1838) (xy 19.392138 -48.1838) (xy 19.392138 -47.5742)
				)
			)
		)
	)
	(footprint ""
		(layer "F.Cu")
		(at 5.9944 -39.318692 90)
		(property "Reference" "R124"
			(at 2.337308 0.08255 90)
			(unlocked yes)
			(layer "F.SilkS")
			(effects
				(font
					(size 0.635 0.4064)
					(thickness 0.1524)
				)
			)
		)
		(property "Value" "VAL*"
			(at 0.02032 2.13233 90)
			(unlocked yes)
			(layer "F.Fab")
			(hide yes)
			(effects
				(font
					(size 0.7874 0.5842)
					(thickness 0.1524)
				)
			)
		)
		(property "Device Type" "RESISTOR-G155-11000-01,100OHM,A"
			(at 0.008382 1.210564 90)
			(unlocked yes)
			(layer "F.Fab")
			(hide yes)
			(effects
				(font
					(size 0.7874 0.5842)
					(thickness 0.1524)
				)
			)
		)
		(property "User Part Number" "PARTNUM*"
			(at 0.02032 4.024884 90)
			(unlocked yes)
			(layer "Cmts.User")
			(hide yes)
			(effects
				(font
					(size 0.7874 0.5842)
					(thickness 0.1524)
				)
			)
		)
		(property "Tolerance" "TOL*"
			(at 0.044704 3.05435 90)
			(unlocked yes)
			(layer "Cmts.User")
			(hide yes)
			(effects
				(font
					(size 0.7874 0.5842)
					(thickness 0.1524)
				)
			)
		)
		(duplicate_pad_numbers_are_jumpers no)
		(fp_line
			(start 1.143 -0.5588)
			(end -1.143 -0.5588)
			(stroke
				(width 0.1)
				(type default)
			)
			(layer "F.SilkS")
		)
		(fp_line
			(start -1.143 -0.5588)
			(end -1.143 0.5588)
			(stroke
				(width 0.1)
				(type default)
			)
			(layer "F.SilkS")
		)
		(fp_line
			(start 1.143 0.5588)
			(end 1.143 -0.5588)
			(stroke
				(width 0.1)
				(type default)
			)
			(layer "F.SilkS")
		)
		(fp_line
			(start -1.143 0.5588)
			(end 1.143 0.5588)
			(stroke
				(width 0.1)
				(type default)
			)
			(layer "F.SilkS")
		)
		(fp_poly
			(pts
				(xy -1.143 0.5588) (xy 1.143 0.5588) (xy 1.143 -0.5588) (xy -1.143 -0.5588)
			)
			(stroke
				(width 0)
				(type default)
			)
			(fill no)
			(layer "F.CrtYd")
		)
		(fp_line
			(start 0.508 -0.3048)
			(end -0.508 -0.3048)
			(stroke
				(width 0.1)
				(type default)
			)
			(layer "F.Fab")
		)
		(fp_line
			(start -0.508 -0.3048)
			(end -0.508 0.3048)
			(stroke
				(width 0.1)
				(type default)
			)
			(layer "F.Fab")
		)
		(fp_line
			(start 0.508 0.3048)
			(end 0.508 -0.3048)
			(stroke
				(width 0.1)
				(type default)
			)
			(layer "F.Fab")
		)
		(fp_line
			(start -0.508 0.3048)
			(end 0.508 0.3048)
			(stroke
				(width 0.1)
				(type default)
			)
			(layer "F.Fab")
		)
		(pad "1" smd rect
			(at -0.5334 0 90)
			(size 0.7112 0.6096)
			(layers "F.Cu" "F.Mask" "F.Paste")
			(net "FPGA_OUT_SMA1_LED_BLUE_N")
		)
		(pad "2" smd rect
			(at 0.5334 0 90)
			(size 0.7112 0.6096)
			(layers "F.Cu" "F.Mask" "F.Paste")
			(net "UNNAMED_14_LED4PV14_I265_1")
		)
		(zone
			(layer "F.Cu")
			(hatch none 0.5)
			(connect_pads
				(clearance 0)
			)
			(min_thickness 0.25)
			(keepout
				(tracks not_allowed)
				(vias allowed)
				(pads allowed)
				(copperpour not_allowed)
				(footprints allowed)
			)
			(placement
				(enabled no)
				(sheetname "")
			)
			(fill
				(thermal_gap 0.5)
				(thermal_bridge_width 0.5)
				(island_removal_mode 0)
			)
			(polygon
				(pts
					(xy 6.2992 -39.242492) (xy 6.2992 -39.394892) (xy 5.6896 -39.394892) (xy 5.6896 -39.242492)
				)
			)
		)
		(zone
			(layer "F.Cu")
			(hatch none 0.5)
			(connect_pads
				(clearance 0)
			)
			(min_thickness 0.25)
			(keepout
				(tracks allowed)
				(vias not_allowed)
				(pads allowed)
				(copperpour not_allowed)
				(footprints allowed)
			)
			(placement
				(enabled no)
				(sheetname "")
			)
			(fill
				(thermal_gap 0.5)
				(thermal_bridge_width 0.5)
				(island_removal_mode 0)
			)
			(polygon
				(pts
					(xy 6.2992 -39.242492) (xy 6.2992 -39.394892) (xy 5.6896 -39.394892) (xy 5.6896 -39.242492)
				)
			)
		)
	)
	(footprint ""
		(layer "F.Cu")
		(at 18.288 -87.63 90)
		(property "Reference" "U17"
			(at -1.524 -2.50063 90)
			(unlocked yes)
			(layer "F.SilkS")
			(effects
				(font
					(size 0.7874 0.5842)
					(thickness 0.1524)
				)
			)
		)
		(property "Value" ""
			(at 0 0 90)
			(layer "F.Fab")
			(effects
				(font
					(size 1.27 1.27)
				)
			)
		)
		(property "User Part Number" "PARTNUM*"
			(at 0.1016 3.45567 90)
			(unlocked yes)
			(layer "Cmts.User")
			(hide yes)
			(effects
				(font
					(size 0.7874 0.5842)
					(thickness 0.1524)
				)
			)
		)
		(property "Device Type" "CL1001485A-G122-00019-01"
			(at 0.1016 2.54127 90)
			(unlocked yes)
			(layer "F.Fab")
			(hide yes)
			(effects
				(font
					(size 0.7874 0.5842)
					(thickness 0.1524)
				)
			)
		)
		(duplicate_pad_numbers_are_jumpers no)
		(fp_line
			(start 1.0541 -1.704086)
			(end -1.0541 -1.704086)
			(stroke
				(width 0.1)
				(type default)
			)
			(layer "F.SilkS")
		)
		(fp_line
			(start -1.0541 -1.704086)
			(end -1.0541 -1.45796)
			(stroke
				(width 0.1)
				(type default)
			)
			(layer "F.SilkS")
		)
		(fp_line
			(start 2.286 -1.45796)
			(end 1.0541 -1.45796)
			(stroke
				(width 0.1)
				(type default)
			)
			(layer "F.SilkS")
		)
		(fp_line
			(start 1.0541 -1.45796)
			(end 1.0541 -1.704086)
			(stroke
				(width 0.1)
				(type default)
			)
			(layer "F.SilkS")
		)
		(fp_line
			(start -1.0541 -1.45796)
			(end -2.286 -1.45796)
			(stroke
				(width 0.1)
				(type default)
			)
			(layer "F.SilkS")
		)
		(fp_line
			(start -2.286 -1.45796)
			(end -2.286 1.45796)
			(stroke
				(width 0.1)
				(type default)
			)
			(layer "F.SilkS")
		)
		(fp_line
			(start 2.286 1.45796)
			(end 2.286 -1.45796)
			(stroke
				(width 0.1)
				(type default)
			)
			(layer "F.SilkS")
		)
		(fp_line
			(start 1.0541 1.45796)
			(end 2.286 1.45796)
			(stroke
				(width 0.1)
				(type default)
			)
			(layer "F.SilkS")
		)
		(fp_line
			(start -1.0541 1.45796)
			(end -1.0541 1.704086)
			(stroke
				(width 0.1)
				(type default)
			)
			(layer "F.SilkS")
		)
		(fp_line
			(start -2.286 1.45796)
			(end -1.0541 1.45796)
			(stroke
				(width 0.1)
				(type default)
			)
			(layer "F.SilkS")
		)
		(fp_line
			(start 1.0541 1.704086)
			(end 1.0541 1.45796)
			(stroke
				(width 0.1)
				(type default)
			)
			(layer "F.SilkS")
		)
		(fp_line
			(start -1.0541 1.704086)
			(end 1.0541 1.704086)
			(stroke
				(width 0.1)
				(type default)
			)
			(layer "F.SilkS")
		)
		(fp_poly
			(pts
				(arc
					(start -2.8956 -0.6858)
					(mid -2.8956 -1.4478)
					(end -2.8956 -0.6858)
				)
			)
			(stroke
				(width 0)
				(type default)
			)
			(fill yes)
			(layer "F.SilkS")
		)
		(fp_rect
			(start 2.54 1.9558)
			(end -2.54 -1.9558)
			(stroke
				(width 0)
				(type default)
			)
			(fill no)
			(layer "F.CrtYd")
		)
		(fp_line
			(start 0.8001 -1.450086)
			(end 0.8001 -1.199896)
			(stroke
				(width 0.1)
				(type default)
			)
			(layer "F.Fab")
		)
		(fp_line
			(start -0.8001 -1.450086)
			(end 0.8001 -1.450086)
			(stroke
				(width 0.1)
				(type default)
			)
			(layer "F.Fab")
		)
		(fp_line
			(start 0.599948 -1.249934)
			(end 0.8001 -1.450086)
			(stroke
				(width 0.1)
				(type default)
			)
			(layer "F.Fab")
		)
		(fp_line
			(start 0.599948 -1.249934)
			(end 0.599948 1.249934)
			(stroke
				(width 0.1)
				(type default)
			)
			(layer "F.Fab")
		)
		(fp_line
			(start -0.599948 -1.249934)
			(end -0.8001 -1.450086)
			(stroke
				(width 0.1)
				(type default)
			)
			(layer "F.Fab")
		)
		(fp_line
			(start -0.599948 -1.249934)
			(end 0.599948 -1.249934)
			(stroke
				(width 0.1)
				(type default)
			)
			(layer "F.Fab")
		)
		(fp_line
			(start 1.500124 -1.199896)
			(end 1.500124 -0.700024)
			(stroke
				(width 0.1)
				(type default)
			)
			(layer "F.Fab")
		)
		(fp_line
			(start 0.700024 -1.199896)
			(end 1.500124 -1.199896)
			(stroke
				(width 0.1)
				(type default)
			)
			(layer "F.Fab")
		)
		(fp_line
			(start -0.700024 -1.199896)
			(end -0.700024 -0.700024)
			(stroke
				(width 0.1)
				(type default)
			)
			(layer "F.Fab")
		)
		(fp_line
			(start -0.8001 -1.199896)
			(end -0.8001 -1.450086)
			(stroke
				(width 0.1)
				(type default)
			)
			(layer "F.Fab")
		)
		(fp_line
			(start -1.500124 -1.199896)
			(end -0.700024 -1.199896)
			(stroke
				(width 0.1)
				(type default)
			)
			(layer "F.Fab")
		)
		(fp_line
			(start 1.500124 -0.700024)
			(end 0.700024 -0.700024)
			(stroke
				(width 0.1)
				(type default)
			)
			(layer "F.Fab")
		)
		(fp_line
			(start 0.8001 -0.700024)
			(end 0.8001 -0.249936)
			(stroke
				(width 0.1)
				(type default)
			)
			(layer "F.Fab")
		)
		(fp_line
			(start 0.700024 -0.700024)
			(end 0.700024 -1.199896)
			(stroke
				(width 0.1)
				(type default)
			)
			(layer "F.Fab")
		)
		(fp_line
			(start -0.700024 -0.700024)
			(end -1.500124 -0.700024)
			(stroke
				(width 0.1)
				(type default)
			)
			(layer "F.Fab")
		)
		(fp_line
			(start -0.8001 -0.700024)
			(end -0.8001 -0.249936)
			(stroke
				(width 0.1)
				(type default)
			)
			(layer "F.Fab")
		)
		(fp_line
			(start -1.500124 -0.700024)
			(end -1.500124 -1.199896)
			(stroke
				(width 0.1)
				(type default)
			)
			(layer "F.Fab")
		)
		(fp_line
			(start 1.500124 -0.249936)
			(end 1.500124 0.249936)
			(stroke
				(width 0.1)
				(type default)
			)
			(layer "F.Fab")
		)
		(fp_line
			(start 0.8001 -0.249936)
			(end 0.700024 -0.249936)
			(stroke
				(width 0.1)
				(type default)
			)
			(layer "F.Fab")
		)
		(fp_line
			(start 0.700024 -0.249936)
			(end 1.500124 -0.249936)
			(stroke
				(width 0.1)
				(type default)
			)
			(layer "F.Fab")
		)
		(fp_line
			(start 0.700024 -0.249936)
			(end 0.700024 0.249936)
			(stroke
				(width 0.1)
				(type default)
			)
			(layer "F.Fab")
		)
		(fp_line
			(start -0.700024 -0.249936)
			(end -0.700024 0.249936)
			(stroke
				(width 0.1)
				(type default)
			)
			(layer "F.Fab")
		)
		(fp_line
			(start -1.500124 -0.249936)
			(end -0.700024 -0.249936)
			(stroke
				(width 0.1)
				(type default)
			)
			(layer "F.Fab")
		)
		(fp_line
			(start 1.500124 0.249936)
			(end 0.700024 0.249936)
			(stroke
				(width 0.1)
				(type default)
			)
			(layer "F.Fab")
		)
		(fp_line
			(start 0.8001 0.249936)
			(end 0.8001 0.700024)
			(stroke
				(width 0.1)
				(type default)
			)
			(layer "F.Fab")
		)
		(fp_line
			(start 0.700024 0.249936)
			(end 0.700024 -0.249936)
			(stroke
				(width 0.1)
				(type default)
			)
			(layer "F.Fab")
		)
		(fp_line
			(start 0.700024 0.249936)
			(end 0.8001 0.249936)
			(stroke
				(width 0.1)
				(type default)
			)
			(layer "F.Fab")
		)
		(fp_line
			(start -0.700024 0.249936)
			(end -1.500124 0.249936)
			(stroke
				(width 0.1)
				(type default)
			)
			(layer "F.Fab")
		)
		(fp_line
			(start -0.8001 0.249936)
			(end -0.8001 0.700024)
			(stroke
				(width 0.1)
				(type default)
			)
			(layer "F.Fab")
		)
		(fp_line
			(start -1.500124 0.249936)
			(end -1.500124 -0.249936)
			(stroke
				(width 0.1)
				(type default)
			)
			(layer "F.Fab")
		)
		(fp_line
			(start 1.500124 0.700024)
			(end 1.500124 1.199896)
			(stroke
				(width 0.1)
				(type default)
			)
			(layer "F.Fab")
		)
		(fp_line
			(start 0.700024 0.700024)
			(end 1.500124 0.700024)
			(stroke
				(width 0.1)
				(type default)
			)
			(layer "F.Fab")
		)
		(fp_line
			(start -0.700024 0.700024)
			(end -0.700024 1.199896)
			(stroke
				(width 0.1)
				(type default)
			)
			(layer "F.Fab")
		)
		(fp_line
			(start -1.500124 0.700024)
			(end -0.700024 0.700024)
			(stroke
				(width 0.1)
				(type default)
			)
			(layer "F.Fab")
		)
		(fp_line
			(start 1.500124 1.199896)
			(end 0.700024 1.199896)
			(stroke
				(width 0.1)
				(type default)
			)
			(layer "F.Fab")
		)
		(fp_line
			(start 0.700024 1.199896)
			(end 0.700024 0.700024)
			(stroke
				(width 0.1)
				(type default)
			)
			(layer "F.Fab")
		)
		(fp_line
			(start -0.700024 1.199896)
			(end -1.500124 1.199896)
			(stroke
				(width 0.1)
				(type default)
			)
			(layer "F.Fab")
		)
		(fp_line
			(start -0.8001 1.199896)
			(end -0.8001 1.450086)
			(stroke
				(width 0.1)
				(type default)
			)
			(layer "F.Fab")
		)
		(fp_line
			(start -1.500124 1.199896)
			(end -1.500124 0.700024)
			(stroke
				(width 0.1)
				(type default)
			)
			(layer "F.Fab")
		)
		(fp_line
			(start 0.599948 1.249934)
			(end -0.599948 1.249934)
			(stroke
				(width 0.1)
				(type default)
			)
			(layer "F.Fab")
		)
		(fp_line
			(start -0.599948 1.249934)
			(end -0.599948 -1.249934)
			(stroke
				(width 0.1)
				(type default)
			)
			(layer "F.Fab")
		)
		(fp_line
			(start 0.8001 1.450086)
			(end 0.8001 1.199896)
			(stroke
				(width 0.1)
				(type default)
			)
			(layer "F.Fab")
		)
		(fp_line
			(start 0.8001 1.450086)
			(end 0.599948 1.249934)
			(stroke
				(width 0.1)
				(type default)
			)
			(layer "F.Fab")
		)
		(fp_line
			(start -0.8001 1.450086)
			(end -0.599948 1.249934)
			(stroke
				(width 0.1)
				(type default)
			)
			(layer "F.Fab")
		)
		(fp_line
			(start -0.8001 1.450086)
			(end 0.8001 1.450086)
			(stroke
				(width 0.1)
				(type default)
			)
			(layer "F.Fab")
		)
		(fp_poly
			(pts
				(arc
					(start -0.350012 -0.799846)
					(mid -0.350012 -1.100074)
					(end -0.350012 -0.799846)
				)
			)
			(stroke
				(width 0)
				(type default)
			)
			(fill yes)
			(layer "F.Fab")
		)
		(fp_text user "6"
			(at 1.570228 -1.765046 0)
			(unlocked yes)
			(layer "F.SilkS")
			(effects
				(font
					(size 0.635 0.4064)
					(thickness 0.1524)
				)
			)
		)
		(fp_text user "4"
			(at 2.76225 2.032 0)
			(unlocked yes)
			(layer "F.SilkS")
			(effects
				(font
					(size 0.635 0.4064)
					(thickness 0.1524)
				)
			)
		)
		(fp_text user "3"
			(at -2.06375 2.159 0)
			(unlocked yes)
			(layer "F.SilkS")
			(effects
				(font
					(size 0.635 0.4064)
					(thickness 0.1524)
				)
			)
		)
		(fp_text user "6"
			(at 2.572258 -1.0668 0)
			(unlocked yes)
			(layer "F.Fab")
			(effects
				(font
					(size 0.7874 0.5842)
					(thickness 0.1524)
				)
			)
		)
		(fp_text user "4"
			(at 2.623058 0.8636 0)
			(unlocked yes)
			(layer "F.Fab")
			(effects
				(font
					(size 0.7874 0.5842)
					(thickness 0.1524)
				)
			)
		)
		(fp_text user "3"
			(at -2.429256 1.155954 0)
			(unlocked yes)
			(layer "F.Fab")
			(effects
				(font
					(size 0.7874 0.5842)
					(thickness 0.1524)
				)
			)
		)
		(pad "1" smd rect
			(at -1.4351 -0.94996 180)
			(size 0.508 1.1938)
			(layers "F.Cu" "F.Mask" "F.Paste")
			(net "Net_756")
		)
		(pad "2" smd rect
			(at -1.4351 0 180)
			(size 0.508 1.1938)
			(layers "F.Cu" "F.Mask" "F.Paste")
			(net "SG")
		)
		(pad "3" smd rect
			(at -1.4351 0.94996 180)
			(size 0.508 1.1938)
			(layers "F.Cu" "F.Mask" "F.Paste")
			(net "Net_755")
		)
		(pad "4" smd rect
			(at 1.4351 0.94996 180)
			(size 0.508 1.1938)
			(layers "F.Cu" "F.Mask" "F.Paste")
			(net "FT_USB_DM")
		)
		(pad "5" smd rect
			(at 1.4351 0 180)
			(size 0.508 1.1938)
			(layers "F.Cu" "F.Mask" "F.Paste")
			(net "XP5R0V_FT4232")
		)
		(pad "6" smd rect
			(at 1.4351 -0.94996 180)
			(size 0.508 1.1938)
			(layers "F.Cu" "F.Mask" "F.Paste")
			(net "FT_USB_DP")
		)
	)
	(footprint ""
		(layer "F.Cu")
		(at 13.462 -37.211 -90)
		(property "Reference" "R156"
			(at 1.27 3.51663 90)
			(unlocked yes)
			(layer "F.SilkS")
			(effects
				(font
					(size 0.7874 0.5842)
					(thickness 0.1524)
				)
			)
		)
		(property "Value" "VAL*"
			(at 0.02032 2.13233 270)
			(unlocked yes)
			(layer "F.Fab")
			(hide yes)
			(effects
				(font
					(size 0.7874 0.5842)
					(thickness 0.1524)
				)
			)
		)
		(property "Tolerance" "TOL*"
			(at 0.044704 3.05435 270)
			(unlocked yes)
			(layer "Cmts.User")
			(hide yes)
			(effects
				(font
					(size 0.7874 0.5842)
					(thickness 0.1524)
				)
			)
		)
		(property "User Part Number" "PARTNUM*"
			(at 0.02032 4.024884 270)
			(unlocked yes)
			(layer "Cmts.User")
			(hide yes)
			(effects
				(font
					(size 0.7874 0.5842)
					(thickness 0.1524)
				)
			)
		)
		(property "Device Type" "RESISTOR-G155-11000-01,100OHM,A"
			(at 0.008382 1.210564 270)
			(unlocked yes)
			(layer "F.Fab")
			(hide yes)
			(effects
				(font
					(size 0.7874 0.5842)
					(thickness 0.1524)
				)
			)
		)
		(duplicate_pad_numbers_are_jumpers no)
		(fp_line
			(start -1.143 0.5588)
			(end 1.143 0.5588)
			(stroke
				(width 0.1)
				(type default)
			)
			(layer "F.SilkS")
		)
		(fp_line
			(start 1.143 0.5588)
			(end 1.143 -0.5588)
			(stroke
				(width 0.1)
				(type default)
			)
			(layer "F.SilkS")
		)
		(fp_line
			(start -1.143 -0.5588)
			(end -1.143 0.5588)
			(stroke
				(width 0.1)
				(type default)
			)
			(layer "F.SilkS")
		)
		(fp_line
			(start 1.143 -0.5588)
			(end -1.143 -0.5588)
			(stroke
				(width 0.1)
				(type default)
			)
			(layer "F.SilkS")
		)
		(fp_poly
			(pts
				(xy -1.143 0.5588) (xy 1.143 0.5588) (xy 1.143 -0.5588) (xy -1.143 -0.5588)
			)
			(stroke
				(width 0)
				(type default)
			)
			(fill no)
			(layer "F.CrtYd")
		)
		(fp_line
			(start -0.508 0.3048)
			(end 0.508 0.3048)
			(stroke
				(width 0.1)
				(type default)
			)
			(layer "F.Fab")
		)
		(fp_line
			(start 0.508 0.3048)
			(end 0.508 -0.3048)
			(stroke
				(width 0.1)
				(type default)
			)
			(layer "F.Fab")
		)
		(fp_line
			(start -0.508 -0.3048)
			(end -0.508 0.3048)
			(stroke
				(width 0.1)
				(type default)
			)
			(layer "F.Fab")
		)
		(fp_line
			(start 0.508 -0.3048)
			(end -0.508 -0.3048)
			(stroke
				(width 0.1)
				(type default)
			)
			(layer "F.Fab")
		)
		(pad "1" smd rect
			(at -0.5334 0 270)
			(size 0.7112 0.6096)
			(layers "F.Cu" "F.Mask" "F.Paste")
			(net "ANT3_OUT")
		)
		(pad "2" smd rect
			(at 0.5334 0 270)
			(size 0.7112 0.6096)
			(layers "F.Cu" "F.Mask" "F.Paste")
			(net "UNNAMED_12_74HCT2G125DPTSSOP8_I")
		)
		(zone
			(layer "F.Cu")
			(hatch none 0.5)
			(connect_pads
				(clearance 0)
			)
			(min_thickness 0.25)
			(keepout
				(tracks not_allowed)
				(vias allowed)
				(pads allowed)
				(copperpour not_allowed)
				(footprints allowed)
			)
			(placement
				(enabled no)
				(sheetname "")
			)
			(fill
				(thermal_gap 0.5)
				(thermal_bridge_width 0.5)
				(island_removal_mode 0)
			)
			(polygon
				(pts
					(xy 13.1572 -37.2872) (xy 13.1572 -37.1348) (xy 13.7668 -37.1348) (xy 13.7668 -37.2872)
				)
			)
		)
		(zone
			(layer "F.Cu")
			(hatch none 0.5)
			(connect_pads
				(clearance 0)
			)
			(min_thickness 0.25)
			(keepout
				(tracks allowed)
				(vias not_allowed)
				(pads allowed)
				(copperpour not_allowed)
				(footprints allowed)
			)
			(placement
				(enabled no)
				(sheetname "")
			)
			(fill
				(thermal_gap 0.5)
				(thermal_bridge_width 0.5)
				(island_removal_mode 0)
			)
			(polygon
				(pts
					(xy 13.1572 -37.2872) (xy 13.1572 -37.1348) (xy 13.7668 -37.1348) (xy 13.7668 -37.2872)
				)
			)
		)
	)
	(footprint ""
		(layer "F.Cu")
		(at 55.88 -131.064)
		(property "Reference" "SP70"
			(at 0 0 0)
			(layer "F.SilkS")
			(hide yes)
			(effects
				(font
					(size 1.27 1.27)
				)
			)
		)
		(property "Value" ""
			(at 0 0 0)
			(layer "F.Fab")
			(effects
				(font
					(size 1.27 1.27)
				)
			)
		)
		(duplicate_pad_numbers_are_jumpers no)
	)
	(footprint ""
		(layer "F.Cu")
		(at 54.102 -130.429)
		(property "Reference" "SP51"
			(at 0 0 0)
			(layer "F.SilkS")
			(hide yes)
			(effects
				(font
					(size 1.27 1.27)
				)
			)
		)
		(property "Value" ""
			(at 0 0 0)
			(layer "F.Fab")
			(effects
				(font
					(size 1.27 1.27)
				)
			)
		)
		(duplicate_pad_numbers_are_jumpers no)
	)
	(footprint ""
		(layer "F.Cu")
		(at 4.572 -81.534 90)
		(property "Reference" "R397"
			(at -2.667 -0.97663 90)
			(unlocked yes)
			(layer "F.SilkS")
			(effects
				(font
					(size 0.7874 0.5842)
					(thickness 0.1524)
				)
			)
		)
		(property "Value" "VAL*"
			(at 0.02032 2.13233 90)
			(unlocked yes)
			(layer "F.Fab")
			(hide yes)
			(effects
				(font
					(size 0.7874 0.5842)
					(thickness 0.1524)
				)
			)
		)
		(property "Tolerance" "TOL*"
			(at 0.044704 3.05435 90)
			(unlocked yes)
			(layer "Cmts.User")
			(hide yes)
			(effects
				(font
					(size 0.7874 0.5842)
					(thickness 0.1524)
				)
			)
		)
		(property "User Part Number" "PARTNUM*"
			(at 0.02032 4.024884 90)
			(unlocked yes)
			(layer "Cmts.User")
			(hide yes)
			(effects
				(font
					(size 0.7874 0.5842)
					(thickness 0.1524)
				)
			)
		)
		(property "Device Type" "RESISTOR-G155-133R0-01,33OHM,1%"
			(at 0.008382 1.210564 90)
			(unlocked yes)
			(layer "F.Fab")
			(hide yes)
			(effects
				(font
					(size 0.7874 0.5842)
					(thickness 0.1524)
				)
			)
		)
		(duplicate_pad_numbers_are_jumpers no)
		(fp_line
			(start 1.143 -0.5588)
			(end -1.143 -0.5588)
			(stroke
				(width 0.1)
				(type default)
			)
			(layer "F.SilkS")
		)
		(fp_line
			(start -1.143 -0.5588)
			(end -1.143 0.5588)
			(stroke
				(width 0.1)
				(type default)
			)
			(layer "F.SilkS")
		)
		(fp_line
			(start 1.143 0.5588)
			(end 1.143 -0.5588)
			(stroke
				(width 0.1)
				(type default)
			)
			(layer "F.SilkS")
		)
		(fp_line
			(start -1.143 0.5588)
			(end 1.143 0.5588)
			(stroke
				(width 0.1)
				(type default)
			)
			(layer "F.SilkS")
		)
		(fp_rect
			(start -1.143 -0.5588)
			(end 1.143 0.5588)
			(stroke
				(width 0)
				(type default)
			)
			(fill no)
			(layer "F.CrtYd")
		)
		(fp_line
			(start 0.508 -0.3048)
			(end -0.508 -0.3048)
			(stroke
				(width 0.1)
				(type default)
			)
			(layer "F.Fab")
		)
		(fp_line
			(start -0.508 -0.3048)
			(end -0.508 0.3048)
			(stroke
				(width 0.1)
				(type default)
			)
			(layer "F.Fab")
		)
		(fp_line
			(start 0.508 0.3048)
			(end 0.508 -0.3048)
			(stroke
				(width 0.1)
				(type default)
			)
			(layer "F.Fab")
		)
		(fp_line
			(start -0.508 0.3048)
			(end 0.508 0.3048)
			(stroke
				(width 0.1)
				(type default)
			)
			(layer "F.Fab")
		)
		(pad "1" smd rect
			(at -0.5334 0 90)
			(size 0.7112 0.6096)
			(layers "F.Cu" "F.Mask" "F.Paste")
			(net "GPS_SMA_LED_BLUE_N")
		)
		(pad "2" smd rect
			(at 0.5334 0 90)
			(size 0.7112 0.6096)
			(layers "F.Cu" "F.Mask" "F.Paste")
			(net "UNNAMED_14_LED4PV14_I269_1")
		)
		(zone
			(layer "F.Cu")
			(hatch none 0.5)
			(connect_pads
				(clearance 0)
			)
			(min_thickness 0.25)
			(keepout
				(tracks not_allowed)
				(vias allowed)
				(pads allowed)
				(copperpour not_allowed)
				(footprints allowed)
			)
			(placement
				(enabled no)
				(sheetname "")
			)
			(fill
				(thermal_gap 0.5)
				(thermal_bridge_width 0.5)
				(island_removal_mode 0)
			)
			(polygon
				(pts
					(xy 4.2672 -81.4578) (xy 4.8768 -81.4578) (xy 4.8768 -81.6102) (xy 4.2672 -81.6102)
				)
			)
		)
		(zone
			(layer "F.Cu")
			(hatch none 0.5)
			(connect_pads
				(clearance 0)
			)
			(min_thickness 0.25)
			(keepout
				(tracks allowed)
				(vias not_allowed)
				(pads allowed)
				(copperpour not_allowed)
				(footprints allowed)
			)
			(placement
				(enabled no)
				(sheetname "")
			)
			(fill
				(thermal_gap 0.5)
				(thermal_bridge_width 0.5)
				(island_removal_mode 0)
			)
			(polygon
				(pts
					(xy 4.2672 -81.4578) (xy 4.8768 -81.4578) (xy 4.8768 -81.6102) (xy 4.2672 -81.6102)
				)
			)
		)
	)
	(footprint ""
		(layer "F.Cu")
		(at 124.587 -43.688)
		(property "Reference" "R212"
			(at 3.048 -1.35763 0)
			(unlocked yes)
			(layer "F.SilkS")
			(effects
				(font
					(size 0.7874 0.5842)
					(thickness 0.1524)
				)
			)
		)
		(property "Value" "VAL*"
			(at 0.02032 2.13233 0)
			(unlocked yes)
			(layer "F.Fab")
			(hide yes)
			(effects
				(font
					(size 0.7874 0.5842)
					(thickness 0.1524)
				)
			)
		)
		(property "Device Type" "RESISTOR-G155-11000-01,100OHM,A"
			(at 0.008382 1.210564 0)
			(unlocked yes)
			(layer "F.Fab")
			(hide yes)
			(effects
				(font
					(size 0.7874 0.5842)
					(thickness 0.1524)
				)
			)
		)
		(property "User Part Number" "PARTNUM*"
			(at 0.02032 4.024884 0)
			(unlocked yes)
			(layer "Cmts.User")
			(hide yes)
			(effects
				(font
					(size 0.7874 0.5842)
					(thickness 0.1524)
				)
			)
		)
		(property "Tolerance" "TOL*"
			(at 0.044704 3.05435 0)
			(unlocked yes)
			(layer "Cmts.User")
			(hide yes)
			(effects
				(font
					(size 0.7874 0.5842)
					(thickness 0.1524)
				)
			)
		)
		(duplicate_pad_numbers_are_jumpers no)
		(fp_line
			(start -1.143 -0.5588)
			(end -1.143 0.5588)
			(stroke
				(width 0.1)
				(type default)
			)
			(layer "F.SilkS")
		)
		(fp_line
			(start -1.143 0.5588)
			(end 1.143 0.5588)
			(stroke
				(width 0.1)
				(type default)
			)
			(layer "F.SilkS")
		)
		(fp_line
			(start 1.143 -0.5588)
			(end -1.143 -0.5588)
			(stroke
				(width 0.1)
				(type default)
			)
			(layer "F.SilkS")
		)
		(fp_line
			(start 1.143 0.5588)
			(end 1.143 -0.5588)
			(stroke
				(width 0.1)
				(type default)
			)
			(layer "F.SilkS")
		)
		(fp_rect
			(start -1.143 0.5588)
			(end 1.143 -0.5588)
			(stroke
				(width 0)
				(type default)
			)
			(fill no)
			(layer "F.CrtYd")
		)
		(fp_line
			(start -0.508 -0.3048)
			(end -0.508 0.3048)
			(stroke
				(width 0.1)
				(type default)
			)
			(layer "F.Fab")
		)
		(fp_line
			(start -0.508 0.3048)
			(end 0.508 0.3048)
			(stroke
				(width 0.1)
				(type default)
			)
			(layer "F.Fab")
		)
		(fp_line
			(start 0.508 -0.3048)
			(end -0.508 -0.3048)
			(stroke
				(width 0.1)
				(type default)
			)
			(layer "F.Fab")
		)
		(fp_line
			(start 0.508 0.3048)
			(end 0.508 -0.3048)
			(stroke
				(width 0.1)
				(type default)
			)
			(layer "F.Fab")
		)
		(pad "1" smd rect
			(at -0.5334 0)
			(size 0.7112 0.6096)
			(layers "F.Cu" "F.Mask" "F.Paste")
			(net "FPGA_M0")
		)
		(pad "2" smd rect
			(at 0.5334 0)
			(size 0.7112 0.6096)
			(layers "F.Cu" "F.Mask" "F.Paste")
			(net "SG")
		)
		(zone
			(layer "F.Cu")
			(hatch none 0.5)
			(connect_pads
				(clearance 0)
			)
			(min_thickness 0.25)
			(keepout
				(tracks allowed)
				(vias not_allowed)
				(pads allowed)
				(copperpour not_allowed)
				(footprints allowed)
			)
			(placement
				(enabled no)
				(sheetname "")
			)
			(fill
				(thermal_gap 0.5)
				(thermal_bridge_width 0.5)
				(island_removal_mode 0)
			)
			(polygon
				(pts
					(xy 124.5108 -43.3832) (xy 124.6632 -43.3832) (xy 124.6632 -43.9928) (xy 124.5108 -43.9928)
				)
			)
		)
	)
	(footprint ""
		(layer "F.Cu")
		(at 49.8094 -100.9904)
		(property "Reference" "L1"
			(at 0.1016 4.63677 0)
			(unlocked yes)
			(layer "F.SilkS")
			(effects
				(font
					(size 0.7874 0.5842)
					(thickness 0.1524)
				)
			)
		)
		(property "Value" "VAL*"
			(at -0.035306 8.510778 0)
			(unlocked yes)
			(layer "F.Fab")
			(hide yes)
			(effects
				(font
					(size 0.7874 0.5842)
					(thickness 0.1524)
				)
			)
		)
		(property "Tolerance" "TOL*"
			(at -0.061722 7.222744 0)
			(unlocked yes)
			(layer "Cmts.User")
			(hide yes)
			(effects
				(font
					(size 0.7874 0.5842)
					(thickness 0.1524)
				)
			)
		)
		(property "User Part Number" "PARTNUM*"
			(at 0 6.106668 0)
			(unlocked yes)
			(layer "Cmts.User")
			(hide yes)
			(effects
				(font
					(size 0.7874 0.5842)
					(thickness 0.1524)
				)
			)
		)
		(property "Device Type" "INDUCTOR_2-G190-10424-01,4.7UHA"
			(at 0 4.912868 0)
			(unlocked yes)
			(layer "F.Fab")
			(hide yes)
			(effects
				(font
					(size 0.7874 0.5842)
					(thickness 0.1524)
				)
			)
		)
		(duplicate_pad_numbers_are_jumpers no)
		(fp_line
			(start -4.448302 -3.803904)
			(end 4.448302 -3.803904)
			(stroke
				(width 0.1)
				(type default)
			)
			(layer "F.SilkS")
		)
		(fp_line
			(start -4.448302 3.803904)
			(end -4.448302 -3.803904)
			(stroke
				(width 0.1)
				(type default)
			)
			(layer "F.SilkS")
		)
		(fp_line
			(start 4.448302 -3.803904)
			(end 4.448302 3.803904)
			(stroke
				(width 0.1)
				(type default)
			)
			(layer "F.SilkS")
		)
		(fp_line
			(start 4.448302 3.803904)
			(end -4.448302 3.803904)
			(stroke
				(width 0.1)
				(type default)
			)
			(layer "F.SilkS")
		)
		(fp_rect
			(start 4.702302 -4.057904)
			(end -4.702302 4.057904)
			(stroke
				(width 0)
				(type default)
			)
			(fill no)
			(layer "F.CrtYd")
		)
		(fp_line
			(start -3.800094 -3.549904)
			(end 3.800094 -3.549904)
			(stroke
				(width 0.1)
				(type default)
			)
			(layer "F.Fab")
		)
		(fp_line
			(start -3.800094 3.549904)
			(end -3.800094 -3.549904)
			(stroke
				(width 0.1)
				(type default)
			)
			(layer "F.Fab")
		)
		(fp_line
			(start 3.800094 -3.549904)
			(end 3.800094 3.549904)
			(stroke
				(width 0.1)
				(type default)
			)
			(layer "F.Fab")
		)
		(fp_line
			(start 3.800094 3.549904)
			(end -3.800094 3.549904)
			(stroke
				(width 0.1)
				(type default)
			)
			(layer "F.Fab")
		)
		(fp_text user "1"
			(at -3.7084 4.50977 0)
			(unlocked yes)
			(layer "F.SilkS")
			(effects
				(font
					(size 0.7874 0.5842)
					(thickness 0.1524)
				)
			)
		)
		(fp_text user "2"
			(at 4.0386 4.50977 0)
			(unlocked yes)
			(layer "F.SilkS")
			(effects
				(font
					(size 0.7874 0.5842)
					(thickness 0.1524)
				)
			)
		)
		(fp_text user "1"
			(at -4.3434 0.30607 0)
			(unlocked yes)
			(layer "F.Fab")
			(effects
				(font
					(size 0.7874 0.5842)
					(thickness 0.1524)
				)
			)
		)
		(fp_text user "2"
			(at 4.5466 0.05207 0)
			(unlocked yes)
			(layer "F.Fab")
			(effects
				(font
					(size 0.7874 0.5842)
					(thickness 0.1524)
				)
			)
		)
		(pad "1" smd rect
			(at -2.975102 0)
			(size 2.4384 3.7084)
			(layers "F.Cu" "F.Mask" "F.Paste")
			(net "XP5R0V_SW")
		)
		(pad "2" smd rect
			(at 2.975102 0)
			(size 2.4384 3.7084)
			(layers "F.Cu" "F.Mask" "F.Paste")
			(net "XP5R0V")
		)
		(zone
			(layer "F.Cu")
			(hatch none 0.5)
			(connect_pads
				(clearance 0)
			)
			(min_thickness 0.25)
			(keepout
				(tracks allowed)
				(vias not_allowed)
				(pads allowed)
				(copperpour not_allowed)
				(footprints allowed)
			)
			(placement
				(enabled no)
				(sheetname "")
			)
			(fill
				(thermal_gap 0.5)
				(thermal_bridge_width 0.5)
				(island_removal_mode 0)
			)
			(polygon
				(pts
					(xy 46.009306 -97.440496) (xy 46.009306 -99.1362) (xy 48.053498 -99.1362) (xy 48.053498 -102.8446)
					(xy 46.009306 -102.8446) (xy 46.009306 -104.540304) (xy 53.609494 -104.540304) (xy 53.609494 -102.8446)
					(xy 51.565302 -102.8446) (xy 51.565302 -99.1362) (xy 53.609494 -99.1362) (xy 53.609494 -97.440496)
				)
			)
		)
	)
	(footprint ""
		(layer "F.Cu")
		(at 28.575 -75.184 -90)
		(property "Reference" "R352"
			(at -0.381 -2.45237 90)
			(unlocked yes)
			(layer "F.SilkS")
			(effects
				(font
					(size 0.7874 0.5842)
					(thickness 0.1524)
				)
			)
		)
		(property "Value" "VAL*"
			(at 0.02032 2.13233 270)
			(unlocked yes)
			(layer "F.Fab")
			(hide yes)
			(effects
				(font
					(size 0.7874 0.5842)
					(thickness 0.1524)
				)
			)
		)
		(property "Tolerance" "TOL*"
			(at 0.044704 3.05435 270)
			(unlocked yes)
			(layer "Cmts.User")
			(hide yes)
			(effects
				(font
					(size 0.7874 0.5842)
					(thickness 0.1524)
				)
			)
		)
		(property "User Part Number" "PARTNUM*"
			(at 0.02032 4.024884 270)
			(unlocked yes)
			(layer "Cmts.User")
			(hide yes)
			(effects
				(font
					(size 0.7874 0.5842)
					(thickness 0.1524)
				)
			)
		)
		(property "Device Type" "RESISTOR-G155-11000-01,100OHM,A"
			(at 0.008382 1.210564 270)
			(unlocked yes)
			(layer "F.Fab")
			(hide yes)
			(effects
				(font
					(size 0.7874 0.5842)
					(thickness 0.1524)
				)
			)
		)
		(duplicate_pad_numbers_are_jumpers no)
		(fp_line
			(start -1.143 0.5588)
			(end 1.143 0.5588)
			(stroke
				(width 0.1)
				(type default)
			)
			(layer "F.SilkS")
		)
		(fp_line
			(start 1.143 0.5588)
			(end 1.143 -0.5588)
			(stroke
				(width 0.1)
				(type default)
			)
			(layer "F.SilkS")
		)
		(fp_line
			(start -1.143 -0.5588)
			(end -1.143 0.5588)
			(stroke
				(width 0.1)
				(type default)
			)
			(layer "F.SilkS")
		)
		(fp_line
			(start 1.143 -0.5588)
			(end -1.143 -0.5588)
			(stroke
				(width 0.1)
				(type default)
			)
			(layer "F.SilkS")
		)
		(fp_poly
			(pts
				(xy -1.143 0.5588) (xy 1.143 0.5588) (xy 1.143 -0.5588) (xy -1.143 -0.5588)
			)
			(stroke
				(width 0)
				(type default)
			)
			(fill no)
			(layer "F.CrtYd")
		)
		(fp_line
			(start -0.508 0.3048)
			(end 0.508 0.3048)
			(stroke
				(width 0.1)
				(type default)
			)
			(layer "F.Fab")
		)
		(fp_line
			(start 0.508 0.3048)
			(end 0.508 -0.3048)
			(stroke
				(width 0.1)
				(type default)
			)
			(layer "F.Fab")
		)
		(fp_line
			(start -0.508 -0.3048)
			(end -0.508 0.3048)
			(stroke
				(width 0.1)
				(type default)
			)
			(layer "F.Fab")
		)
		(fp_line
			(start 0.508 -0.3048)
			(end -0.508 -0.3048)
			(stroke
				(width 0.1)
				(type default)
			)
			(layer "F.Fab")
		)
		(pad "1" smd rect
			(at -0.5334 0 270)
			(size 0.7112 0.6096)
			(layers "F.Cu" "F.Mask" "F.Paste")
			(net "R_FT4232_CHC_RX")
		)
		(pad "2" smd rect
			(at 0.5334 0 270)
			(size 0.7112 0.6096)
			(layers "F.Cu" "F.Mask" "F.Paste")
			(net "UART_FT4232_RX_FPGA_TX")
		)
		(zone
			(layer "F.Cu")
			(hatch none 0.5)
			(connect_pads
				(clearance 0)
			)
			(min_thickness 0.25)
			(keepout
				(tracks not_allowed)
				(vias allowed)
				(pads allowed)
				(copperpour not_allowed)
				(footprints allowed)
			)
			(placement
				(enabled no)
				(sheetname "")
			)
			(fill
				(thermal_gap 0.5)
				(thermal_bridge_width 0.5)
				(island_removal_mode 0)
			)
			(polygon
				(pts
					(xy 28.2702 -75.2602) (xy 28.2702 -75.1078) (xy 28.8798 -75.1078) (xy 28.8798 -75.2602)
				)
			)
		)
		(zone
			(layer "F.Cu")
			(hatch none 0.5)
			(connect_pads
				(clearance 0)
			)
			(min_thickness 0.25)
			(keepout
				(tracks allowed)
				(vias not_allowed)
				(pads allowed)
				(copperpour not_allowed)
				(footprints allowed)
			)
			(placement
				(enabled no)
				(sheetname "")
			)
			(fill
				(thermal_gap 0.5)
				(thermal_bridge_width 0.5)
				(island_removal_mode 0)
			)
			(polygon
				(pts
					(xy 28.2702 -75.2602) (xy 28.2702 -75.1078) (xy 28.8798 -75.1078) (xy 28.8798 -75.2602)
				)
			)
		)
	)
	(footprint ""
		(layer "F.Cu")
		(at 133.223 -40.513)
		(property "Reference" "C175"
			(at 4.445 6.13537 0)
			(unlocked yes)
			(layer "F.SilkS")
			(effects
				(font
					(size 0.7874 0.5842)
					(thickness 0.1524)
				)
			)
		)
		(property "Value" "VAL*"
			(at 0.1016 3.769106 0)
			(unlocked yes)
			(layer "F.Fab")
			(hide yes)
			(effects
				(font
					(size 0.7874 0.5842)
					(thickness 0.1524)
				)
			)
		)
		(property "Tolerance" "TOL*"
			(at 0.127 4.734306 0)
			(unlocked yes)
			(layer "Cmts.User")
			(hide yes)
			(effects
				(font
					(size 0.7874 0.5842)
					(thickness 0.1524)
				)
			)
		)
		(property "User Part Number" "PARTNUM*"
			(at 0.2032 5.801106 0)
			(unlocked yes)
			(layer "Cmts.User")
			(hide yes)
			(effects
				(font
					(size 0.7874 0.5842)
					(thickness 0.1524)
				)
			)
		)
		(property "Device Type" "CAPACITOR-G109-0G107-BM,100UF,A"
			(at 0.0762 2.829306 0)
			(unlocked yes)
			(layer "F.Fab")
			(hide yes)
			(effects
				(font
					(size 0.7874 0.5842)
					(thickness 0.1524)
				)
			)
		)
		(duplicate_pad_numbers_are_jumpers no)
		(fp_line
			(start -2.159 -1.5748)
			(end 2.159 -1.5748)
			(stroke
				(width 0.1)
				(type default)
			)
			(layer "F.SilkS")
		)
		(fp_line
			(start -2.159 1.5748)
			(end -2.159 -1.5748)
			(stroke
				(width 0.1)
				(type default)
			)
			(layer "F.SilkS")
		)
		(fp_line
			(start 2.159 -1.5748)
			(end 2.159 1.5748)
			(stroke
				(width 0.1)
				(type default)
			)
			(layer "F.SilkS")
		)
		(fp_line
			(start 2.159 1.5748)
			(end -2.159 1.5748)
			(stroke
				(width 0.1)
				(type default)
			)
			(layer "F.SilkS")
		)
		(fp_rect
			(start -2.159 -1.5748)
			(end 2.159 1.5748)
			(stroke
				(width 0)
				(type default)
			)
			(fill no)
			(layer "F.CrtYd")
		)
		(fp_line
			(start -1.6002 -1.2446)
			(end -1.6002 1.2446)
			(stroke
				(width 0.1)
				(type default)
			)
			(layer "F.Fab")
		)
		(fp_line
			(start -1.6002 1.2446)
			(end 1.6002 1.2446)
			(stroke
				(width 0.1)
				(type default)
			)
			(layer "F.Fab")
		)
		(fp_line
			(start 1.6002 -1.2446)
			(end -1.6002 -1.2446)
			(stroke
				(width 0.1)
				(type default)
			)
			(layer "F.Fab")
		)
		(fp_line
			(start 1.6002 1.2446)
			(end 1.6002 -1.2446)
			(stroke
				(width 0.1)
				(type default)
			)
			(layer "F.Fab")
		)
		(pad "1" smd rect
			(at -1.3335 0)
			(size 1.143 2.6416)
			(layers "F.Cu" "F.Mask" "F.Paste")
			(net "XP1R0V_FPGA_VCCINT")
		)
		(pad "2" smd rect
			(at 1.3335 0)
			(size 1.143 2.6416)
			(layers "F.Cu" "F.Mask" "F.Paste")
			(net "SG")
		)
		(zone
			(layer "F.Cu")
			(hatch none 0.5)
			(connect_pads
				(clearance 0)
			)
			(min_thickness 0.25)
			(keepout
				(tracks allowed)
				(vias not_allowed)
				(pads allowed)
				(copperpour not_allowed)
				(footprints allowed)
			)
			(placement
				(enabled no)
				(sheetname "")
			)
			(fill
				(thermal_gap 0.5)
				(thermal_bridge_width 0.5)
				(island_removal_mode 0)
			)
			(polygon
				(pts
					(xy 132.5372 -41.91) (xy 132.5372 -39.116) (xy 133.9088 -39.116) (xy 133.9088 -41.91)
				)
			)
		)
	)
	(footprint ""
		(layer "F.Cu")
		(at 54.229 -80.645 -90)
		(property "Reference" "U35"
			(at 0.508 -2.70637 90)
			(unlocked yes)
			(layer "F.SilkS")
			(effects
				(font
					(size 0.7874 0.5842)
					(thickness 0.1524)
				)
			)
		)
		(property "Value" ""
			(at 0 0 270)
			(layer "F.Fab")
			(effects
				(font
					(size 1.27 1.27)
				)
			)
		)
		(property "Device Type" "LM75BDP_TSSOP8-G220-10215-01"
			(at -0.03175 2.55651 270)
			(unlocked yes)
			(layer "F.Fab")
			(hide yes)
			(effects
				(font
					(size 0.7874 0.5842)
					(thickness 0.1524)
				)
			)
		)
		(property "User Part Number" "PARTNUM*"
			(at -0.037592 3.488182 270)
			(unlocked yes)
			(layer "Cmts.User")
			(hide yes)
			(effects
				(font
					(size 0.7874 0.5842)
					(thickness 0.1524)
				)
			)
		)
		(duplicate_pad_numbers_are_jumpers no)
		(fp_line
			(start -1.778 1.778)
			(end 1.778 1.778)
			(stroke
				(width 0.1)
				(type default)
			)
			(layer "F.SilkS")
		)
		(fp_line
			(start 1.778 1.778)
			(end 1.778 1.45796)
			(stroke
				(width 0.1)
				(type default)
			)
			(layer "F.SilkS")
		)
		(fp_line
			(start -3.3147 1.45796)
			(end -1.778 1.45796)
			(stroke
				(width 0.1)
				(type default)
			)
			(layer "F.SilkS")
		)
		(fp_line
			(start -1.778 1.45796)
			(end -1.778 1.778)
			(stroke
				(width 0.1)
				(type default)
			)
			(layer "F.SilkS")
		)
		(fp_line
			(start 1.778 1.45796)
			(end 3.3147 1.45796)
			(stroke
				(width 0.1)
				(type default)
			)
			(layer "F.SilkS")
		)
		(fp_line
			(start 3.3147 1.45796)
			(end 3.3147 -1.45796)
			(stroke
				(width 0.1)
				(type default)
			)
			(layer "F.SilkS")
		)
		(fp_line
			(start -3.3147 -1.45796)
			(end -3.3147 1.45796)
			(stroke
				(width 0.1)
				(type default)
			)
			(layer "F.SilkS")
		)
		(fp_line
			(start -1.778 -1.45796)
			(end -3.3147 -1.45796)
			(stroke
				(width 0.1)
				(type default)
			)
			(layer "F.SilkS")
		)
		(fp_line
			(start 1.778 -1.45796)
			(end 1.778 -1.778)
			(stroke
				(width 0.1)
				(type default)
			)
			(layer "F.SilkS")
		)
		(fp_line
			(start 3.3147 -1.45796)
			(end 1.778 -1.45796)
			(stroke
				(width 0.1)
				(type default)
			)
			(layer "F.SilkS")
		)
		(fp_line
			(start -1.778 -1.778)
			(end -1.778 -1.45796)
			(stroke
				(width 0.1)
				(type default)
			)
			(layer "F.SilkS")
		)
		(fp_line
			(start 1.778 -1.778)
			(end -1.778 -1.778)
			(stroke
				(width 0.1)
				(type default)
			)
			(layer "F.SilkS")
		)
		(fp_poly
			(pts
				(arc
					(start -3.730498 -1.372362)
					(mid -3.730498 -0.610362)
					(end -3.730498 -1.372362)
				)
			)
			(stroke
				(width 0)
				(type default)
			)
			(fill yes)
			(layer "F.SilkS")
		)
		(fp_poly
			(pts
				(xy -3.5687 -2.032) (xy -3.5687 2.032) (xy 3.5687 2.032) (xy 3.5687 -2.032)
			)
			(stroke
				(width 0)
				(type default)
			)
			(fill no)
			(layer "F.CrtYd")
		)
		(fp_line
			(start -1.524 1.524)
			(end -1.524 -1.524)
			(stroke
				(width 0.1)
				(type default)
			)
			(layer "F.Fab")
		)
		(fp_line
			(start 1.524 1.524)
			(end -1.524 1.524)
			(stroke
				(width 0.1)
				(type default)
			)
			(layer "F.Fab")
		)
		(fp_line
			(start -1.524 -1.524)
			(end 1.524 -1.524)
			(stroke
				(width 0.1)
				(type default)
			)
			(layer "F.Fab")
		)
		(fp_line
			(start 1.524 -1.524)
			(end 1.524 1.524)
			(stroke
				(width 0.1)
				(type default)
			)
			(layer "F.Fab")
		)
		(fp_poly
			(pts
				(arc
					(start -0.9906 -1.3208)
					(mid -0.9906 -0.5588)
					(end -0.9906 -1.3208)
				)
			)
			(stroke
				(width 0)
				(type default)
			)
			(fill yes)
			(layer "F.Fab")
		)
		(fp_text user "5"
			(at 3.91795 1.905 0)
			(unlocked yes)
			(layer "F.SilkS")
			(effects
				(font
					(size 0.635 0.4064)
					(thickness 0.1524)
				)
			)
		)
		(fp_text user "4"
			(at -4.08305 1.778 0)
			(unlocked yes)
			(layer "F.SilkS")
			(effects
				(font
					(size 0.635 0.4064)
					(thickness 0.1524)
				)
			)
		)
		(fp_text user "8"
			(at 3.40995 -2.413 0)
			(unlocked yes)
			(layer "F.SilkS")
			(effects
				(font
					(size 0.635 0.4064)
					(thickness 0.1524)
				)
			)
		)
		(fp_text user "5"
			(at 3.21437 1.651 0)
			(unlocked yes)
			(layer "F.Fab")
			(effects
				(font
					(size 0.7874 0.5842)
					(thickness 0.1524)
				)
			)
		)
		(fp_text user "4"
			(at -3.26263 1.524 0)
			(unlocked yes)
			(layer "F.Fab")
			(effects
				(font
					(size 0.7874 0.5842)
					(thickness 0.1524)
				)
			)
		)
		(fp_text user "8"
			(at 3.21437 -1.905 0)
			(unlocked yes)
			(layer "F.Fab")
			(effects
				(font
					(size 0.7874 0.5842)
					(thickness 0.1524)
				)
			)
		)
		(pad "1" smd rect
			(at -2.2987 -0.97536)
			(size 0.4572 1.524)
			(layers "F.Cu" "F.Mask" "F.Paste")
			(net "R_LM75B_2_I2C_SDA")
		)
		(pad "2" smd rect
			(at -2.2987 -0.32512)
			(size 0.4572 1.524)
			(layers "F.Cu" "F.Mask" "F.Paste")
			(net "LM75B_I2C_SCL")
		)
		(pad "3" smd rect
			(at -2.2987 0.32512)
			(size 0.4572 1.524)
			(layers "F.Cu" "F.Mask" "F.Paste")
			(net "FPGA_IN_LM75B_INT2_N")
		)
		(pad "4" smd rect
			(at -2.2987 0.97536)
			(size 0.4572 1.524)
			(layers "F.Cu" "F.Mask" "F.Paste")
			(net "SG")
		)
		(pad "5" smd rect
			(at 2.2987 0.97536)
			(size 0.4572 1.524)
			(layers "F.Cu" "F.Mask" "F.Paste")
			(net "UNNAMED_6_LM75BDPTSSOP8_I59_A2")
		)
		(pad "6" smd rect
			(at 2.2987 0.32512)
			(size 0.4572 1.524)
			(layers "F.Cu" "F.Mask" "F.Paste")
			(net "UNNAMED_6_LM75BDPTSSOP8_I59_A1")
		)
		(pad "7" smd rect
			(at 2.2987 -0.32512)
			(size 0.4572 1.524)
			(layers "F.Cu" "F.Mask" "F.Paste")
			(net "UNNAMED_6_LM75BDPTSSOP8_I59_A0")
		)
		(pad "8" smd rect
			(at 2.2987 -0.97536)
			(size 0.4572 1.524)
			(layers "F.Cu" "F.Mask" "F.Paste")
			(net "XP3R3V_FPGA")
		)
	)
	(footprint ""
		(layer "F.Cu")
		(at 95.25 -53.34)
		(property "Reference" "TP181"
			(at 0 0 0)
			(layer "F.SilkS")
			(hide yes)
			(effects
				(font
					(size 1.27 1.27)
				)
			)
		)
		(property "Value" ""
			(at 0 0 0)
			(layer "F.Fab")
			(effects
				(font
					(size 1.27 1.27)
				)
			)
		)
		(property "Device Type" "TP_PIONT-TP010CT020B030_PTH-TPA"
			(at -1.341882 0.996696 0)
			(unlocked yes)
			(layer "F.Fab")
			(hide yes)
			(effects
				(font
					(size 0.7874 0.5842)
					(thickness 0.1524)
				)
				(justify left)
			)
		)
		(duplicate_pad_numbers_are_jumpers no)
		(fp_poly
			(pts
				(arc
					(start 0.889 0)
					(mid -0.889 0)
					(end 0.889 0)
				)
			)
			(stroke
				(width 0)
				(type default)
			)
			(fill no)
			(layer "B.CrtYd")
		)
		(fp_poly
			(pts
				(arc
					(start 0.889 0)
					(mid -0.889 0)
					(end 0.889 0)
				)
			)
			(stroke
				(width 0)
				(type default)
			)
			(fill no)
			(layer "F.CrtYd")
		)
		(pad "1" thru_hole circle
			(at 0 0)
			(size 0.508 0.508)
			(drill 0.254)
			(layers "*.Cu" "*.Mask")
			(remove_unused_layers no)
			(net "IO_L21P_16")
			(clearance 0.1016)
			(padstack
				(mode front_inner_back)
				(layer "Inner"
					(shape circle)
					(size 0.508 0.508)
					(clearance 0.1016)
				)
				(layer "B.Cu"
					(shape circle)
					(size 0.762 0.762)
					(clearance -0.0254)
				)
			)
		)
	)
	(footprint ""
		(layer "F.Cu")
		(at 11.557 -44.704 90)
		(property "Reference" "R126"
			(at 0.508 -1.23063 90)
			(unlocked yes)
			(layer "F.SilkS")
			(effects
				(font
					(size 0.7874 0.5842)
					(thickness 0.1524)
				)
			)
		)
		(property "Value" "VAL*"
			(at 0.02032 2.13233 90)
			(unlocked yes)
			(layer "F.Fab")
			(hide yes)
			(effects
				(font
					(size 0.7874 0.5842)
					(thickness 0.1524)
				)
			)
		)
		(property "Tolerance" "TOL*"
			(at 0.044704 3.05435 90)
			(unlocked yes)
			(layer "Cmts.User")
			(hide yes)
			(effects
				(font
					(size 0.7874 0.5842)
					(thickness 0.1524)
				)
			)
		)
		(property "User Part Number" "PARTNUM*"
			(at 0.02032 4.024884 90)
			(unlocked yes)
			(layer "Cmts.User")
			(hide yes)
			(effects
				(font
					(size 0.7874 0.5842)
					(thickness 0.1524)
				)
			)
		)
		(property "Device Type" "RESISTOR-G155-149R9-01,49.9OHMA"
			(at 0.008382 1.210564 90)
			(unlocked yes)
			(layer "F.Fab")
			(hide yes)
			(effects
				(font
					(size 0.7874 0.5842)
					(thickness 0.1524)
				)
			)
		)
		(duplicate_pad_numbers_are_jumpers no)
		(fp_line
			(start 1.143 -0.5588)
			(end -1.143 -0.5588)
			(stroke
				(width 0.1)
				(type default)
			)
			(layer "F.SilkS")
		)
		(fp_line
			(start -1.143 -0.5588)
			(end -1.143 0.5588)
			(stroke
				(width 0.1)
				(type default)
			)
			(layer "F.SilkS")
		)
		(fp_line
			(start 1.143 0.5588)
			(end 1.143 -0.5588)
			(stroke
				(width 0.1)
				(type default)
			)
			(layer "F.SilkS")
		)
		(fp_line
			(start -1.143 0.5588)
			(end 1.143 0.5588)
			(stroke
				(width 0.1)
				(type default)
			)
			(layer "F.SilkS")
		)
		(fp_poly
			(pts
				(xy -1.143 0.5588) (xy 1.143 0.5588) (xy 1.143 -0.5588) (xy -1.143 -0.5588)
			)
			(stroke
				(width 0)
				(type default)
			)
			(fill no)
			(layer "F.CrtYd")
		)
		(fp_line
			(start 0.508 -0.3048)
			(end -0.508 -0.3048)
			(stroke
				(width 0.1)
				(type default)
			)
			(layer "F.Fab")
		)
		(fp_line
			(start -0.508 -0.3048)
			(end -0.508 0.3048)
			(stroke
				(width 0.1)
				(type default)
			)
			(layer "F.Fab")
		)
		(fp_line
			(start 0.508 0.3048)
			(end 0.508 -0.3048)
			(stroke
				(width 0.1)
				(type default)
			)
			(layer "F.Fab")
		)
		(fp_line
			(start -0.508 0.3048)
			(end 0.508 0.3048)
			(stroke
				(width 0.1)
				(type default)
			)
			(layer "F.Fab")
		)
		(pad "1" smd rect
			(at -0.5334 0 90)
			(size 0.7112 0.6096)
			(layers "F.Cu" "F.Mask" "F.Paste")
			(net "BF_SMA2_SIG_IO_CONN")
		)
		(pad "2" smd rect
			(at 0.5334 0 90)
			(size 0.7112 0.6096)
			(layers "F.Cu" "F.Mask" "F.Paste")
			(net "SMA2_SIG_IO_CONN")
		)
		(zone
			(layer "F.Cu")
			(hatch none 0.5)
			(connect_pads
				(clearance 0)
			)
			(min_thickness 0.25)
			(keepout
				(tracks allowed)
				(vias not_allowed)
				(pads allowed)
				(copperpour not_allowed)
				(footprints allowed)
			)
			(placement
				(enabled no)
				(sheetname "")
			)
			(fill
				(thermal_gap 0.5)
				(thermal_bridge_width 0.5)
				(island_removal_mode 0)
			)
			(polygon
				(pts
					(xy 11.8618 -44.6278) (xy 11.8618 -44.7802) (xy 11.2522 -44.7802) (xy 11.2522 -44.6278)
				)
			)
		)
		(zone
			(layer "F.Cu")
			(hatch none 0.5)
			(connect_pads
				(clearance 0)
			)
			(min_thickness 0.25)
			(keepout
				(tracks not_allowed)
				(vias allowed)
				(pads allowed)
				(copperpour not_allowed)
				(footprints allowed)
			)
			(placement
				(enabled no)
				(sheetname "")
			)
			(fill
				(thermal_gap 0.5)
				(thermal_bridge_width 0.5)
				(island_removal_mode 0)
			)
			(polygon
				(pts
					(xy 11.8618 -44.6278) (xy 11.8618 -44.7802) (xy 11.2522 -44.7802) (xy 11.2522 -44.6278)
				)
			)
		)
	)
	(footprint ""
		(layer "F.Cu")
		(at 161.04997 -89.149936 -90)
		(property "Reference" "P3"
			(at -8.232394 -0.36703 0)
			(unlocked yes)
			(layer "F.SilkS")
			(effects
				(font
					(size 0.7874 0.5842)
					(thickness 0.1524)
				)
			)
		)
		(property "Value" ""
			(at 0 0 270)
			(layer "F.Fab")
			(effects
				(font
					(size 1.27 1.27)
				)
			)
		)
		(property "Device Type" "CONN_HDR_2X3_M_RA_TH-G200-1251A"
			(at 0 14.183868 270)
			(unlocked yes)
			(layer "F.Fab")
			(hide yes)
			(effects
				(font
					(size 0.7874 0.5842)
					(thickness 0.1524)
				)
			)
		)
		(property "User Part Number" "PARTNUM*"
			(at 0 15.377668 270)
			(unlocked yes)
			(layer "Cmts.User")
			(hide yes)
			(effects
				(font
					(size 0.7874 0.5842)
					(thickness 0.1524)
				)
			)
		)
		(duplicate_pad_numbers_are_jumpers no)
		(fp_line
			(start -7.343902 13.074904)
			(end -7.343902 -7.043928)
			(stroke
				(width 0.1)
				(type default)
			)
			(layer "F.SilkS")
		)
		(fp_line
			(start 7.343902 13.074904)
			(end -7.343902 13.074904)
			(stroke
				(width 0.1)
				(type default)
			)
			(layer "F.SilkS")
		)
		(fp_line
			(start -7.343902 -7.043928)
			(end 7.343902 -7.043928)
			(stroke
				(width 0.1)
				(type default)
			)
			(layer "F.SilkS")
		)
		(fp_line
			(start 7.343902 -7.043928)
			(end 7.343902 13.074904)
			(stroke
				(width 0.1)
				(type default)
			)
			(layer "F.SilkS")
		)
		(fp_rect
			(start 10.60069 17.900904)
			(end -10.60069 0.89916)
			(stroke
				(width 0)
				(type default)
			)
			(fill no)
			(layer "B.CrtYd")
		)
		(fp_rect
			(start 7.597902 13.328904)
			(end -7.597902 -7.297928)
			(stroke
				(width 0)
				(type default)
			)
			(fill no)
			(layer "F.CrtYd")
		)
		(fp_line
			(start -7.089902 6.389878)
			(end -7.089902 -6.789928)
			(stroke
				(width 0.1)
				(type default)
			)
			(layer "F.Fab")
		)
		(fp_line
			(start 7.089902 6.389878)
			(end -7.089902 6.389878)
			(stroke
				(width 0.1)
				(type default)
			)
			(layer "F.Fab")
		)
		(fp_line
			(start -7.089902 -6.789928)
			(end 7.089902 -6.789928)
			(stroke
				(width 0.1)
				(type default)
			)
			(layer "F.Fab")
		)
		(fp_line
			(start 7.089902 -6.789928)
			(end 7.089902 6.389878)
			(stroke
				(width 0.1)
				(type default)
			)
			(layer "F.Fab")
		)
		(fp_text user "4"
			(at -8.092694 11.06297 0)
			(unlocked yes)
			(layer "F.SilkS")
			(effects
				(font
					(size 0.7874 0.5842)
					(thickness 0.1524)
				)
			)
		)
		(fp_text user "6"
			(at 8.163306 9.53897 0)
			(unlocked yes)
			(layer "F.SilkS")
			(effects
				(font
					(size 0.7874 0.5842)
					(thickness 0.1524)
				)
			)
		)
		(fp_text user "1"
			(at -7.965694 6.49097 0)
			(unlocked yes)
			(layer "F.SilkS")
			(effects
				(font
					(size 0.7874 0.5842)
					(thickness 0.1524)
				)
			)
		)
		(fp_text user "3"
			(at 8.036306 5.98297 0)
			(unlocked yes)
			(layer "F.SilkS")
			(effects
				(font
					(size 0.7874 0.5842)
					(thickness 0.1524)
				)
			)
		)
		(fp_text user "6"
			(at 6.996176 11.553444 0)
			(unlocked yes)
			(layer "F.Fab")
			(effects
				(font
					(size 0.7874 0.5842)
					(thickness 0.1524)
				)
			)
		)
		(fp_text user "4"
			(at -7.671308 11.30173 0)
			(unlocked yes)
			(layer "F.Fab")
			(effects
				(font
					(size 0.7874 0.5842)
					(thickness 0.1524)
				)
			)
		)
		(fp_text user "3"
			(at 7.120636 7.170674 0)
			(unlocked yes)
			(layer "F.Fab")
			(effects
				(font
					(size 0.7874 0.5842)
					(thickness 0.1524)
				)
			)
		)
		(fp_text user "1"
			(at -7.515606 6.825742 0)
			(unlocked yes)
			(layer "F.Fab")
			(effects
				(font
					(size 0.7874 0.5842)
					(thickness 0.1524)
				)
			)
		)
		(pad "" np_thru_hole circle
			(at -4.19989 0 270)
			(size 2.7432 2.7432)
			(drill 2.9972)
			(layers "*.Cu" "*.Mask")
			(padstack
				(mode front_inner_back)
				(layer "Inner"
					(shape circle)
					(size 2.7432 2.7432)
					(clearance 0.4445)
				)
				(layer "B.Cu"
					(shape circle)
					(size 2.7432 2.7432)
				)
			)
		)
		(pad "" np_thru_hole circle
			(at 4.19989 0 270)
			(size 2.7432 2.7432)
			(drill 2.9972)
			(layers "*.Cu" "*.Mask")
			(padstack
				(mode front_inner_back)
				(layer "Inner"
					(shape circle)
					(size 2.7432 2.7432)
					(clearance 0.4445)
				)
				(layer "B.Cu"
					(shape circle)
					(size 2.7432 2.7432)
				)
			)
		)
		(pad "1" thru_hole rect
			(at -4.19989 7.29996 270)
			(size 2.6416 2.6416)
			(drill 1.9304)
			(layers "*.Cu" "*.Mask")
			(remove_unused_layers no)
			(net "XP12R0V_EXT")
			(padstack
				(mode front_inner_back)
				(layer "Inner"
					(shape circle)
					(size 2.6416 2.6416)
					(clearance -0.0635)
				)
				(layer "B.Cu"
					(shape rect)
					(size 2.6416 2.6416)
				)
			)
		)
		(pad "2" thru_hole circle
			(at 0 7.29996 270)
			(size 2.6416 2.6416)
			(drill 1.9304)
			(layers "*.Cu" "*.Mask")
			(remove_unused_layers no)
			(net "XP12R0V_EXT")
			(padstack
				(mode front_inner_back)
				(layer "Inner"
					(shape circle)
					(size 2.6416 2.6416)
					(clearance -0.0635)
				)
				(layer "B.Cu"
					(shape circle)
					(size 2.6416 2.6416)
				)
			)
		)
		(pad "3" thru_hole circle
			(at 4.19989 7.29996 270)
			(size 2.6416 2.6416)
			(drill 1.9304)
			(layers "*.Cu" "*.Mask")
			(remove_unused_layers no)
			(net "XP12R0V_EXT")
			(padstack
				(mode front_inner_back)
				(layer "Inner"
					(shape circle)
					(size 2.6416 2.6416)
					(clearance -0.0635)
				)
				(layer "B.Cu"
					(shape circle)
					(size 2.6416 2.6416)
				)
			)
		)
		(pad "4" thru_hole circle
			(at -4.19989 11.500104 270)
			(size 2.6416 2.6416)
			(drill 1.9304)
			(layers "*.Cu" "*.Mask")
			(remove_unused_layers no)
			(net "SG")
			(padstack
				(mode front_inner_back)
				(layer "Inner"
					(shape circle)
					(size 2.6416 2.6416)
					(clearance -0.0635)
				)
				(layer "B.Cu"
					(shape circle)
					(size 2.6416 2.6416)
				)
			)
		)
		(pad "5" thru_hole circle
			(at 0 11.500104 270)
			(size 2.6416 2.6416)
			(drill 1.9304)
			(layers "*.Cu" "*.Mask")
			(remove_unused_layers no)
			(net "SG")
			(padstack
				(mode front_inner_back)
				(layer "Inner"
					(shape circle)
					(size 2.6416 2.6416)
					(clearance -0.0635)
				)
				(layer "B.Cu"
					(shape circle)
					(size 2.6416 2.6416)
				)
			)
		)
		(pad "6" thru_hole circle
			(at 4.19989 11.500104 270)
			(size 2.6416 2.6416)
			(drill 1.9304)
			(layers "*.Cu" "*.Mask")
			(remove_unused_layers no)
			(net "SG")
			(padstack
				(mode front_inner_back)
				(layer "Inner"
					(shape circle)
					(size 2.6416 2.6416)
					(clearance -0.0635)
				)
				(layer "B.Cu"
					(shape circle)
					(size 2.6416 2.6416)
				)
			)
		)
		(zone
			(layers "F.Cu" "B.Cu" "In1.Cu" "In2.Cu" "In3.Cu" "In4.Cu" "In5.Cu" "In6.Cu"
				"In7.Cu" "In8.Cu"
			)
			(hatch none 0.5)
			(connect_pads
				(clearance 0)
			)
			(min_thickness 0.25)
			(keepout
				(tracks not_allowed)
				(vias allowed)
				(pads allowed)
				(copperpour not_allowed)
				(footprints allowed)
			)
			(placement
				(enabled no)
				(sheetname "")
			)
			(fill
				(thermal_gap 0.5)
				(thermal_bridge_width 0.5)
				(island_removal_mode 0)
			)
			(polygon
				(pts
					(arc
						(start 163.18357 -93.349826)
						(mid 158.91637 -93.349826)
						(end 163.18357 -93.349826)
					)
				)
			)
		)
		(zone
			(layers "F.Cu" "B.Cu" "In1.Cu" "In2.Cu" "In3.Cu" "In4.Cu" "In5.Cu" "In6.Cu"
				"In7.Cu" "In8.Cu"
			)
			(hatch none 0.5)
			(connect_pads
				(clearance 0)
			)
			(min_thickness 0.25)
			(keepout
				(tracks not_allowed)
				(vias allowed)
				(pads allowed)
				(copperpour not_allowed)
				(footprints allowed)
			)
			(placement
				(enabled no)
				(sheetname "")
			)
			(fill
				(thermal_gap 0.5)
				(thermal_bridge_width 0.5)
				(island_removal_mode 0)
			)
			(polygon
				(pts
					(arc
						(start 163.18357 -84.950046)
						(mid 158.91637 -84.950046)
						(end 163.18357 -84.950046)
					)
				)
			)
		)
	)
	(footprint ""
		(layer "F.Cu")
		(at 10.5664 -39.318692 90)
		(property "Reference" "R386"
			(at 0.178308 1.02235 90)
			(unlocked yes)
			(layer "F.SilkS")
			(effects
				(font
					(size 0.635 0.4064)
					(thickness 0.1524)
				)
			)
		)
		(property "Value" "VAL*"
			(at 0.02032 2.13233 90)
			(unlocked yes)
			(layer "F.Fab")
			(hide yes)
			(effects
				(font
					(size 0.7874 0.5842)
					(thickness 0.1524)
				)
			)
		)
		(property "Tolerance" "TOL*"
			(at 0.044704 3.05435 90)
			(unlocked yes)
			(layer "Cmts.User")
			(hide yes)
			(effects
				(font
					(size 0.7874 0.5842)
					(thickness 0.1524)
				)
			)
		)
		(property "User Part Number" "PARTNUM*"
			(at 0.02032 4.024884 90)
			(unlocked yes)
			(layer "Cmts.User")
			(hide yes)
			(effects
				(font
					(size 0.7874 0.5842)
					(thickness 0.1524)
				)
			)
		)
		(property "Device Type" "RESISTOR-G155-133R0-01,33OHM,1%"
			(at 0.008382 1.210564 90)
			(unlocked yes)
			(layer "F.Fab")
			(hide yes)
			(effects
				(font
					(size 0.7874 0.5842)
					(thickness 0.1524)
				)
			)
		)
		(duplicate_pad_numbers_are_jumpers no)
		(fp_line
			(start 1.143 -0.5588)
			(end -1.143 -0.5588)
			(stroke
				(width 0.1)
				(type default)
			)
			(layer "F.SilkS")
		)
		(fp_line
			(start -1.143 -0.5588)
			(end -1.143 0.5588)
			(stroke
				(width 0.1)
				(type default)
			)
			(layer "F.SilkS")
		)
		(fp_line
			(start 1.143 0.5588)
			(end 1.143 -0.5588)
			(stroke
				(width 0.1)
				(type default)
			)
			(layer "F.SilkS")
		)
		(fp_line
			(start -1.143 0.5588)
			(end 1.143 0.5588)
			(stroke
				(width 0.1)
				(type default)
			)
			(layer "F.SilkS")
		)
		(fp_rect
			(start -1.143 -0.5588)
			(end 1.143 0.5588)
			(stroke
				(width 0)
				(type default)
			)
			(fill no)
			(layer "F.CrtYd")
		)
		(fp_line
			(start 0.508 -0.3048)
			(end -0.508 -0.3048)
			(stroke
				(width 0.1)
				(type default)
			)
			(layer "F.Fab")
		)
		(fp_line
			(start -0.508 -0.3048)
			(end -0.508 0.3048)
			(stroke
				(width 0.1)
				(type default)
			)
			(layer "F.Fab")
		)
		(fp_line
			(start 0.508 0.3048)
			(end 0.508 -0.3048)
			(stroke
				(width 0.1)
				(type default)
			)
			(layer "F.Fab")
		)
		(fp_line
			(start -0.508 0.3048)
			(end 0.508 0.3048)
			(stroke
				(width 0.1)
				(type default)
			)
			(layer "F.Fab")
		)
		(pad "1" smd rect
			(at -0.5334 0 90)
			(size 0.7112 0.6096)
			(layers "F.Cu" "F.Mask" "F.Paste")
			(net "SMA1_LED_GREEN_N")
		)
		(pad "2" smd rect
			(at 0.5334 0 90)
			(size 0.7112 0.6096)
			(layers "F.Cu" "F.Mask" "F.Paste")
			(net "UNNAMED_14_LED4PV14_I265_4")
		)
		(zone
			(layer "F.Cu")
			(hatch none 0.5)
			(connect_pads
				(clearance 0)
			)
			(min_thickness 0.25)
			(keepout
				(tracks not_allowed)
				(vias allowed)
				(pads allowed)
				(copperpour not_allowed)
				(footprints allowed)
			)
			(placement
				(enabled no)
				(sheetname "")
			)
			(fill
				(thermal_gap 0.5)
				(thermal_bridge_width 0.5)
				(island_removal_mode 0)
			)
			(polygon
				(pts
					(xy 10.2616 -39.242492) (xy 10.8712 -39.242492) (xy 10.8712 -39.394892) (xy 10.2616 -39.394892)
				)
			)
		)
		(zone
			(layer "F.Cu")
			(hatch none 0.5)
			(connect_pads
				(clearance 0)
			)
			(min_thickness 0.25)
			(keepout
				(tracks allowed)
				(vias not_allowed)
				(pads allowed)
				(copperpour not_allowed)
				(footprints allowed)
			)
			(placement
				(enabled no)
				(sheetname "")
			)
			(fill
				(thermal_gap 0.5)
				(thermal_bridge_width 0.5)
				(island_removal_mode 0)
			)
			(polygon
				(pts
					(xy 10.2616 -39.242492) (xy 10.8712 -39.242492) (xy 10.8712 -39.394892) (xy 10.2616 -39.394892)
				)
			)
		)
	)
	(footprint ""
		(layer "F.Cu")
		(at 79.883 -43.053)
		(property "Reference" "R96"
			(at 0 13.88237 0)
			(unlocked yes)
			(layer "F.SilkS")
			(effects
				(font
					(size 0.7874 0.5842)
					(thickness 0.1524)
				)
			)
		)
		(property "Value" "VAL*"
			(at 0.02032 2.13233 0)
			(unlocked yes)
			(layer "F.Fab")
			(hide yes)
			(effects
				(font
					(size 0.7874 0.5842)
					(thickness 0.1524)
				)
			)
		)
		(property "Device Type" "RESISTOR-G155-133R0-01,33OHM,1%"
			(at 0.008382 1.210564 0)
			(unlocked yes)
			(layer "F.Fab")
			(hide yes)
			(effects
				(font
					(size 0.7874 0.5842)
					(thickness 0.1524)
				)
			)
		)
		(property "User Part Number" "PARTNUM*"
			(at 0.02032 4.024884 0)
			(unlocked yes)
			(layer "Cmts.User")
			(hide yes)
			(effects
				(font
					(size 0.7874 0.5842)
					(thickness 0.1524)
				)
			)
		)
		(property "Tolerance" "TOL*"
			(at 0.044704 3.05435 0)
			(unlocked yes)
			(layer "Cmts.User")
			(hide yes)
			(effects
				(font
					(size 0.7874 0.5842)
					(thickness 0.1524)
				)
			)
		)
		(duplicate_pad_numbers_are_jumpers no)
		(fp_line
			(start -1.143 -0.5588)
			(end -1.143 0.5588)
			(stroke
				(width 0.1)
				(type default)
			)
			(layer "F.SilkS")
		)
		(fp_line
			(start -1.143 0.5588)
			(end 1.143 0.5588)
			(stroke
				(width 0.1)
				(type default)
			)
			(layer "F.SilkS")
		)
		(fp_line
			(start 1.143 -0.5588)
			(end -1.143 -0.5588)
			(stroke
				(width 0.1)
				(type default)
			)
			(layer "F.SilkS")
		)
		(fp_line
			(start 1.143 0.5588)
			(end 1.143 -0.5588)
			(stroke
				(width 0.1)
				(type default)
			)
			(layer "F.SilkS")
		)
		(fp_rect
			(start -1.143 0.5588)
			(end 1.143 -0.5588)
			(stroke
				(width 0)
				(type default)
			)
			(fill no)
			(layer "F.CrtYd")
		)
		(fp_line
			(start -0.508 -0.3048)
			(end -0.508 0.3048)
			(stroke
				(width 0.1)
				(type default)
			)
			(layer "F.Fab")
		)
		(fp_line
			(start -0.508 0.3048)
			(end 0.508 0.3048)
			(stroke
				(width 0.1)
				(type default)
			)
			(layer "F.Fab")
		)
		(fp_line
			(start 0.508 -0.3048)
			(end -0.508 -0.3048)
			(stroke
				(width 0.1)
				(type default)
			)
			(layer "F.Fab")
		)
		(fp_line
			(start 0.508 0.3048)
			(end 0.508 -0.3048)
			(stroke
				(width 0.1)
				(type default)
			)
			(layer "F.Fab")
		)
		(pad "1" smd rect
			(at -0.5334 0)
			(size 0.7112 0.6096)
			(layers "F.Cu" "F.Mask" "F.Paste")
			(net "MAC_ALARM")
		)
		(pad "2" smd rect
			(at 0.5334 0)
			(size 0.7112 0.6096)
			(layers "F.Cu" "F.Mask" "F.Paste")
			(net "FPGA_IN_MAC_ALARM_OUT_N")
		)
		(zone
			(layer "F.Cu")
			(hatch none 0.5)
			(connect_pads
				(clearance 0)
			)
			(min_thickness 0.25)
			(keepout
				(tracks allowed)
				(vias not_allowed)
				(pads allowed)
				(copperpour not_allowed)
				(footprints allowed)
			)
			(placement
				(enabled no)
				(sheetname "")
			)
			(fill
				(thermal_gap 0.5)
				(thermal_bridge_width 0.5)
				(island_removal_mode 0)
			)
			(polygon
				(pts
					(xy 79.8068 -42.7482) (xy 79.9592 -42.7482) (xy 79.9592 -43.3578) (xy 79.8068 -43.3578)
				)
			)
		)
	)
	(footprint ""
		(layer "F.Cu")
		(at 99.3648 -78.5368)
		(property "Reference" "C184"
			(at 2.78257 -1.4732 90)
			(unlocked yes)
			(layer "F.SilkS")
			(effects
				(font
					(size 0.7874 0.5842)
					(thickness 0.1524)
				)
			)
		)
		(property "Value" "VAL*"
			(at 0.0762 2.067306 0)
			(unlocked yes)
			(layer "F.Fab")
			(hide yes)
			(effects
				(font
					(size 0.7874 0.5842)
					(thickness 0.1524)
				)
			)
		)
		(property "Tolerance" "TOL*"
			(at 0.0762 3.032506 0)
			(unlocked yes)
			(layer "Cmts.User")
			(hide yes)
			(effects
				(font
					(size 0.7874 0.5842)
					(thickness 0.1524)
				)
			)
		)
		(property "User Part Number" "PARTNUM*"
			(at 0.1016 4.023106 0)
			(unlocked yes)
			(layer "Cmts.User")
			(hide yes)
			(effects
				(font
					(size 0.7874 0.5842)
					(thickness 0.1524)
				)
			)
		)
		(property "Device Type" "CAPACITOR-G105-0B104-EK,0.1UF,A"
			(at 0.0508 1.127506 0)
			(unlocked yes)
			(layer "F.Fab")
			(hide yes)
			(effects
				(font
					(size 0.7874 0.5842)
					(thickness 0.1524)
				)
			)
		)
		(duplicate_pad_numbers_are_jumpers no)
		(fp_line
			(start -1.143 -0.5588)
			(end -1.143 0.5588)
			(stroke
				(width 0.1)
				(type default)
			)
			(layer "F.SilkS")
		)
		(fp_line
			(start -1.143 0.5588)
			(end 1.143 0.5588)
			(stroke
				(width 0.1)
				(type default)
			)
			(layer "F.SilkS")
		)
		(fp_line
			(start 1.143 -0.5588)
			(end -1.143 -0.5588)
			(stroke
				(width 0.1)
				(type default)
			)
			(layer "F.SilkS")
		)
		(fp_line
			(start 1.143 0.5588)
			(end 1.143 -0.5588)
			(stroke
				(width 0.1)
				(type default)
			)
			(layer "F.SilkS")
		)
		(fp_rect
			(start -1.143 -0.5588)
			(end 1.143 0.5588)
			(stroke
				(width 0)
				(type default)
			)
			(fill no)
			(layer "F.CrtYd")
		)
		(fp_line
			(start -0.508 -0.3048)
			(end -0.508 0.3048)
			(stroke
				(width 0.1)
				(type default)
			)
			(layer "F.Fab")
		)
		(fp_line
			(start -0.508 0.3048)
			(end 0.508 0.3048)
			(stroke
				(width 0.1)
				(type default)
			)
			(layer "F.Fab")
		)
		(fp_line
			(start 0.508 -0.3048)
			(end -0.508 -0.3048)
			(stroke
				(width 0.1)
				(type default)
			)
			(layer "F.Fab")
		)
		(fp_line
			(start 0.508 0.3048)
			(end 0.508 -0.3048)
			(stroke
				(width 0.1)
				(type default)
			)
			(layer "F.Fab")
		)
		(pad "1" smd rect
			(at -0.5334 0)
			(size 0.7112 0.6096)
			(layers "F.Cu" "F.Mask" "F.Paste")
			(net "XP1R2V_EN_R")
		)
		(pad "2" smd rect
			(at 0.5334 0)
			(size 0.7112 0.6096)
			(layers "F.Cu" "F.Mask" "F.Paste")
			(net "SG")
		)
		(zone
			(layer "F.Cu")
			(hatch none 0.5)
			(connect_pads
				(clearance 0)
			)
			(min_thickness 0.25)
			(keepout
				(tracks allowed)
				(vias not_allowed)
				(pads allowed)
				(copperpour not_allowed)
				(footprints allowed)
			)
			(placement
				(enabled no)
				(sheetname "")
			)
			(fill
				(thermal_gap 0.5)
				(thermal_bridge_width 0.5)
				(island_removal_mode 0)
			)
			(polygon
				(pts
					(xy 99.2886 -78.8416) (xy 99.2886 -78.232) (xy 99.441 -78.232) (xy 99.441 -78.8416)
				)
			)
		)
	)
	(footprint ""
		(layer "F.Cu")
		(at 20.32 -33.02 180)
		(property "Reference" "R389"
			(at -2.667 -0.67437 0)
			(unlocked yes)
			(layer "F.SilkS")
			(effects
				(font
					(size 0.7874 0.5842)
					(thickness 0.1524)
				)
			)
		)
		(property "Value" "VAL*"
			(at 0.02032 2.13233 180)
			(unlocked yes)
			(layer "F.Fab")
			(hide yes)
			(effects
				(font
					(size 0.7874 0.5842)
					(thickness 0.1524)
				)
			)
		)
		(property "Tolerance" "TOL*"
			(at 0.044704 3.05435 180)
			(unlocked yes)
			(layer "Cmts.User")
			(hide yes)
			(effects
				(font
					(size 0.7874 0.5842)
					(thickness 0.1524)
				)
			)
		)
		(property "User Part Number" "PARTNUM*"
			(at 0.02032 4.024884 180)
			(unlocked yes)
			(layer "Cmts.User")
			(hide yes)
			(effects
				(font
					(size 0.7874 0.5842)
					(thickness 0.1524)
				)
			)
		)
		(property "Device Type" "RESISTOR-G155-133R0-01,33OHM,1%"
			(at 0.008382 1.210564 180)
			(unlocked yes)
			(layer "F.Fab")
			(hide yes)
			(effects
				(font
					(size 0.7874 0.5842)
					(thickness 0.1524)
				)
			)
		)
		(duplicate_pad_numbers_are_jumpers no)
		(fp_line
			(start 1.143 0.5588)
			(end 1.143 -0.5588)
			(stroke
				(width 0.1)
				(type default)
			)
			(layer "F.SilkS")
		)
		(fp_line
			(start 1.143 -0.5588)
			(end -1.143 -0.5588)
			(stroke
				(width 0.1)
				(type default)
			)
			(layer "F.SilkS")
		)
		(fp_line
			(start -1.143 0.5588)
			(end 1.143 0.5588)
			(stroke
				(width 0.1)
				(type default)
			)
			(layer "F.SilkS")
		)
		(fp_line
			(start -1.143 -0.5588)
			(end -1.143 0.5588)
			(stroke
				(width 0.1)
				(type default)
			)
			(layer "F.SilkS")
		)
		(fp_rect
			(start -1.143 -0.5588)
			(end 1.143 0.5588)
			(stroke
				(width 0)
				(type default)
			)
			(fill no)
			(layer "F.CrtYd")
		)
		(fp_line
			(start 0.508 0.3048)
			(end 0.508 -0.3048)
			(stroke
				(width 0.1)
				(type default)
			)
			(layer "F.Fab")
		)
		(fp_line
			(start 0.508 -0.3048)
			(end -0.508 -0.3048)
			(stroke
				(width 0.1)
				(type default)
			)
			(layer "F.Fab")
		)
		(fp_line
			(start -0.508 0.3048)
			(end 0.508 0.3048)
			(stroke
				(width 0.1)
				(type default)
			)
			(layer "F.Fab")
		)
		(fp_line
			(start -0.508 -0.3048)
			(end -0.508 0.3048)
			(stroke
				(width 0.1)
				(type default)
			)
			(layer "F.Fab")
		)
		(pad "1" smd rect
			(at -0.5334 0 180)
			(size 0.7112 0.6096)
			(layers "F.Cu" "F.Mask" "F.Paste")
			(net "SMA2_LED_GREEN_N")
		)
		(pad "2" smd rect
			(at 0.5334 0 180)
			(size 0.7112 0.6096)
			(layers "F.Cu" "F.Mask" "F.Paste")
			(net "UNNAMED_14_LED4PV14_I266_4")
		)
		(zone
			(layer "F.Cu")
			(hatch none 0.5)
			(connect_pads
				(clearance 0)
			)
			(min_thickness 0.25)
			(keepout
				(tracks not_allowed)
				(vias allowed)
				(pads allowed)
				(copperpour not_allowed)
				(footprints allowed)
			)
			(placement
				(enabled no)
				(sheetname "")
			)
			(fill
				(thermal_gap 0.5)
				(thermal_bridge_width 0.5)
				(island_removal_mode 0)
			)
			(polygon
				(pts
					(xy 20.3962 -32.7152) (xy 20.3962 -33.3248) (xy 20.2438 -33.3248) (xy 20.2438 -32.7152)
				)
			)
		)
		(zone
			(layer "F.Cu")
			(hatch none 0.5)
			(connect_pads
				(clearance 0)
			)
			(min_thickness 0.25)
			(keepout
				(tracks allowed)
				(vias not_allowed)
				(pads allowed)
				(copperpour not_allowed)
				(footprints allowed)
			)
			(placement
				(enabled no)
				(sheetname "")
			)
			(fill
				(thermal_gap 0.5)
				(thermal_bridge_width 0.5)
				(island_removal_mode 0)
			)
			(polygon
				(pts
					(xy 20.3962 -32.7152) (xy 20.3962 -33.3248) (xy 20.2438 -33.3248) (xy 20.2438 -32.7152)
				)
			)
		)
	)
	(footprint ""
		(layer "F.Cu")
		(at 39.6494 -95.9104)
		(property "Reference" "L7"
			(at -0.2032 1.46177 0)
			(unlocked yes)
			(layer "F.SilkS")
			(effects
				(font
					(size 0.7874 0.5842)
					(thickness 0.1524)
				)
				(justify left)
			)
		)
		(property "Value" "VAL*"
			(at -0.9398 3.70967 0)
			(unlocked yes)
			(layer "F.Fab")
			(hide yes)
			(effects
				(font
					(size 0.7874 0.5842)
					(thickness 0.1524)
				)
				(justify left)
			)
		)
		(property "Tolerance" "TOL*"
			(at -0.9906 5.00507 0)
			(unlocked yes)
			(layer "Cmts.User")
			(hide yes)
			(effects
				(font
					(size 0.7874 0.5842)
					(thickness 0.1524)
				)
				(justify left)
			)
		)
		(property "User Part Number" "PARTNUM*"
			(at -2.54 2.46507 0)
			(unlocked yes)
			(layer "Cmts.User")
			(hide yes)
			(effects
				(font
					(size 0.7874 0.5842)
					(thickness 0.1524)
				)
				(justify left)
			)
		)
		(property "Device Type" "FERRITEBEAD-G191-10101-01,26OHA"
			(at -0.9906 1.22047 0)
			(unlocked yes)
			(layer "F.Fab")
			(hide yes)
			(effects
				(font
					(size 0.7874 0.5842)
					(thickness 0.1524)
				)
				(justify left)
			)
		)
		(duplicate_pad_numbers_are_jumpers no)
		(fp_line
			(start -1.3208 -0.7112)
			(end 1.3208 -0.7112)
			(stroke
				(width 0.1)
				(type default)
			)
			(layer "F.SilkS")
		)
		(fp_line
			(start -1.3208 0.7112)
			(end -1.3208 -0.7112)
			(stroke
				(width 0.1)
				(type default)
			)
			(layer "F.SilkS")
		)
		(fp_line
			(start 1.3208 -0.7112)
			(end 1.3208 0.7112)
			(stroke
				(width 0.1)
				(type default)
			)
			(layer "F.SilkS")
		)
		(fp_line
			(start 1.3208 0.7112)
			(end -1.3208 0.7112)
			(stroke
				(width 0.1)
				(type default)
			)
			(layer "F.SilkS")
		)
		(fp_rect
			(start -1.3208 0.7112)
			(end 1.3208 -0.7112)
			(stroke
				(width 0)
				(type default)
			)
			(fill no)
			(layer "F.CrtYd")
		)
		(fp_line
			(start -0.8128 -0.4572)
			(end 0.8128 -0.4572)
			(stroke
				(width 0.1)
				(type default)
			)
			(layer "F.Fab")
		)
		(fp_line
			(start -0.8128 0.4572)
			(end -0.8128 -0.4572)
			(stroke
				(width 0.1)
				(type default)
			)
			(layer "F.Fab")
		)
		(fp_line
			(start 0.8128 -0.4572)
			(end 0.8128 0.4572)
			(stroke
				(width 0.1)
				(type default)
			)
			(layer "F.Fab")
		)
		(fp_line
			(start 0.8128 0.4572)
			(end -0.8128 0.4572)
			(stroke
				(width 0.1)
				(type default)
			)
			(layer "F.Fab")
		)
		(pad "1" smd rect
			(at -0.6858 0)
			(size 0.762 0.8636)
			(layers "F.Cu" "F.Mask" "F.Paste")
			(net "XP12R0V")
		)
		(pad "2" smd rect
			(at 0.6858 0)
			(size 0.762 0.8636)
			(layers "F.Cu" "F.Mask" "F.Paste")
			(net "VIN_XP5R0V")
		)
		(zone
			(layer "F.Cu")
			(hatch none 0.5)
			(connect_pads
				(clearance 0)
			)
			(min_thickness 0.25)
			(keepout
				(tracks allowed)
				(vias not_allowed)
				(pads allowed)
				(copperpour not_allowed)
				(footprints allowed)
			)
			(placement
				(enabled no)
				(sheetname "")
			)
			(fill
				(thermal_gap 0.5)
				(thermal_bridge_width 0.5)
				(island_removal_mode 0)
			)
			(polygon
				(pts
					(xy 39.497 -95.4532) (xy 39.8018 -95.4532) (xy 39.8018 -96.3676) (xy 39.497 -96.3676)
				)
			)
		)
		(zone
			(layer "F.Cu")
			(hatch none 0.5)
			(connect_pads
				(clearance 0)
			)
			(min_thickness 0.25)
			(keepout
				(tracks not_allowed)
				(vias allowed)
				(pads allowed)
				(copperpour not_allowed)
				(footprints allowed)
			)
			(placement
				(enabled no)
				(sheetname "")
			)
			(fill
				(thermal_gap 0.5)
				(thermal_bridge_width 0.5)
				(island_removal_mode 0)
			)
			(polygon
				(pts
					(xy 39.497 -95.4532) (xy 39.8018 -95.4532) (xy 39.8018 -96.3676) (xy 39.497 -96.3676)
				)
			)
		)
	)
	(footprint ""
		(layer "F.Cu")
		(at 122.428 -53.975)
		(property "Reference" "TP45"
			(at -0.08763 -0.8128 90)
			(unlocked yes)
			(layer "F.SilkS")
			(effects
				(font
					(size 0.7874 0.5842)
					(thickness 0.1524)
				)
				(justify left)
			)
		)
		(property "Value" ""
			(at 0 0 0)
			(layer "F.Fab")
			(effects
				(font
					(size 1.27 1.27)
				)
			)
		)
		(property "Device Type" "TP_PIONT-TP010CT020B030_PTH-TPA"
			(at -1.341882 0.996696 0)
			(unlocked yes)
			(layer "F.Fab")
			(hide yes)
			(effects
				(font
					(size 0.7874 0.5842)
					(thickness 0.000001)
				)
				(justify left)
			)
		)
		(duplicate_pad_numbers_are_jumpers no)
		(fp_poly
			(pts
				(arc
					(start 0.889 0)
					(mid -0.889 0)
					(end 0.889 0)
				)
			)
			(stroke
				(width 0)
				(type default)
			)
			(fill no)
			(layer "B.CrtYd")
		)
		(fp_poly
			(pts
				(arc
					(start 0.889 0)
					(mid -0.889 0)
					(end 0.889 0)
				)
			)
			(stroke
				(width 0)
				(type default)
			)
			(fill no)
			(layer "F.CrtYd")
		)
		(pad "1" thru_hole circle
			(at 0 0)
			(size 0.508 0.508)
			(drill 0.254)
			(layers "*.Cu" "*.Mask")
			(remove_unused_layers no)
			(net "FPGA_PROGRAM_N")
			(clearance 0.1016)
			(padstack
				(mode front_inner_back)
				(layer "Inner"
					(shape circle)
					(size 0.508 0.508)
					(clearance 0.1016)
				)
				(layer "B.Cu"
					(shape circle)
					(size 0.762 0.762)
					(clearance -0.0254)
				)
			)
		)
	)
	(footprint ""
		(layer "F.Cu")
		(at 80.772 -65.2526 180)
		(property "Reference" "R305"
			(at 10.287 19.16303 0)
			(unlocked yes)
			(layer "F.SilkS")
			(effects
				(font
					(size 0.7874 0.5842)
					(thickness 0.1524)
				)
			)
		)
		(property "Value" "VAL*"
			(at 0.02032 2.13233 180)
			(unlocked yes)
			(layer "F.Fab")
			(hide yes)
			(effects
				(font
					(size 0.7874 0.5842)
					(thickness 0.1524)
				)
			)
		)
		(property "Device Type" "RESISTOR-G155-11001-01,1KOHM,1%"
			(at 0.008382 1.210564 180)
			(unlocked yes)
			(layer "F.Fab")
			(hide yes)
			(effects
				(font
					(size 0.7874 0.5842)
					(thickness 0.1524)
				)
			)
		)
		(property "User Part Number" "PARTNUM*"
			(at 0.02032 4.024884 180)
			(unlocked yes)
			(layer "Cmts.User")
			(hide yes)
			(effects
				(font
					(size 0.7874 0.5842)
					(thickness 0.1524)
				)
			)
		)
		(property "Tolerance" "TOL*"
			(at 0.044704 3.05435 180)
			(unlocked yes)
			(layer "Cmts.User")
			(hide yes)
			(effects
				(font
					(size 0.7874 0.5842)
					(thickness 0.1524)
				)
			)
		)
		(duplicate_pad_numbers_are_jumpers no)
		(fp_line
			(start 1.143 0.5588)
			(end 1.143 -0.5588)
			(stroke
				(width 0.1)
				(type default)
			)
			(layer "F.SilkS")
		)
		(fp_line
			(start 1.143 -0.5588)
			(end -1.143 -0.5588)
			(stroke
				(width 0.1)
				(type default)
			)
			(layer "F.SilkS")
		)
		(fp_line
			(start -1.143 0.5588)
			(end 1.143 0.5588)
			(stroke
				(width 0.1)
				(type default)
			)
			(layer "F.SilkS")
		)
		(fp_line
			(start -1.143 -0.5588)
			(end -1.143 0.5588)
			(stroke
				(width 0.1)
				(type default)
			)
			(layer "F.SilkS")
		)
		(fp_rect
			(start 1.143 -0.5588)
			(end -1.143 0.5588)
			(stroke
				(width 0)
				(type default)
			)
			(fill no)
			(layer "F.CrtYd")
		)
		(fp_line
			(start 0.508 0.3048)
			(end 0.508 -0.3048)
			(stroke
				(width 0.1)
				(type default)
			)
			(layer "F.Fab")
		)
		(fp_line
			(start 0.508 -0.3048)
			(end -0.508 -0.3048)
			(stroke
				(width 0.1)
				(type default)
			)
			(layer "F.Fab")
		)
		(fp_line
			(start -0.508 0.3048)
			(end 0.508 0.3048)
			(stroke
				(width 0.1)
				(type default)
			)
			(layer "F.Fab")
		)
		(fp_line
			(start -0.508 -0.3048)
			(end -0.508 0.3048)
			(stroke
				(width 0.1)
				(type default)
			)
			(layer "F.Fab")
		)
		(pad "1" smd rect
			(at -0.5334 0 180)
			(size 0.7112 0.6096)
			(layers "F.Cu" "F.Mask" "F.Paste")
			(net "UNNAMED_9_BNO080LGA28_I29_PS0")
		)
		(pad "2" smd rect
			(at 0.5334 0 180)
			(size 0.7112 0.6096)
			(layers "F.Cu" "F.Mask" "F.Paste")
			(net "SG")
		)
		(zone
			(layer "F.Cu")
			(hatch none 0.5)
			(connect_pads
				(clearance 0)
			)
			(min_thickness 0.25)
			(keepout
				(tracks allowed)
				(vias not_allowed)
				(pads allowed)
				(copperpour not_allowed)
				(footprints allowed)
			)
			(placement
				(enabled no)
				(sheetname "")
			)
			(fill
				(thermal_gap 0.5)
				(thermal_bridge_width 0.5)
				(island_removal_mode 0)
			)
			(polygon
				(pts
					(xy 80.6958 -64.9478) (xy 80.8482 -64.9478) (xy 80.8482 -65.5574) (xy 80.6958 -65.5574)
				)
			)
		)
	)
	(footprint ""
		(layer "F.Cu")
		(at 43.815 -73.66 180)
		(property "Reference" "C307"
			(at -0.635 -1.18237 0)
			(unlocked yes)
			(layer "F.SilkS")
			(effects
				(font
					(size 0.7874 0.5842)
					(thickness 0.1524)
				)
			)
		)
		(property "Value" "VAL*"
			(at 0.193548 2.13614 180)
			(unlocked yes)
			(layer "F.Fab")
			(hide yes)
			(effects
				(font
					(size 0.7874 0.5842)
					(thickness 0.1524)
				)
			)
		)
		(property "User Part Number" "PARTNUM*"
			(at 0.216154 4.185666 180)
			(unlocked yes)
			(layer "Cmts.User")
			(hide yes)
			(effects
				(font
					(size 0.7874 0.5842)
					(thickness 0.1524)
				)
			)
		)
		(property "Device Type" "CAPACITOR-G104-0B103-EK,0.01UFA"
			(at 0.184404 1.180592 180)
			(unlocked yes)
			(layer "F.Fab")
			(hide yes)
			(effects
				(font
					(size 0.7874 0.5842)
					(thickness 0.1524)
				)
			)
		)
		(property "Tolerance" "TOL*"
			(at 0.216154 3.1496 180)
			(unlocked yes)
			(layer "Cmts.User")
			(hide yes)
			(effects
				(font
					(size 0.7874 0.5842)
					(thickness 0.1524)
				)
			)
		)
		(duplicate_pad_numbers_are_jumpers no)
		(fp_line
			(start 0.671322 0.4445)
			(end -0.671322 0.4445)
			(stroke
				(width 0.1)
				(type default)
			)
			(layer "F.SilkS")
		)
		(fp_line
			(start 0.671322 -0.4445)
			(end 0.671322 0.4445)
			(stroke
				(width 0.1)
				(type default)
			)
			(layer "F.SilkS")
		)
		(fp_line
			(start -0.671322 0.4445)
			(end -0.671322 -0.4445)
			(stroke
				(width 0.1)
				(type default)
			)
			(layer "F.SilkS")
		)
		(fp_line
			(start -0.671322 -0.4445)
			(end 0.671322 -0.4445)
			(stroke
				(width 0.1)
				(type default)
			)
			(layer "F.SilkS")
		)
		(fp_rect
			(start -0.671322 0.4445)
			(end 0.671322 -0.4445)
			(stroke
				(width 0)
				(type default)
			)
			(fill no)
			(layer "F.CrtYd")
		)
		(fp_line
			(start 0.31496 0.1651)
			(end 0.31496 -0.1651)
			(stroke
				(width 0.1)
				(type default)
			)
			(layer "F.Fab")
		)
		(fp_line
			(start 0.31496 -0.1651)
			(end -0.31496 -0.1651)
			(stroke
				(width 0.1)
				(type default)
			)
			(layer "F.Fab")
		)
		(fp_line
			(start -0.31496 0.1651)
			(end 0.31496 0.1651)
			(stroke
				(width 0.1)
				(type default)
			)
			(layer "F.Fab")
		)
		(fp_line
			(start -0.31496 -0.1651)
			(end -0.31496 0.1651)
			(stroke
				(width 0.1)
				(type default)
			)
			(layer "F.Fab")
		)
		(pad "1" smd rect
			(at -0.264922 0 180)
			(size 0.3048 0.381)
			(layers "F.Cu" "F.Mask" "F.Paste")
			(net "UNNAMED_525_CAPACITOR_I18_1")
		)
		(pad "2" smd rect
			(at 0.264922 0 180)
			(size 0.3048 0.381)
			(layers "F.Cu" "F.Mask" "F.Paste")
			(net "SG")
		)
		(zone
			(layer "F.Cu")
			(hatch none 0.5)
			(connect_pads
				(clearance 0)
			)
			(min_thickness 0.25)
			(keepout
				(tracks not_allowed)
				(vias allowed)
				(pads allowed)
				(copperpour not_allowed)
				(footprints allowed)
			)
			(placement
				(enabled no)
				(sheetname "")
			)
			(fill
				(thermal_gap 0.5)
				(thermal_bridge_width 0.5)
				(island_removal_mode 0)
			)
			(polygon
				(pts
					(xy 43.927522 -73.8505) (xy 43.702478 -73.8505) (xy 43.702478 -73.4695) (xy 43.927522 -73.4695)
				)
			)
		)
		(zone
			(layer "F.Cu")
			(hatch none 0.5)
			(connect_pads
				(clearance 0)
			)
			(min_thickness 0.25)
			(keepout
				(tracks allowed)
				(vias not_allowed)
				(pads allowed)
				(copperpour not_allowed)
				(footprints allowed)
			)
			(placement
				(enabled no)
				(sheetname "")
			)
			(fill
				(thermal_gap 0.5)
				(thermal_bridge_width 0.5)
				(island_removal_mode 0)
			)
			(polygon
				(pts
					(xy 43.927522 -73.4695) (xy 43.927522 -73.8505) (xy 43.702478 -73.8505) (xy 43.702478 -73.4695)
				)
			)
		)
	)
	(footprint ""
		(layer "F.Cu")
		(at 119.761 -19.939)
		(property "Reference" "R475"
			(at -0.127 1.18237 0)
			(unlocked yes)
			(layer "F.SilkS")
			(effects
				(font
					(size 0.7874 0.5842)
					(thickness 0.1524)
				)
			)
		)
		(property "Value" "VAL*"
			(at 0.02032 2.13233 0)
			(unlocked yes)
			(layer "F.Fab")
			(hide yes)
			(effects
				(font
					(size 0.7874 0.5842)
					(thickness 0.1524)
				)
			)
		)
		(property "Tolerance" "TOL*"
			(at 0.044704 3.05435 0)
			(unlocked yes)
			(layer "Cmts.User")
			(hide yes)
			(effects
				(font
					(size 0.7874 0.5842)
					(thickness 0.1524)
				)
			)
		)
		(property "User Part Number" "PARTNUM*"
			(at 0.02032 4.024884 0)
			(unlocked yes)
			(layer "Cmts.User")
			(hide yes)
			(effects
				(font
					(size 0.7874 0.5842)
					(thickness 0.1524)
				)
			)
		)
		(property "Device Type" "RESISTOR-G155-11003-01,100KOHMA"
			(at 0.008382 1.210564 0)
			(unlocked yes)
			(layer "F.Fab")
			(hide yes)
			(effects
				(font
					(size 0.7874 0.5842)
					(thickness 0.1524)
				)
			)
		)
		(duplicate_pad_numbers_are_jumpers no)
		(fp_line
			(start -1.143 -0.5588)
			(end -1.143 0.5588)
			(stroke
				(width 0.1)
				(type default)
			)
			(layer "F.SilkS")
		)
		(fp_line
			(start -1.143 0.5588)
			(end 1.143 0.5588)
			(stroke
				(width 0.1)
				(type default)
			)
			(layer "F.SilkS")
		)
		(fp_line
			(start 1.143 -0.5588)
			(end -1.143 -0.5588)
			(stroke
				(width 0.1)
				(type default)
			)
			(layer "F.SilkS")
		)
		(fp_line
			(start 1.143 0.5588)
			(end 1.143 -0.5588)
			(stroke
				(width 0.1)
				(type default)
			)
			(layer "F.SilkS")
		)
		(fp_poly
			(pts
				(xy -1.143 0.5588) (xy 1.143 0.5588) (xy 1.143 -0.5588) (xy -1.143 -0.5588)
			)
			(stroke
				(width 0)
				(type default)
			)
			(fill no)
			(layer "F.CrtYd")
		)
		(fp_line
			(start -0.508 -0.3048)
			(end -0.508 0.3048)
			(stroke
				(width 0.1)
				(type default)
			)
			(layer "F.Fab")
		)
		(fp_line
			(start -0.508 0.3048)
			(end 0.508 0.3048)
			(stroke
				(width 0.1)
				(type default)
			)
			(layer "F.Fab")
		)
		(fp_line
			(start 0.508 -0.3048)
			(end -0.508 -0.3048)
			(stroke
				(width 0.1)
				(type default)
			)
			(layer "F.Fab")
		)
		(fp_line
			(start 0.508 0.3048)
			(end 0.508 -0.3048)
			(stroke
				(width 0.1)
				(type default)
			)
			(layer "F.Fab")
		)
		(pad "1" smd rect
			(at -0.5334 0)
			(size 0.7112 0.6096)
			(layers "F.Cu" "F.Mask" "F.Paste")
			(net "XP3R3V_FPGA")
		)
		(pad "2" smd rect
			(at 0.5334 0)
			(size 0.7112 0.6096)
			(layers "F.Cu" "F.Mask" "F.Paste")
			(net "FPGA_PCA9546_I2C_SCL")
		)
		(zone
			(layer "F.Cu")
			(hatch none 0.5)
			(connect_pads
				(clearance 0)
			)
			(min_thickness 0.25)
			(keepout
				(tracks not_allowed)
				(vias allowed)
				(pads allowed)
				(copperpour not_allowed)
				(footprints allowed)
			)
			(placement
				(enabled no)
				(sheetname "")
			)
			(fill
				(thermal_gap 0.5)
				(thermal_bridge_width 0.5)
				(island_removal_mode 0)
			)
			(polygon
				(pts
					(xy 119.6848 -19.6342) (xy 119.8372 -19.6342) (xy 119.8372 -20.2438) (xy 119.6848 -20.2438)
				)
			)
		)
		(zone
			(layer "F.Cu")
			(hatch none 0.5)
			(connect_pads
				(clearance 0)
			)
			(min_thickness 0.25)
			(keepout
				(tracks allowed)
				(vias not_allowed)
				(pads allowed)
				(copperpour not_allowed)
				(footprints allowed)
			)
			(placement
				(enabled no)
				(sheetname "")
			)
			(fill
				(thermal_gap 0.5)
				(thermal_bridge_width 0.5)
				(island_removal_mode 0)
			)
			(polygon
				(pts
					(xy 119.6848 -19.6342) (xy 119.8372 -19.6342) (xy 119.8372 -20.2438) (xy 119.6848 -20.2438)
				)
			)
		)
	)
	(footprint ""
		(layer "F.Cu")
		(at 94.234 -68.834)
		(property "Reference" "R167"
			(at -28.067 -19.39163 0)
			(unlocked yes)
			(layer "F.SilkS")
			(effects
				(font
					(size 0.7874 0.5842)
					(thickness 0.1524)
				)
			)
		)
		(property "Value" "VAL*"
			(at 0.02032 2.13233 0)
			(unlocked yes)
			(layer "F.Fab")
			(hide yes)
			(effects
				(font
					(size 0.7874 0.5842)
					(thickness 0.1524)
				)
			)
		)
		(property "Tolerance" "TOL*"
			(at 0.044704 3.05435 0)
			(unlocked yes)
			(layer "Cmts.User")
			(hide yes)
			(effects
				(font
					(size 0.7874 0.5842)
					(thickness 0.1524)
				)
			)
		)
		(property "User Part Number" "PARTNUM*"
			(at 0.02032 4.024884 0)
			(unlocked yes)
			(layer "Cmts.User")
			(hide yes)
			(effects
				(font
					(size 0.7874 0.5842)
					(thickness 0.1524)
				)
			)
		)
		(property "Device Type" "RESISTOR-G155-14701-01,4.7KOHMA"
			(at 0.008382 1.210564 0)
			(unlocked yes)
			(layer "F.Fab")
			(hide yes)
			(effects
				(font
					(size 0.7874 0.5842)
					(thickness 0.1524)
				)
			)
		)
		(duplicate_pad_numbers_are_jumpers no)
		(fp_line
			(start -1.143 -0.5588)
			(end -1.143 0.5588)
			(stroke
				(width 0.1)
				(type default)
			)
			(layer "F.SilkS")
		)
		(fp_line
			(start -1.143 0.5588)
			(end 1.143 0.5588)
			(stroke
				(width 0.1)
				(type default)
			)
			(layer "F.SilkS")
		)
		(fp_line
			(start 1.143 -0.5588)
			(end -1.143 -0.5588)
			(stroke
				(width 0.1)
				(type default)
			)
			(layer "F.SilkS")
		)
		(fp_line
			(start 1.143 0.5588)
			(end 1.143 -0.5588)
			(stroke
				(width 0.1)
				(type default)
			)
			(layer "F.SilkS")
		)
		(fp_poly
			(pts
				(xy -1.143 0.5588) (xy 1.143 0.5588) (xy 1.143 -0.5588) (xy -1.143 -0.5588)
			)
			(stroke
				(width 0)
				(type default)
			)
			(fill no)
			(layer "F.CrtYd")
		)
		(fp_line
			(start -0.508 -0.3048)
			(end -0.508 0.3048)
			(stroke
				(width 0.1)
				(type default)
			)
			(layer "F.Fab")
		)
		(fp_line
			(start -0.508 0.3048)
			(end 0.508 0.3048)
			(stroke
				(width 0.1)
				(type default)
			)
			(layer "F.Fab")
		)
		(fp_line
			(start 0.508 -0.3048)
			(end -0.508 -0.3048)
			(stroke
				(width 0.1)
				(type default)
			)
			(layer "F.Fab")
		)
		(fp_line
			(start 0.508 0.3048)
			(end 0.508 -0.3048)
			(stroke
				(width 0.1)
				(type default)
			)
			(layer "F.Fab")
		)
		(pad "1" smd rect
			(at -0.5334 0)
			(size 0.7112 0.6096)
			(layers "F.Cu" "F.Mask" "F.Paste")
			(net "XP3R3V_FPGA")
		)
		(pad "2" smd rect
			(at 0.5334 0)
			(size 0.7112 0.6096)
			(layers "F.Cu" "F.Mask" "F.Paste")
			(net "FPGA_IN_RST_DLY_N")
		)
		(zone
			(layer "F.Cu")
			(hatch none 0.5)
			(connect_pads
				(clearance 0)
			)
			(min_thickness 0.25)
			(keepout
				(tracks allowed)
				(vias not_allowed)
				(pads allowed)
				(copperpour not_allowed)
				(footprints allowed)
			)
			(placement
				(enabled no)
				(sheetname "")
			)
			(fill
				(thermal_gap 0.5)
				(thermal_bridge_width 0.5)
				(island_removal_mode 0)
			)
			(polygon
				(pts
					(xy 94.1578 -68.5292) (xy 94.3102 -68.5292) (xy 94.3102 -69.1388) (xy 94.1578 -69.1388)
				)
			)
		)
		(zone
			(layer "F.Cu")
			(hatch none 0.5)
			(connect_pads
				(clearance 0)
			)
			(min_thickness 0.25)
			(keepout
				(tracks not_allowed)
				(vias allowed)
				(pads allowed)
				(copperpour not_allowed)
				(footprints allowed)
			)
			(placement
				(enabled no)
				(sheetname "")
			)
			(fill
				(thermal_gap 0.5)
				(thermal_bridge_width 0.5)
				(island_removal_mode 0)
			)
			(polygon
				(pts
					(xy 94.1578 -68.5292) (xy 94.3102 -68.5292) (xy 94.3102 -69.1388) (xy 94.1578 -69.1388)
				)
			)
		)
	)
	(footprint ""
		(layer "F.Cu")
		(at 80.3148 -84.201 180)
		(property "Reference" "U4"
			(at 0.3048 3.52933 0)
			(unlocked yes)
			(layer "F.SilkS")
			(effects
				(font
					(size 0.7874 0.5842)
					(thickness 0.1524)
				)
			)
		)
		(property "Value" ""
			(at 0 0 180)
			(layer "F.Fab")
			(effects
				(font
					(size 1.27 1.27)
				)
			)
		)
		(property "Device Type" "PCA9546APW_TSSOP16-G223-10280-A"
			(at 0 0.924306 180)
			(unlocked yes)
			(layer "F.Fab")
			(hide yes)
			(effects
				(font
					(size 0.7874 0.5842)
					(thickness 0.1524)
				)
			)
		)
		(property "User Part Number" "PARTNUM*"
			(at 0 1.940306 180)
			(unlocked yes)
			(layer "Cmts.User")
			(hide yes)
			(effects
				(font
					(size 0.7874 0.5842)
					(thickness 0.1524)
				)
			)
		)
		(duplicate_pad_numbers_are_jumpers no)
		(fp_line
			(start 4.0767 2.7559)
			(end -4.0767 2.7559)
			(stroke
				(width 0.1)
				(type default)
			)
			(layer "F.SilkS")
		)
		(fp_line
			(start 4.0767 -2.7559)
			(end 4.0767 2.7559)
			(stroke
				(width 0.1)
				(type default)
			)
			(layer "F.SilkS")
		)
		(fp_line
			(start -4.0767 2.7559)
			(end -4.0767 -2.7559)
			(stroke
				(width 0.1)
				(type default)
			)
			(layer "F.SilkS")
		)
		(fp_line
			(start -4.0767 -2.7559)
			(end 4.0767 -2.7559)
			(stroke
				(width 0.1)
				(type default)
			)
			(layer "F.SilkS")
		)
		(fp_poly
			(pts
				(arc
					(start -5.1435 -2.2225)
					(mid -4.3815 -2.2225)
					(end -5.1435 -2.2225)
				)
			)
			(stroke
				(width 0)
				(type default)
			)
			(fill yes)
			(layer "F.SilkS")
		)
		(fp_rect
			(start -4.3307 3.0099)
			(end 4.3307 -3.0099)
			(stroke
				(width 0)
				(type default)
			)
			(fill no)
			(layer "F.CrtYd")
		)
		(fp_line
			(start 2.1971 2.5019)
			(end -2.1971 2.5019)
			(stroke
				(width 0.1)
				(type default)
			)
			(layer "F.Fab")
		)
		(fp_line
			(start 2.1971 -2.5019)
			(end 2.1971 2.5019)
			(stroke
				(width 0.1)
				(type default)
			)
			(layer "F.Fab")
		)
		(fp_line
			(start -2.1971 2.5019)
			(end -2.1971 -2.5019)
			(stroke
				(width 0.1)
				(type default)
			)
			(layer "F.Fab")
		)
		(fp_line
			(start -2.1971 -2.5019)
			(end 2.1971 -2.5019)
			(stroke
				(width 0.1)
				(type default)
			)
			(layer "F.Fab")
		)
		(fp_poly
			(pts
				(arc
					(start -1.914652 -1.942084)
					(mid -1.114044 -1.941576)
					(end -1.914652 -1.942084)
				)
			)
			(stroke
				(width 0)
				(type default)
			)
			(fill yes)
			(layer "F.Fab")
		)
		(fp_text user "9"
			(at 4.5466 2.31267 180)
			(unlocked yes)
			(layer "F.SilkS")
			(effects
				(font
					(size 0.7874 0.5842)
					(thickness 0.1524)
				)
			)
		)
		(fp_text user "16"
			(at 2.8448 -3.72237 0)
			(unlocked yes)
			(layer "F.SilkS")
			(effects
				(font
					(size 0.7874 0.5842)
					(thickness 0.1524)
				)
			)
		)
		(fp_text user "8"
			(at -4.6482 2.11963 0)
			(unlocked yes)
			(layer "F.SilkS")
			(effects
				(font
					(size 0.7874 0.5842)
					(thickness 0.1524)
				)
			)
		)
		(fp_text user "16"
			(at 3.0988 -2.43967 0)
			(unlocked yes)
			(layer "F.Fab")
			(effects
				(font
					(size 0.7874 0.5842)
					(thickness 0.1524)
				)
			)
		)
		(fp_text user "9"
			(at 2.9718 2.25933 0)
			(unlocked yes)
			(layer "F.Fab")
			(effects
				(font
					(size 0.7874 0.5842)
					(thickness 0.1524)
				)
			)
		)
		(fp_text user "8"
			(at -2.7432 2.38633 0)
			(unlocked yes)
			(layer "F.Fab")
			(effects
				(font
					(size 0.7874 0.5842)
					(thickness 0.1524)
				)
			)
		)
		(pad "1" smd rect
			(at -3.0353 -2.275078 270)
			(size 0.3556 1.5748)
			(layers "F.Cu" "F.Mask" "F.Paste")
			(net "UNNAMED_5_PCA9546APWTSSOP16_I33")
		)
		(pad "2" smd rect
			(at -3.0353 -1.625092 270)
			(size 0.3556 1.5748)
			(layers "F.Cu" "F.Mask" "F.Paste")
			(net "UNNAMED_5_PCA9546APWTSSOP16_I_1")
		)
		(pad "3" smd rect
			(at -3.0353 -0.975106 270)
			(size 0.3556 1.5748)
			(layers "F.Cu" "F.Mask" "F.Paste")
			(net "PCA9546_RST_N")
		)
		(pad "4" smd rect
			(at -3.0353 -0.32512 270)
			(size 0.3556 1.5748)
			(layers "F.Cu" "F.Mask" "F.Paste")
			(net "LM75B_I2C_SDA")
		)
		(pad "5" smd rect
			(at -3.0353 0.32512 270)
			(size 0.3556 1.5748)
			(layers "F.Cu" "F.Mask" "F.Paste")
			(net "LM75B_I2C_SCL")
		)
		(pad "6" smd rect
			(at -3.0353 0.975106 270)
			(size 0.3556 1.5748)
			(layers "F.Cu" "F.Mask" "F.Paste")
			(net "SHT3X_I2C_SDA")
		)
		(pad "7" smd rect
			(at -3.0353 1.625092 270)
			(size 0.3556 1.5748)
			(layers "F.Cu" "F.Mask" "F.Paste")
			(net "SHT3X_I2C_SCL")
		)
		(pad "8" smd rect
			(at -3.0353 2.275078 270)
			(size 0.3556 1.5748)
			(layers "F.Cu" "F.Mask" "F.Paste")
			(net "SG")
		)
		(pad "9" smd rect
			(at 3.0353 2.275078 270)
			(size 0.3556 1.5748)
			(layers "F.Cu" "F.Mask" "F.Paste")
			(net "ICP10100_I2C_SDA")
		)
		(pad "10" smd rect
			(at 3.0353 1.625092 270)
			(size 0.3556 1.5748)
			(layers "F.Cu" "F.Mask" "F.Paste")
			(net "ICP10100_I2C_SCL")
		)
		(pad "11" smd rect
			(at 3.0353 0.975106 270)
			(size 0.3556 1.5748)
			(layers "F.Cu" "F.Mask" "F.Paste")
			(net "BNO080_I2C_SDA")
		)
		(pad "12" smd rect
			(at 3.0353 0.32512 270)
			(size 0.3556 1.5748)
			(layers "F.Cu" "F.Mask" "F.Paste")
			(net "BNO080_I2C_SCL")
		)
		(pad "13" smd rect
			(at 3.0353 -0.32512 270)
			(size 0.3556 1.5748)
			(layers "F.Cu" "F.Mask" "F.Paste")
			(net "UNNAMED_5_PCA9546APWTSSOP16_I_2")
		)
		(pad "14" smd rect
			(at 3.0353 -0.975106 270)
			(size 0.3556 1.5748)
			(layers "F.Cu" "F.Mask" "F.Paste")
			(net "R_PCA9546_I2C_SCL")
		)
		(pad "15" smd rect
			(at 3.0353 -1.625092 270)
			(size 0.3556 1.5748)
			(layers "F.Cu" "F.Mask" "F.Paste")
			(net "R_PCA9546_I2C_SDA")
		)
		(pad "16" smd rect
			(at 3.0353 -2.275078 270)
			(size 0.3556 1.5748)
			(layers "F.Cu" "F.Mask" "F.Paste")
			(net "VDD_PCA9546A")
		)
	)
	(footprint ""
		(layer "F.Cu")
		(at 138.050016 -107.849924 -90)
		(property "Reference" "DS1"
			(at -0.100076 1.866646 90)
			(unlocked yes)
			(layer "F.SilkS")
			(effects
				(font
					(size 0.7874 0.5842)
					(thickness 0.1524)
				)
			)
		)
		(property "Value" ""
			(at 0 0 270)
			(layer "F.Fab")
			(effects
				(font
					(size 1.27 1.27)
				)
			)
		)
		(property "User Part Number" "PARTNUM*"
			(at 0.1778 2.422881 270)
			(unlocked yes)
			(layer "Cmts.User")
			(hide yes)
			(effects
				(font
					(size 0.786892 0.583946)
					(thickness 0.000001)
				)
			)
		)
		(property "Device Type" "OPTICAL-G170-10143-01"
			(at 0.1778 1.483081 270)
			(unlocked yes)
			(layer "F.Fab")
			(hide yes)
			(effects
				(font
					(size 0.786892 0.583946)
					(thickness 0.000001)
				)
			)
		)
		(duplicate_pad_numbers_are_jumpers no)
		(fp_line
			(start -1.3208 1.2192)
			(end -2.5908 1.2192)
			(stroke
				(width 0.1)
				(type default)
			)
			(layer "F.SilkS")
		)
		(fp_line
			(start -1.397508 0.704088)
			(end -1.397508 -0.704088)
			(stroke
				(width 0.1)
				(type default)
			)
			(layer "F.SilkS")
		)
		(fp_line
			(start 1.397508 0.704088)
			(end -1.397508 0.704088)
			(stroke
				(width 0.1)
				(type default)
			)
			(layer "F.SilkS")
		)
		(fp_line
			(start -1.9558 0.5842)
			(end -1.9558 1.8542)
			(stroke
				(width 0.1)
				(type default)
			)
			(layer "F.SilkS")
		)
		(fp_line
			(start -1.397508 -0.704088)
			(end 1.397508 -0.704088)
			(stroke
				(width 0.1)
				(type default)
			)
			(layer "F.SilkS")
		)
		(fp_line
			(start 1.397508 -0.704088)
			(end 1.397508 0.704088)
			(stroke
				(width 0.1)
				(type default)
			)
			(layer "F.SilkS")
		)
		(fp_rect
			(start 1.905508 0.704088)
			(end 1.397508 -0.704088)
			(stroke
				(width 0)
				(type default)
			)
			(fill yes)
			(layer "F.SilkS")
		)
		(fp_rect
			(start 1.905508 0.958088)
			(end -1.651508 -0.958088)
			(stroke
				(width 0)
				(type default)
			)
			(fill no)
			(layer "F.CrtYd")
		)
		(fp_line
			(start -1.3208 1.0922)
			(end -2.5908 1.0922)
			(stroke
				(width 0.1)
				(type default)
			)
			(layer "F.Fab")
		)
		(fp_line
			(start -1.9558 0.4572)
			(end -1.9558 1.7272)
			(stroke
				(width 0.1)
				(type default)
			)
			(layer "F.Fab")
		)
		(fp_line
			(start -0.850138 0.450088)
			(end 0.850138 0.450088)
			(stroke
				(width 0.1)
				(type default)
			)
			(layer "F.Fab")
		)
		(fp_line
			(start 0.850138 0.450088)
			(end 0.850138 -0.450088)
			(stroke
				(width 0.1)
				(type default)
			)
			(layer "F.Fab")
		)
		(fp_line
			(start -0.850138 -0.450088)
			(end -0.850138 0.450088)
			(stroke
				(width 0.1)
				(type default)
			)
			(layer "F.Fab")
		)
		(fp_line
			(start 0.850138 -0.450088)
			(end -0.850138 -0.450088)
			(stroke
				(width 0.1)
				(type default)
			)
			(layer "F.Fab")
		)
		(fp_rect
			(start 0.850138 0.450088)
			(end 0.342138 -0.450088)
			(stroke
				(width 0)
				(type default)
			)
			(fill yes)
			(layer "F.Fab")
		)
		(fp_text user "C"
			(at 1.582674 1.398016 0)
			(unlocked yes)
			(layer "F.SilkS")
			(effects
				(font
					(size 0.635 0.4064)
					(thickness 0.1524)
				)
			)
		)
		(fp_text user "A"
			(at -2.024126 0.382016 0)
			(unlocked yes)
			(layer "F.SilkS")
			(effects
				(font
					(size 0.635 0.4064)
					(thickness 0.1524)
				)
			)
		)
		(fp_text user "A"
			(at -1.700276 0.255016 0)
			(unlocked yes)
			(layer "F.Fab")
			(effects
				(font
					(size 0.7874 0.5842)
					(thickness 0.1524)
				)
			)
		)
		(fp_text user "C"
			(at 1.082294 -0.887984 0)
			(unlocked yes)
			(layer "F.Fab")
			(effects
				(font
					(size 0.7874 0.5842)
					(thickness 0.1524)
				)
			)
		)
		(pad "A" smd rect
			(at -0.749808 0 270)
			(size 0.7874 0.7874)
			(layers "F.Cu" "F.Mask" "F.Paste")
			(net "UNNAMED_14_OPTICAL_I12_A")
		)
		(pad "C" smd rect
			(at 0.749808 0 270)
			(size 0.7874 0.7874)
			(layers "F.Cu" "F.Mask" "F.Paste")
			(net "LED_DATOUT3")
		)
	)
	(footprint ""
		(layer "F.Cu")
		(at 12.1412 -65.786 90)
		(property "Reference" "R371"
			(at 5.334 -0.29083 90)
			(unlocked yes)
			(layer "F.SilkS")
			(effects
				(font
					(size 0.7874 0.5842)
					(thickness 0.1524)
				)
			)
		)
		(property "Value" "VAL*"
			(at 0.02032 2.13233 90)
			(unlocked yes)
			(layer "F.Fab")
			(hide yes)
			(effects
				(font
					(size 0.7874 0.5842)
					(thickness 0.1524)
				)
			)
		)
		(property "Tolerance" "TOL*"
			(at 0.044704 3.05435 90)
			(unlocked yes)
			(layer "Cmts.User")
			(hide yes)
			(effects
				(font
					(size 0.7874 0.5842)
					(thickness 0.1524)
				)
			)
		)
		(property "User Part Number" "PARTNUM*"
			(at 0.02032 4.024884 90)
			(unlocked yes)
			(layer "Cmts.User")
			(hide yes)
			(effects
				(font
					(size 0.7874 0.5842)
					(thickness 0.1524)
				)
			)
		)
		(property "Device Type" "RESISTOR-G155-149R9-01,49.9OHMA"
			(at 0.008382 1.210564 90)
			(unlocked yes)
			(layer "F.Fab")
			(hide yes)
			(effects
				(font
					(size 0.7874 0.5842)
					(thickness 0.1524)
				)
			)
		)
		(duplicate_pad_numbers_are_jumpers no)
		(fp_line
			(start 1.143 -0.5588)
			(end -1.143 -0.5588)
			(stroke
				(width 0.1)
				(type default)
			)
			(layer "F.SilkS")
		)
		(fp_line
			(start -1.143 -0.5588)
			(end -1.143 0.5588)
			(stroke
				(width 0.1)
				(type default)
			)
			(layer "F.SilkS")
		)
		(fp_line
			(start 1.143 0.5588)
			(end 1.143 -0.5588)
			(stroke
				(width 0.1)
				(type default)
			)
			(layer "F.SilkS")
		)
		(fp_line
			(start -1.143 0.5588)
			(end 1.143 0.5588)
			(stroke
				(width 0.1)
				(type default)
			)
			(layer "F.SilkS")
		)
		(fp_poly
			(pts
				(xy -1.143 0.5588) (xy 1.143 0.5588) (xy 1.143 -0.5588) (xy -1.143 -0.5588)
			)
			(stroke
				(width 0)
				(type default)
			)
			(fill no)
			(layer "F.CrtYd")
		)
		(fp_line
			(start 0.508 -0.3048)
			(end -0.508 -0.3048)
			(stroke
				(width 0.1)
				(type default)
			)
			(layer "F.Fab")
		)
		(fp_line
			(start -0.508 -0.3048)
			(end -0.508 0.3048)
			(stroke
				(width 0.1)
				(type default)
			)
			(layer "F.Fab")
		)
		(fp_line
			(start 0.508 0.3048)
			(end 0.508 -0.3048)
			(stroke
				(width 0.1)
				(type default)
			)
			(layer "F.Fab")
		)
		(fp_line
			(start -0.508 0.3048)
			(end 0.508 0.3048)
			(stroke
				(width 0.1)
				(type default)
			)
			(layer "F.Fab")
		)
		(pad "1" smd rect
			(at -0.5334 0 90)
			(size 0.7112 0.6096)
			(layers "F.Cu" "F.Mask" "F.Paste")
			(net "BF_ANT1_IN")
		)
		(pad "2" smd rect
			(at 0.5334 0 90)
			(size 0.7112 0.6096)
			(layers "F.Cu" "F.Mask" "F.Paste")
			(net "ANT1_IN")
		)
		(zone
			(layer "F.Cu")
			(hatch none 0.5)
			(connect_pads
				(clearance 0)
			)
			(min_thickness 0.25)
			(keepout
				(tracks allowed)
				(vias not_allowed)
				(pads allowed)
				(copperpour not_allowed)
				(footprints allowed)
			)
			(placement
				(enabled no)
				(sheetname "")
			)
			(fill
				(thermal_gap 0.5)
				(thermal_bridge_width 0.5)
				(island_removal_mode 0)
			)
			(polygon
				(pts
					(xy 12.446 -65.7098) (xy 12.446 -65.8622) (xy 11.8364 -65.8622) (xy 11.8364 -65.7098)
				)
			)
		)
		(zone
			(layer "F.Cu")
			(hatch none 0.5)
			(connect_pads
				(clearance 0)
			)
			(min_thickness 0.25)
			(keepout
				(tracks not_allowed)
				(vias allowed)
				(pads allowed)
				(copperpour not_allowed)
				(footprints allowed)
			)
			(placement
				(enabled no)
				(sheetname "")
			)
			(fill
				(thermal_gap 0.5)
				(thermal_bridge_width 0.5)
				(island_removal_mode 0)
			)
			(polygon
				(pts
					(xy 12.446 -65.7098) (xy 12.446 -65.8622) (xy 11.8364 -65.8622) (xy 11.8364 -65.7098)
				)
			)
		)
	)
	(footprint ""
		(layer "F.Cu")
		(at 80.772 -61.8236)
		(property "Reference" "R306"
			(at -10.287 -19.51863 0)
			(unlocked yes)
			(layer "F.SilkS")
			(effects
				(font
					(size 0.7874 0.5842)
					(thickness 0.1524)
				)
			)
		)
		(property "Value" "VAL*"
			(at 0.02032 2.13233 0)
			(unlocked yes)
			(layer "F.Fab")
			(hide yes)
			(effects
				(font
					(size 0.7874 0.5842)
					(thickness 0.1524)
				)
			)
		)
		(property "Tolerance" "TOL*"
			(at 0.044704 3.05435 0)
			(unlocked yes)
			(layer "Cmts.User")
			(hide yes)
			(effects
				(font
					(size 0.7874 0.5842)
					(thickness 0.1524)
				)
			)
		)
		(property "User Part Number" "PARTNUM*"
			(at 0.02032 4.024884 0)
			(unlocked yes)
			(layer "Cmts.User")
			(hide yes)
			(effects
				(font
					(size 0.7874 0.5842)
					(thickness 0.1524)
				)
			)
		)
		(property "Device Type" "RESISTOR-G155-14701-01,4.7KOHMA"
			(at 0.008382 1.210564 0)
			(unlocked yes)
			(layer "F.Fab")
			(hide yes)
			(effects
				(font
					(size 0.7874 0.5842)
					(thickness 0.1524)
				)
			)
		)
		(duplicate_pad_numbers_are_jumpers no)
		(fp_line
			(start -1.143 -0.5588)
			(end -1.143 0.5588)
			(stroke
				(width 0.1)
				(type default)
			)
			(layer "F.SilkS")
		)
		(fp_line
			(start -1.143 0.5588)
			(end 1.143 0.5588)
			(stroke
				(width 0.1)
				(type default)
			)
			(layer "F.SilkS")
		)
		(fp_line
			(start 1.143 -0.5588)
			(end -1.143 -0.5588)
			(stroke
				(width 0.1)
				(type default)
			)
			(layer "F.SilkS")
		)
		(fp_line
			(start 1.143 0.5588)
			(end 1.143 -0.5588)
			(stroke
				(width 0.1)
				(type default)
			)
			(layer "F.SilkS")
		)
		(fp_rect
			(start -1.143 0.5588)
			(end 1.143 -0.5588)
			(stroke
				(width 0)
				(type default)
			)
			(fill no)
			(layer "F.CrtYd")
		)
		(fp_line
			(start -0.508 -0.3048)
			(end -0.508 0.3048)
			(stroke
				(width 0.1)
				(type default)
			)
			(layer "F.Fab")
		)
		(fp_line
			(start -0.508 0.3048)
			(end 0.508 0.3048)
			(stroke
				(width 0.1)
				(type default)
			)
			(layer "F.Fab")
		)
		(fp_line
			(start 0.508 -0.3048)
			(end -0.508 -0.3048)
			(stroke
				(width 0.1)
				(type default)
			)
			(layer "F.Fab")
		)
		(fp_line
			(start 0.508 0.3048)
			(end 0.508 -0.3048)
			(stroke
				(width 0.1)
				(type default)
			)
			(layer "F.Fab")
		)
		(pad "1" smd rect
			(at -0.5334 0)
			(size 0.7112 0.6096)
			(layers "F.Cu" "F.Mask" "F.Paste")
			(net "XP3R3V_FPGA")
		)
		(pad "2" smd rect
			(at 0.5334 0)
			(size 0.7112 0.6096)
			(layers "F.Cu" "F.Mask" "F.Paste")
			(net "UNNAMED_9_BNO080LGA28_I29_CLKSE")
		)
		(zone
			(layer "F.Cu")
			(hatch none 0.5)
			(connect_pads
				(clearance 0)
			)
			(min_thickness 0.25)
			(keepout
				(tracks allowed)
				(vias not_allowed)
				(pads allowed)
				(copperpour not_allowed)
				(footprints allowed)
			)
			(placement
				(enabled no)
				(sheetname "")
			)
			(fill
				(thermal_gap 0.5)
				(thermal_bridge_width 0.5)
				(island_removal_mode 0)
			)
			(polygon
				(pts
					(xy 80.6958 -61.5188) (xy 80.8482 -61.5188) (xy 80.8482 -62.1284) (xy 80.6958 -62.1284)
				)
			)
		)
	)
	(footprint ""
		(layer "F.Cu")
		(at 55.88 -131.572)
		(property "Reference" "SP71"
			(at 0 0 0)
			(layer "F.SilkS")
			(hide yes)
			(effects
				(font
					(size 1.27 1.27)
				)
			)
		)
		(property "Value" ""
			(at 0 0 0)
			(layer "F.Fab")
			(effects
				(font
					(size 1.27 1.27)
				)
			)
		)
		(duplicate_pad_numbers_are_jumpers no)
	)
	(footprint ""
		(layer "F.Cu")
		(at 120.346978 -38.323266)
		(property "Reference" "TP133"
			(at 0 0 0)
			(layer "F.SilkS")
			(hide yes)
			(effects
				(font
					(size 1.27 1.27)
				)
			)
		)
		(property "Value" ""
			(at 0 0 0)
			(layer "F.Fab")
			(effects
				(font
					(size 1.27 1.27)
				)
			)
		)
		(property "Device Type" "TP_PIONT-TP010CT020B030_PTH-TPA"
			(at -1.341882 0.996696 0)
			(unlocked yes)
			(layer "F.Fab")
			(hide yes)
			(effects
				(font
					(size 0.7874 0.5842)
					(thickness 0.1524)
				)
				(justify left)
			)
		)
		(duplicate_pad_numbers_are_jumpers no)
		(fp_poly
			(pts
				(arc
					(start 0.889 0)
					(mid -0.889 0)
					(end 0.889 0)
				)
			)
			(stroke
				(width 0)
				(type default)
			)
			(fill no)
			(layer "B.CrtYd")
		)
		(fp_poly
			(pts
				(arc
					(start 0.889 0)
					(mid -0.889 0)
					(end 0.889 0)
				)
			)
			(stroke
				(width 0)
				(type default)
			)
			(fill no)
			(layer "F.CrtYd")
		)
		(pad "1" thru_hole circle
			(at 0 0)
			(size 0.508 0.508)
			(drill 0.254)
			(layers "*.Cu" "*.Mask")
			(remove_unused_layers no)
			(net "IO_L20N_34")
			(clearance 0.1016)
			(padstack
				(mode front_inner_back)
				(layer "Inner"
					(shape circle)
					(size 0.508 0.508)
					(clearance 0.1016)
				)
				(layer "B.Cu"
					(shape circle)
					(size 0.762 0.762)
					(clearance -0.0254)
				)
			)
		)
	)
	(footprint ""
		(layer "F.Cu")
		(at 145.8214 -91.8718 180)
		(property "Reference" "R7"
			(at 0.2794 -8.47217 0)
			(unlocked yes)
			(layer "F.SilkS")
			(effects
				(font
					(size 0.7874 0.5842)
					(thickness 0.1524)
				)
			)
		)
		(property "Value" "VAL*"
			(at 0.02032 2.13233 180)
			(unlocked yes)
			(layer "F.Fab")
			(hide yes)
			(effects
				(font
					(size 0.7874 0.5842)
					(thickness 0.1524)
				)
			)
		)
		(property "Device Type" "RESISTOR-G155-100R0-J0,0OHM,-"
			(at 0.008382 1.210564 180)
			(unlocked yes)
			(layer "F.Fab")
			(hide yes)
			(effects
				(font
					(size 0.7874 0.5842)
					(thickness 0.1524)
				)
			)
		)
		(property "User Part Number" "PARTNUM*"
			(at 0.02032 4.024884 180)
			(unlocked yes)
			(layer "Cmts.User")
			(hide yes)
			(effects
				(font
					(size 0.7874 0.5842)
					(thickness 0.1524)
				)
			)
		)
		(property "Tolerance" "TOL*"
			(at 0.044704 3.05435 180)
			(unlocked yes)
			(layer "Cmts.User")
			(hide yes)
			(effects
				(font
					(size 0.7874 0.5842)
					(thickness 0.1524)
				)
			)
		)
		(duplicate_pad_numbers_are_jumpers no)
		(fp_line
			(start 1.143 0.5588)
			(end 1.143 -0.5588)
			(stroke
				(width 0.1)
				(type default)
			)
			(layer "F.SilkS")
		)
		(fp_line
			(start 1.143 -0.5588)
			(end -1.143 -0.5588)
			(stroke
				(width 0.1)
				(type default)
			)
			(layer "F.SilkS")
		)
		(fp_line
			(start -1.143 0.5588)
			(end 1.143 0.5588)
			(stroke
				(width 0.1)
				(type default)
			)
			(layer "F.SilkS")
		)
		(fp_line
			(start -1.143 -0.5588)
			(end -1.143 0.5588)
			(stroke
				(width 0.1)
				(type default)
			)
			(layer "F.SilkS")
		)
		(fp_rect
			(start 1.143 -0.5588)
			(end -1.143 0.5588)
			(stroke
				(width 0)
				(type default)
			)
			(fill no)
			(layer "F.CrtYd")
		)
		(fp_line
			(start 0.508 0.3048)
			(end 0.508 -0.3048)
			(stroke
				(width 0.1)
				(type default)
			)
			(layer "F.Fab")
		)
		(fp_line
			(start 0.508 -0.3048)
			(end -0.508 -0.3048)
			(stroke
				(width 0.1)
				(type default)
			)
			(layer "F.Fab")
		)
		(fp_line
			(start -0.508 0.3048)
			(end 0.508 0.3048)
			(stroke
				(width 0.1)
				(type default)
			)
			(layer "F.Fab")
		)
		(fp_line
			(start -0.508 -0.3048)
			(end -0.508 0.3048)
			(stroke
				(width 0.1)
				(type default)
			)
			(layer "F.Fab")
		)
		(pad "1" smd rect
			(at -0.5334 0 180)
			(size 0.7112 0.6096)
			(layers "F.Cu" "F.Mask" "F.Paste")
			(net "SG")
		)
		(pad "2" smd rect
			(at 0.5334 0 180)
			(size 0.7112 0.6096)
			(layers "F.Cu" "F.Mask" "F.Paste")
			(net "UNNAMED_15_MP5022CGQVZQFN22_I_2")
		)
		(zone
			(layer "F.Cu")
			(hatch none 0.5)
			(connect_pads
				(clearance 0)
			)
			(min_thickness 0.25)
			(keepout
				(tracks allowed)
				(vias not_allowed)
				(pads allowed)
				(copperpour not_allowed)
				(footprints allowed)
			)
			(placement
				(enabled no)
				(sheetname "")
			)
			(fill
				(thermal_gap 0.5)
				(thermal_bridge_width 0.5)
				(island_removal_mode 0)
			)
			(polygon
				(pts
					(xy 145.7452 -91.567) (xy 145.8976 -91.567) (xy 145.8976 -92.1766) (xy 145.7452 -92.1766)
				)
			)
		)
	)
	(footprint ""
		(layer "F.Cu")
		(at 98.044 -96.774 180)
		(property "Reference" "R448"
			(at 1.143 2.75463 0)
			(unlocked yes)
			(layer "F.SilkS")
			(effects
				(font
					(size 0.7874 0.5842)
					(thickness 0.1524)
				)
			)
		)
		(property "Value" "VAL*"
			(at 0.02032 2.13233 180)
			(unlocked yes)
			(layer "F.Fab")
			(hide yes)
			(effects
				(font
					(size 0.7874 0.5842)
					(thickness 0.1524)
				)
			)
		)
		(property "Tolerance" "TOL*"
			(at 0.044704 3.05435 180)
			(unlocked yes)
			(layer "Cmts.User")
			(hide yes)
			(effects
				(font
					(size 0.7874 0.5842)
					(thickness 0.1524)
				)
			)
		)
		(property "User Part Number" "PARTNUM*"
			(at 0.02032 4.024884 180)
			(unlocked yes)
			(layer "Cmts.User")
			(hide yes)
			(effects
				(font
					(size 0.7874 0.5842)
					(thickness 0.1524)
				)
			)
		)
		(property "Device Type" "RESISTOR-G155-133R0-01,33OHM,1%"
			(at 0.008382 1.210564 180)
			(unlocked yes)
			(layer "F.Fab")
			(hide yes)
			(effects
				(font
					(size 0.7874 0.5842)
					(thickness 0.1524)
				)
			)
		)
		(duplicate_pad_numbers_are_jumpers no)
		(fp_line
			(start 1.143 0.5588)
			(end 1.143 -0.5588)
			(stroke
				(width 0.1)
				(type default)
			)
			(layer "F.SilkS")
		)
		(fp_line
			(start 1.143 -0.5588)
			(end -1.143 -0.5588)
			(stroke
				(width 0.1)
				(type default)
			)
			(layer "F.SilkS")
		)
		(fp_line
			(start -1.143 0.5588)
			(end 1.143 0.5588)
			(stroke
				(width 0.1)
				(type default)
			)
			(layer "F.SilkS")
		)
		(fp_line
			(start -1.143 -0.5588)
			(end -1.143 0.5588)
			(stroke
				(width 0.1)
				(type default)
			)
			(layer "F.SilkS")
		)
		(fp_poly
			(pts
				(xy -1.143 0.5588) (xy 1.143 0.5588) (xy 1.143 -0.5588) (xy -1.143 -0.5588)
			)
			(stroke
				(width 0)
				(type default)
			)
			(fill no)
			(layer "F.CrtYd")
		)
		(fp_line
			(start 0.508 0.3048)
			(end 0.508 -0.3048)
			(stroke
				(width 0.1)
				(type default)
			)
			(layer "F.Fab")
		)
		(fp_line
			(start 0.508 -0.3048)
			(end -0.508 -0.3048)
			(stroke
				(width 0.1)
				(type default)
			)
			(layer "F.Fab")
		)
		(fp_line
			(start -0.508 0.3048)
			(end 0.508 0.3048)
			(stroke
				(width 0.1)
				(type default)
			)
			(layer "F.Fab")
		)
		(fp_line
			(start -0.508 -0.3048)
			(end -0.508 0.3048)
			(stroke
				(width 0.1)
				(type default)
			)
			(layer "F.Fab")
		)
		(pad "1" smd rect
			(at -0.5334 0 180)
			(size 0.7112 0.6096)
			(layers "F.Cu" "F.Mask" "F.Paste")
			(net "MUX1_SEL")
		)
		(pad "2" smd rect
			(at 0.5334 0 180)
			(size 0.7112 0.6096)
			(layers "F.Cu" "F.Mask" "F.Paste")
			(net "FPGA_OUT_MUX1_SEL")
		)
		(zone
			(layer "F.Cu")
			(hatch none 0.5)
			(connect_pads
				(clearance 0)
			)
			(min_thickness 0.25)
			(keepout
				(tracks allowed)
				(vias not_allowed)
				(pads allowed)
				(copperpour not_allowed)
				(footprints allowed)
			)
			(placement
				(enabled no)
				(sheetname "")
			)
			(fill
				(thermal_gap 0.5)
				(thermal_bridge_width 0.5)
				(island_removal_mode 0)
			)
			(polygon
				(pts
					(xy 98.1202 -97.0788) (xy 97.9678 -97.0788) (xy 97.9678 -96.4692) (xy 98.1202 -96.4692)
				)
			)
		)
		(zone
			(layer "F.Cu")
			(hatch none 0.5)
			(connect_pads
				(clearance 0)
			)
			(min_thickness 0.25)
			(keepout
				(tracks not_allowed)
				(vias allowed)
				(pads allowed)
				(copperpour not_allowed)
				(footprints allowed)
			)
			(placement
				(enabled no)
				(sheetname "")
			)
			(fill
				(thermal_gap 0.5)
				(thermal_bridge_width 0.5)
				(island_removal_mode 0)
			)
			(polygon
				(pts
					(xy 98.1202 -97.0788) (xy 97.9678 -97.0788) (xy 97.9678 -96.4692) (xy 98.1202 -96.4692)
				)
			)
		)
	)
	(footprint ""
		(layer "F.Cu")
		(at 30.34538 -19.14144 180)
		(property "Reference" "R1992"
			(at 0.508 4.91363 0)
			(unlocked yes)
			(layer "F.SilkS")
			(effects
				(font
					(size 0.7874 0.5842)
					(thickness 0.1524)
				)
			)
		)
		(property "Value" "VAL*"
			(at 0.02032 2.13233 180)
			(unlocked yes)
			(layer "F.Fab")
			(hide yes)
			(effects
				(font
					(size 0.7874 0.5842)
					(thickness 0.1524)
				)
			)
		)
		(property "Tolerance" "TOL*"
			(at 0.044704 3.05435 180)
			(unlocked yes)
			(layer "Cmts.User")
			(hide yes)
			(effects
				(font
					(size 0.7874 0.5842)
					(thickness 0.1524)
				)
			)
		)
		(property "User Part Number" "PARTNUM*"
			(at 0.02032 4.024884 180)
			(unlocked yes)
			(layer "Cmts.User")
			(hide yes)
			(effects
				(font
					(size 0.7874 0.5842)
					(thickness 0.1524)
				)
			)
		)
		(property "Device Type" "RESISTOR-G155-14701-01,4.7KOHMA"
			(at 0.008382 1.210564 180)
			(unlocked yes)
			(layer "F.Fab")
			(hide yes)
			(effects
				(font
					(size 0.7874 0.5842)
					(thickness 0.1524)
				)
			)
		)
		(duplicate_pad_numbers_are_jumpers no)
		(fp_line
			(start 1.143 0.5588)
			(end 1.143 -0.5588)
			(stroke
				(width 0.1)
				(type default)
			)
			(layer "F.SilkS")
		)
		(fp_line
			(start 1.143 -0.5588)
			(end -1.143 -0.5588)
			(stroke
				(width 0.1)
				(type default)
			)
			(layer "F.SilkS")
		)
		(fp_line
			(start -1.143 0.5588)
			(end 1.143 0.5588)
			(stroke
				(width 0.1)
				(type default)
			)
			(layer "F.SilkS")
		)
		(fp_line
			(start -1.143 -0.5588)
			(end -1.143 0.5588)
			(stroke
				(width 0.1)
				(type default)
			)
			(layer "F.SilkS")
		)
		(fp_rect
			(start 1.143 -0.5588)
			(end -1.143 0.5588)
			(stroke
				(width 0)
				(type default)
			)
			(fill no)
			(layer "F.CrtYd")
		)
		(fp_line
			(start 0.508 0.3048)
			(end 0.508 -0.3048)
			(stroke
				(width 0.1)
				(type default)
			)
			(layer "F.Fab")
		)
		(fp_line
			(start 0.508 -0.3048)
			(end -0.508 -0.3048)
			(stroke
				(width 0.1)
				(type default)
			)
			(layer "F.Fab")
		)
		(fp_line
			(start -0.508 0.3048)
			(end 0.508 0.3048)
			(stroke
				(width 0.1)
				(type default)
			)
			(layer "F.Fab")
		)
		(fp_line
			(start -0.508 -0.3048)
			(end -0.508 0.3048)
			(stroke
				(width 0.1)
				(type default)
			)
			(layer "F.Fab")
		)
		(pad "1" smd rect
			(at -0.5334 0 180)
			(size 0.7112 0.6096)
			(layers "F.Cu" "F.Mask" "F.Paste")
			(net "XP3R3V_FPGA")
		)
		(pad "2" smd rect
			(at 0.5334 0 180)
			(size 0.7112 0.6096)
			(layers "F.Cu" "F.Mask" "F.Paste")
			(net "SN_EEPROM_WP")
		)
		(zone
			(layer "F.Cu")
			(hatch none 0.5)
			(connect_pads
				(clearance 0)
			)
			(min_thickness 0.25)
			(keepout
				(tracks allowed)
				(vias not_allowed)
				(pads allowed)
				(copperpour not_allowed)
				(footprints allowed)
			)
			(placement
				(enabled no)
				(sheetname "")
			)
			(fill
				(thermal_gap 0.5)
				(thermal_bridge_width 0.5)
				(island_removal_mode 0)
			)
			(polygon
				(pts
					(xy 30.26918 -18.83664) (xy 30.42158 -18.83664) (xy 30.42158 -19.44624) (xy 30.26918 -19.44624)
				)
			)
		)
	)
	(footprint ""
		(layer "F.Cu")
		(at 106.045 -87.503 -90)
		(property "Reference" "U40"
			(at 1.651 -3.21437 90)
			(unlocked yes)
			(layer "F.SilkS")
			(effects
				(font
					(size 0.7874 0.5842)
					(thickness 0.1524)
				)
			)
		)
		(property "Value" ""
			(at 0 0 270)
			(layer "F.Fab")
			(effects
				(font
					(size 1.27 1.27)
				)
			)
		)
		(property "Device Type" "NLASB3157DFT2G_SC88-G223-10187A"
			(at 0.1524 2.168906 270)
			(unlocked yes)
			(layer "F.Fab")
			(hide yes)
			(effects
				(font
					(size 0.7874 0.5842)
					(thickness 0.000001)
				)
			)
		)
		(property "User Part Number" "PARTNUM*"
			(at 0.127 3.184906 270)
			(unlocked yes)
			(layer "Cmts.User")
			(hide yes)
			(effects
				(font
					(size 0.7874 0.5842)
					(thickness 0.000001)
				)
			)
		)
		(duplicate_pad_numbers_are_jumpers no)
		(fp_line
			(start -1.50876 1.354074)
			(end -1.50876 -1.354074)
			(stroke
				(width 0.1)
				(type default)
			)
			(layer "F.SilkS")
		)
		(fp_line
			(start 1.50876 1.354074)
			(end -1.50876 1.354074)
			(stroke
				(width 0.1)
				(type default)
			)
			(layer "F.SilkS")
		)
		(fp_line
			(start -1.50876 -1.354074)
			(end 1.50876 -1.354074)
			(stroke
				(width 0.1)
				(type default)
			)
			(layer "F.SilkS")
		)
		(fp_line
			(start 1.50876 -1.354074)
			(end 1.50876 1.354074)
			(stroke
				(width 0.1)
				(type default)
			)
			(layer "F.SilkS")
		)
		(fp_poly
			(pts
				(arc
					(start -1.905 -2.159)
					(mid -1.905 -1.397)
					(end -1.905 -2.159)
				)
			)
			(stroke
				(width 0)
				(type default)
			)
			(fill yes)
			(layer "F.SilkS")
		)
		(fp_poly
			(pts
				(xy -1.76276 1.608074) (xy 1.76276 1.608074) (xy 1.76276 -1.608074) (xy -1.76276 -1.608074)
			)
			(stroke
				(width 0)
				(type default)
			)
			(fill no)
			(layer "F.CrtYd")
		)
		(fp_line
			(start -0.674878 1.100074)
			(end -0.674878 -1.100074)
			(stroke
				(width 0.1)
				(type default)
			)
			(layer "F.Fab")
		)
		(fp_line
			(start 0.674878 1.100074)
			(end -0.674878 1.100074)
			(stroke
				(width 0.1)
				(type default)
			)
			(layer "F.Fab")
		)
		(fp_line
			(start -0.674878 -1.100074)
			(end 0.674878 -1.100074)
			(stroke
				(width 0.1)
				(type default)
			)
			(layer "F.Fab")
		)
		(fp_line
			(start 0.674878 -1.100074)
			(end 0.674878 1.100074)
			(stroke
				(width 0.1)
				(type default)
			)
			(layer "F.Fab")
		)
		(fp_poly
			(pts
				(arc
					(start -2.159 -1.3716)
					(mid -2.159 -0.6096)
					(end -2.159 -1.3716)
				)
			)
			(stroke
				(width 0)
				(type default)
			)
			(fill yes)
			(layer "F.Fab")
		)
		(fp_text user "4"
			(at 2.06375 1.27 0)
			(unlocked yes)
			(layer "F.SilkS")
			(effects
				(font
					(size 0.635 0.4064)
					(thickness 0.1524)
				)
			)
		)
		(fp_text user "3"
			(at -2.00025 1.143 0)
			(unlocked yes)
			(layer "F.SilkS")
			(effects
				(font
					(size 0.635 0.4064)
					(thickness 0.1524)
				)
			)
		)
		(fp_text user "6"
			(at 2.06375 -1.27 0)
			(unlocked yes)
			(layer "F.SilkS")
			(effects
				(font
					(size 0.635 0.4064)
					(thickness 0.1524)
				)
			)
		)
		(fp_text user "4"
			(at 2.035048 0.924306 90)
			(unlocked yes)
			(layer "F.Fab")
			(effects
				(font
					(size 0.7874 0.5842)
					(thickness 0.1524)
				)
			)
		)
		(fp_text user "3"
			(at -1.995678 0.91313 90)
			(unlocked yes)
			(layer "F.Fab")
			(effects
				(font
					(size 0.7874 0.5842)
					(thickness 0.1524)
				)
			)
		)
		(fp_text user "6"
			(at 1.97104 -0.731774 90)
			(unlocked yes)
			(layer "F.Fab")
			(effects
				(font
					(size 0.7874 0.5842)
					(thickness 0.1524)
				)
			)
		)
		(pad "1" smd rect
			(at -0.94996 -0.649986 270)
			(size 0.6096 0.4318)
			(layers "F.Cu" "F.Mask" "F.Paste")
			(net "Net_786")
		)
		(pad "2" smd rect
			(at -0.94996 0 270)
			(size 0.6096 0.4318)
			(layers "F.Cu" "F.Mask" "F.Paste")
			(net "SG")
		)
		(pad "3" smd rect
			(at -0.94996 0.649986 270)
			(size 0.6096 0.4318)
			(layers "F.Cu" "F.Mask" "F.Paste")
			(net "FLASH_DQ3")
		)
		(pad "4" smd rect
			(at 0.94996 0.649986 270)
			(size 0.6096 0.4318)
			(layers "F.Cu" "F.Mask" "F.Paste")
			(net "FPGA_FLASH_DQ3")
		)
		(pad "5" smd rect
			(at 0.94996 0 270)
			(size 0.6096 0.4318)
			(layers "F.Cu" "F.Mask" "F.Paste")
			(net "XP3R3V_FPGA")
		)
		(pad "6" smd rect
			(at 0.94996 -0.649986 270)
			(size 0.6096 0.4318)
			(layers "F.Cu" "F.Mask" "F.Paste")
			(net "MUX2_SEL")
		)
	)
	(footprint ""
		(layer "F.Cu")
		(at 94.7166 -72.0598 90)
		(property "Reference" "C194"
			(at 19.8882 -27.49423 90)
			(unlocked yes)
			(layer "F.SilkS")
			(effects
				(font
					(size 0.7874 0.5842)
					(thickness 0.1524)
				)
			)
		)
		(property "Value" "VAL*"
			(at 0.0762 3.134106 90)
			(unlocked yes)
			(layer "F.Fab")
			(hide yes)
			(effects
				(font
					(size 0.7874 0.5842)
					(thickness 0.1524)
				)
			)
		)
		(property "Device Type" "CAPACITOR-G107-0F106-EM,10UF,2A"
			(at 0.0508 2.194306 90)
			(unlocked yes)
			(layer "F.Fab")
			(hide yes)
			(effects
				(font
					(size 0.7874 0.5842)
					(thickness 0.1524)
				)
			)
		)
		(property "User Part Number" "PARTNUM*"
			(at 0.1016 5.013706 90)
			(unlocked yes)
			(layer "Cmts.User")
			(hide yes)
			(effects
				(font
					(size 0.7874 0.5842)
					(thickness 0.1524)
				)
			)
		)
		(property "Tolerance" "TOL*"
			(at 0.0762 4.048506 90)
			(unlocked yes)
			(layer "Cmts.User")
			(hide yes)
			(effects
				(font
					(size 0.7874 0.5842)
					(thickness 0.1524)
				)
			)
		)
		(duplicate_pad_numbers_are_jumpers no)
		(fp_line
			(start 1.5748 -0.9398)
			(end -1.5748 -0.9398)
			(stroke
				(width 0.1)
				(type default)
			)
			(layer "F.SilkS")
		)
		(fp_line
			(start -1.5748 -0.9398)
			(end -1.5748 0.9398)
			(stroke
				(width 0.1)
				(type default)
			)
			(layer "F.SilkS")
		)
		(fp_line
			(start 1.5748 0.9398)
			(end 1.5748 -0.9398)
			(stroke
				(width 0.1)
				(type default)
			)
			(layer "F.SilkS")
		)
		(fp_line
			(start -1.5748 0.9398)
			(end 1.5748 0.9398)
			(stroke
				(width 0.1)
				(type default)
			)
			(layer "F.SilkS")
		)
		(fp_rect
			(start 1.5748 -0.9398)
			(end -1.5748 0.9398)
			(stroke
				(width 0)
				(type default)
			)
			(fill no)
			(layer "F.CrtYd")
		)
		(fp_line
			(start 1.016 -0.635)
			(end -1.016 -0.635)
			(stroke
				(width 0.1)
				(type default)
			)
			(layer "F.Fab")
		)
		(fp_line
			(start -1.016 -0.635)
			(end -1.016 0.635)
			(stroke
				(width 0.1)
				(type default)
			)
			(layer "F.Fab")
		)
		(fp_line
			(start 1.016 0.635)
			(end 1.016 -0.635)
			(stroke
				(width 0.1)
				(type default)
			)
			(layer "F.Fab")
		)
		(fp_line
			(start -1.016 0.635)
			(end 1.016 0.635)
			(stroke
				(width 0.1)
				(type default)
			)
			(layer "F.Fab")
		)
		(pad "1" smd rect
			(at -0.8382 0 90)
			(size 0.9652 1.3716)
			(layers "F.Cu" "F.Mask" "F.Paste")
			(net "XP1R2V_FPGA")
		)
		(pad "2" smd rect
			(at 0.8382 0 90)
			(size 0.9652 1.3716)
			(layers "F.Cu" "F.Mask" "F.Paste")
			(net "SG")
		)
		(zone
			(layer "F.Cu")
			(hatch none 0.5)
			(connect_pads
				(clearance 0)
			)
			(min_thickness 0.25)
			(keepout
				(tracks allowed)
				(vias not_allowed)
				(pads allowed)
				(copperpour not_allowed)
				(footprints allowed)
			)
			(placement
				(enabled no)
				(sheetname "")
			)
			(fill
				(thermal_gap 0.5)
				(thermal_bridge_width 0.5)
				(island_removal_mode 0)
			)
			(polygon
				(pts
					(xy 94.0816 -72.2884) (xy 94.0816 -71.8312) (xy 95.3516 -71.8312) (xy 95.3516 -72.2884)
				)
			)
		)
	)
	(footprint ""
		(layer "F.Cu")
		(at 143.256 -24.511 -90)
		(property "Reference" "C226"
			(at -3.429 0.08763 90)
			(unlocked yes)
			(layer "F.SilkS")
			(effects
				(font
					(size 0.7874 0.5842)
					(thickness 0.1524)
				)
			)
		)
		(property "Value" "VAL*"
			(at 0.0762 2.067306 270)
			(unlocked yes)
			(layer "F.Fab")
			(hide yes)
			(effects
				(font
					(size 0.7874 0.5842)
					(thickness 0.1524)
				)
			)
		)
		(property "Tolerance" "TOL*"
			(at 0.0762 3.032506 270)
			(unlocked yes)
			(layer "Cmts.User")
			(hide yes)
			(effects
				(font
					(size 0.7874 0.5842)
					(thickness 0.1524)
				)
			)
		)
		(property "User Part Number" "PARTNUM*"
			(at 0.1016 4.023106 270)
			(unlocked yes)
			(layer "Cmts.User")
			(hide yes)
			(effects
				(font
					(size 0.7874 0.5842)
					(thickness 0.1524)
				)
			)
		)
		(property "Device Type" "CAPACITOR-G105-0B104-EK,0.1UF,A"
			(at 0.0508 1.127506 270)
			(unlocked yes)
			(layer "F.Fab")
			(hide yes)
			(effects
				(font
					(size 0.7874 0.5842)
					(thickness 0.1524)
				)
			)
		)
		(duplicate_pad_numbers_are_jumpers no)
		(fp_line
			(start -1.143 0.5588)
			(end 1.143 0.5588)
			(stroke
				(width 0.1)
				(type default)
			)
			(layer "F.SilkS")
		)
		(fp_line
			(start 1.143 0.5588)
			(end 1.143 -0.5588)
			(stroke
				(width 0.1)
				(type default)
			)
			(layer "F.SilkS")
		)
		(fp_line
			(start -1.143 -0.5588)
			(end -1.143 0.5588)
			(stroke
				(width 0.1)
				(type default)
			)
			(layer "F.SilkS")
		)
		(fp_line
			(start 1.143 -0.5588)
			(end -1.143 -0.5588)
			(stroke
				(width 0.1)
				(type default)
			)
			(layer "F.SilkS")
		)
		(fp_rect
			(start -1.143 0.5588)
			(end 1.143 -0.5588)
			(stroke
				(width 0)
				(type default)
			)
			(fill no)
			(layer "F.CrtYd")
		)
		(fp_line
			(start -0.508 0.3048)
			(end 0.508 0.3048)
			(stroke
				(width 0.1)
				(type default)
			)
			(layer "F.Fab")
		)
		(fp_line
			(start 0.508 0.3048)
			(end 0.508 -0.3048)
			(stroke
				(width 0.1)
				(type default)
			)
			(layer "F.Fab")
		)
		(fp_line
			(start -0.508 -0.3048)
			(end -0.508 0.3048)
			(stroke
				(width 0.1)
				(type default)
			)
			(layer "F.Fab")
		)
		(fp_line
			(start 0.508 -0.3048)
			(end -0.508 -0.3048)
			(stroke
				(width 0.1)
				(type default)
			)
			(layer "F.Fab")
		)
		(pad "1" smd rect
			(at -0.5334 0 270)
			(size 0.7112 0.6096)
			(layers "F.Cu" "F.Mask" "F.Paste")
			(net "XP3R3V")
		)
		(pad "2" smd rect
			(at 0.5334 0 270)
			(size 0.7112 0.6096)
			(layers "F.Cu" "F.Mask" "F.Paste")
			(net "SG")
		)
		(zone
			(layer "F.Cu")
			(hatch none 0.5)
			(connect_pads
				(clearance 0)
			)
			(min_thickness 0.25)
			(keepout
				(tracks allowed)
				(vias not_allowed)
				(pads allowed)
				(copperpour not_allowed)
				(footprints allowed)
			)
			(placement
				(enabled no)
				(sheetname "")
			)
			(fill
				(thermal_gap 0.5)
				(thermal_bridge_width 0.5)
				(island_removal_mode 0)
			)
			(polygon
				(pts
					(xy 142.9512 -24.5872) (xy 142.9512 -24.4348) (xy 143.5608 -24.4348) (xy 143.5608 -24.5872)
				)
			)
		)
	)
	(footprint ""
		(layer "F.Cu")
		(at 124.587 -42.545 180)
		(property "Reference" "R288"
			(at -3.048 1.35763 0)
			(unlocked yes)
			(layer "F.SilkS")
			(effects
				(font
					(size 0.7874 0.5842)
					(thickness 0.1524)
				)
			)
		)
		(property "Value" "VAL*"
			(at 0.02032 2.13233 180)
			(unlocked yes)
			(layer "F.Fab")
			(hide yes)
			(effects
				(font
					(size 0.7874 0.5842)
					(thickness 0.1524)
				)
			)
		)
		(property "Tolerance" "TOL*"
			(at 0.044704 3.05435 180)
			(unlocked yes)
			(layer "Cmts.User")
			(hide yes)
			(effects
				(font
					(size 0.7874 0.5842)
					(thickness 0.1524)
				)
			)
		)
		(property "User Part Number" "PARTNUM*"
			(at 0.02032 4.024884 180)
			(unlocked yes)
			(layer "Cmts.User")
			(hide yes)
			(effects
				(font
					(size 0.7874 0.5842)
					(thickness 0.1524)
				)
			)
		)
		(property "Device Type" "RESISTOR-G155-14701-01,4.7KOHMA"
			(at 0.008382 1.210564 180)
			(unlocked yes)
			(layer "F.Fab")
			(hide yes)
			(effects
				(font
					(size 0.7874 0.5842)
					(thickness 0.1524)
				)
			)
		)
		(duplicate_pad_numbers_are_jumpers no)
		(fp_line
			(start 1.143 0.5588)
			(end 1.143 -0.5588)
			(stroke
				(width 0.1)
				(type default)
			)
			(layer "F.SilkS")
		)
		(fp_line
			(start 1.143 -0.5588)
			(end -1.143 -0.5588)
			(stroke
				(width 0.1)
				(type default)
			)
			(layer "F.SilkS")
		)
		(fp_line
			(start -1.143 0.5588)
			(end 1.143 0.5588)
			(stroke
				(width 0.1)
				(type default)
			)
			(layer "F.SilkS")
		)
		(fp_line
			(start -1.143 -0.5588)
			(end -1.143 0.5588)
			(stroke
				(width 0.1)
				(type default)
			)
			(layer "F.SilkS")
		)
		(fp_rect
			(start 1.143 0.5588)
			(end -1.143 -0.5588)
			(stroke
				(width 0)
				(type default)
			)
			(fill no)
			(layer "F.CrtYd")
		)
		(fp_line
			(start 0.508 0.3048)
			(end 0.508 -0.3048)
			(stroke
				(width 0.1)
				(type default)
			)
			(layer "F.Fab")
		)
		(fp_line
			(start 0.508 -0.3048)
			(end -0.508 -0.3048)
			(stroke
				(width 0.1)
				(type default)
			)
			(layer "F.Fab")
		)
		(fp_line
			(start -0.508 0.3048)
			(end 0.508 0.3048)
			(stroke
				(width 0.1)
				(type default)
			)
			(layer "F.Fab")
		)
		(fp_line
			(start -0.508 -0.3048)
			(end -0.508 0.3048)
			(stroke
				(width 0.1)
				(type default)
			)
			(layer "F.Fab")
		)
		(pad "1" smd rect
			(at -0.5334 0 180)
			(size 0.7112 0.6096)
			(layers "F.Cu" "F.Mask" "F.Paste")
			(net "SG")
		)
		(pad "2" smd rect
			(at 0.5334 0 180)
			(size 0.7112 0.6096)
			(layers "F.Cu" "F.Mask" "F.Paste")
			(net "FPGA_IN_MAC_BITEOUT")
		)
		(zone
			(layer "F.Cu")
			(hatch none 0.5)
			(connect_pads
				(clearance 0)
			)
			(min_thickness 0.25)
			(keepout
				(tracks allowed)
				(vias not_allowed)
				(pads allowed)
				(copperpour not_allowed)
				(footprints allowed)
			)
			(placement
				(enabled no)
				(sheetname "")
			)
			(fill
				(thermal_gap 0.5)
				(thermal_bridge_width 0.5)
				(island_removal_mode 0)
			)
			(polygon
				(pts
					(xy 124.5108 -42.8498) (xy 124.5108 -42.2402) (xy 124.6632 -42.2402) (xy 124.6632 -42.8498)
				)
			)
		)
	)
	(footprint ""
		(layer "F.Cu")
		(at 41.656 -132.461)
		(property "Reference" "SP36"
			(at 0 0 0)
			(layer "F.SilkS")
			(hide yes)
			(effects
				(font
					(size 1.27 1.27)
				)
			)
		)
		(property "Value" ""
			(at 0 0 0)
			(layer "F.Fab")
			(effects
				(font
					(size 1.27 1.27)
				)
			)
		)
		(duplicate_pad_numbers_are_jumpers no)
	)
	(footprint ""
		(layer "F.Cu")
		(at 90.2716 -44.868846 90)
		(property "Reference" "R266"
			(at -0.164846 -1.47193 90)
			(unlocked yes)
			(layer "F.SilkS")
			(effects
				(font
					(size 0.7874 0.5842)
					(thickness 0.1524)
				)
			)
		)
		(property "Value" "VAL*"
			(at 0.02032 2.13233 90)
			(unlocked yes)
			(layer "F.Fab")
			(hide yes)
			(effects
				(font
					(size 0.7874 0.5842)
					(thickness 0.1524)
				)
			)
		)
		(property "Device Type" "RESISTOR-G155-133R0-01,33OHM,1%"
			(at 0.008382 1.210564 90)
			(unlocked yes)
			(layer "F.Fab")
			(hide yes)
			(effects
				(font
					(size 0.7874 0.5842)
					(thickness 0.1524)
				)
			)
		)
		(property "User Part Number" "PARTNUM*"
			(at 0.02032 4.024884 90)
			(unlocked yes)
			(layer "Cmts.User")
			(hide yes)
			(effects
				(font
					(size 0.7874 0.5842)
					(thickness 0.1524)
				)
			)
		)
		(property "Tolerance" "TOL*"
			(at 0.044704 3.05435 90)
			(unlocked yes)
			(layer "Cmts.User")
			(hide yes)
			(effects
				(font
					(size 0.7874 0.5842)
					(thickness 0.1524)
				)
			)
		)
		(duplicate_pad_numbers_are_jumpers no)
		(fp_line
			(start 1.143 -0.5588)
			(end -1.143 -0.5588)
			(stroke
				(width 0.1)
				(type default)
			)
			(layer "F.SilkS")
		)
		(fp_line
			(start -1.143 -0.5588)
			(end -1.143 0.5588)
			(stroke
				(width 0.1)
				(type default)
			)
			(layer "F.SilkS")
		)
		(fp_line
			(start 1.143 0.5588)
			(end 1.143 -0.5588)
			(stroke
				(width 0.1)
				(type default)
			)
			(layer "F.SilkS")
		)
		(fp_line
			(start -1.143 0.5588)
			(end 1.143 0.5588)
			(stroke
				(width 0.1)
				(type default)
			)
			(layer "F.SilkS")
		)
		(fp_rect
			(start -1.143 -0.5588)
			(end 1.143 0.5588)
			(stroke
				(width 0)
				(type default)
			)
			(fill no)
			(layer "F.CrtYd")
		)
		(fp_line
			(start 0.508 -0.3048)
			(end -0.508 -0.3048)
			(stroke
				(width 0.1)
				(type default)
			)
			(layer "F.Fab")
		)
		(fp_line
			(start -0.508 -0.3048)
			(end -0.508 0.3048)
			(stroke
				(width 0.1)
				(type default)
			)
			(layer "F.Fab")
		)
		(fp_line
			(start 0.508 0.3048)
			(end 0.508 -0.3048)
			(stroke
				(width 0.1)
				(type default)
			)
			(layer "F.Fab")
		)
		(fp_line
			(start -0.508 0.3048)
			(end 0.508 0.3048)
			(stroke
				(width 0.1)
				(type default)
			)
			(layer "F.Fab")
		)
		(pad "1" smd rect
			(at -0.5334 0 90)
			(size 0.7112 0.6096)
			(layers "F.Cu" "F.Mask" "F.Paste")
			(net "RSVD_DBG_USB_MUX_SEL")
		)
		(pad "2" smd rect
			(at 0.5334 0 90)
			(size 0.7112 0.6096)
			(layers "F.Cu" "F.Mask" "F.Paste")
			(net "XP5R0V_USB_CONN_DET")
		)
		(zone
			(layer "F.Cu")
			(hatch none 0.5)
			(connect_pads
				(clearance 0)
			)
			(min_thickness 0.25)
			(keepout
				(tracks allowed)
				(vias not_allowed)
				(pads allowed)
				(copperpour not_allowed)
				(footprints allowed)
			)
			(placement
				(enabled no)
				(sheetname "")
			)
			(fill
				(thermal_gap 0.5)
				(thermal_bridge_width 0.5)
				(island_removal_mode 0)
			)
			(polygon
				(pts
					(xy 89.9668 -44.792646) (xy 90.5764 -44.792646) (xy 90.5764 -44.945046) (xy 89.9668 -44.945046)
				)
			)
		)
	)
	(footprint ""
		(layer "F.Cu")
		(at 47.244 -126.746)
		(property "Reference" "SP67"
			(at 0 0 0)
			(layer "F.SilkS")
			(hide yes)
			(effects
				(font
					(size 1.27 1.27)
				)
			)
		)
		(property "Value" ""
			(at 0 0 0)
			(layer "F.Fab")
			(effects
				(font
					(size 1.27 1.27)
				)
			)
		)
		(duplicate_pad_numbers_are_jumpers no)
	)
	(footprint ""
		(layer "F.Cu")
		(at 122.7074 -69.2912)
		(property "Reference" "TP40"
			(at -2.0066 -1.53543 0)
			(unlocked yes)
			(layer "F.SilkS")
			(effects
				(font
					(size 0.7874 0.5842)
					(thickness 0.1524)
				)
				(justify left)
			)
		)
		(property "Value" ""
			(at 0 0 0)
			(layer "F.Fab")
			(effects
				(font
					(size 1.27 1.27)
				)
			)
		)
		(property "Device Type" "TP_PIONT-TP010CT020B030_PTH-TPA"
			(at -1.341882 0.996696 0)
			(unlocked yes)
			(layer "F.Fab")
			(hide yes)
			(effects
				(font
					(size 0.7874 0.5842)
					(thickness 0.000001)
				)
				(justify left)
			)
		)
		(duplicate_pad_numbers_are_jumpers no)
		(fp_poly
			(pts
				(arc
					(start 0.889 0)
					(mid -0.889 0)
					(end 0.889 0)
				)
			)
			(stroke
				(width 0)
				(type default)
			)
			(fill no)
			(layer "B.CrtYd")
		)
		(fp_poly
			(pts
				(arc
					(start 0.889 0)
					(mid -0.889 0)
					(end 0.889 0)
				)
			)
			(stroke
				(width 0)
				(type default)
			)
			(fill no)
			(layer "F.CrtYd")
		)
		(pad "1" thru_hole circle
			(at 0 0)
			(size 0.508 0.508)
			(drill 0.254)
			(layers "*.Cu" "*.Mask")
			(remove_unused_layers no)
			(net "XP1R2V_FPGA_PG")
			(clearance 0.1016)
			(padstack
				(mode front_inner_back)
				(layer "Inner"
					(shape circle)
					(size 0.508 0.508)
					(clearance 0.1016)
				)
				(layer "B.Cu"
					(shape circle)
					(size 0.762 0.762)
					(clearance -0.0254)
				)
			)
		)
	)
	(footprint ""
		(layer "F.Cu")
		(at 135.001 -70.866 90)
		(property "Reference" "R182"
			(at 4.191 0.92837 90)
			(unlocked yes)
			(layer "F.SilkS")
			(effects
				(font
					(size 0.7874 0.5842)
					(thickness 0.1524)
				)
			)
		)
		(property "Value" "VAL*"
			(at 0.02032 2.13233 90)
			(unlocked yes)
			(layer "F.Fab")
			(hide yes)
			(effects
				(font
					(size 0.7874 0.5842)
					(thickness 0.1524)
				)
			)
		)
		(property "Device Type" "RESISTOR-G155-100R0-J0,0OHM,-"
			(at 0.008382 1.210564 90)
			(unlocked yes)
			(layer "F.Fab")
			(hide yes)
			(effects
				(font
					(size 0.7874 0.5842)
					(thickness 0.1524)
				)
			)
		)
		(property "User Part Number" "PARTNUM*"
			(at 0.02032 4.024884 90)
			(unlocked yes)
			(layer "Cmts.User")
			(hide yes)
			(effects
				(font
					(size 0.7874 0.5842)
					(thickness 0.1524)
				)
			)
		)
		(property "Tolerance" "TOL*"
			(at 0.044704 3.05435 90)
			(unlocked yes)
			(layer "Cmts.User")
			(hide yes)
			(effects
				(font
					(size 0.7874 0.5842)
					(thickness 0.1524)
				)
			)
		)
		(duplicate_pad_numbers_are_jumpers no)
		(fp_line
			(start 1.143 -0.5588)
			(end -1.143 -0.5588)
			(stroke
				(width 0.1)
				(type default)
			)
			(layer "F.SilkS")
		)
		(fp_line
			(start -1.143 -0.5588)
			(end -1.143 0.5588)
			(stroke
				(width 0.1)
				(type default)
			)
			(layer "F.SilkS")
		)
		(fp_line
			(start 1.143 0.5588)
			(end 1.143 -0.5588)
			(stroke
				(width 0.1)
				(type default)
			)
			(layer "F.SilkS")
		)
		(fp_line
			(start -1.143 0.5588)
			(end 1.143 0.5588)
			(stroke
				(width 0.1)
				(type default)
			)
			(layer "F.SilkS")
		)
		(fp_rect
			(start 1.143 0.5588)
			(end -1.143 -0.5588)
			(stroke
				(width 0)
				(type default)
			)
			(fill no)
			(layer "F.CrtYd")
		)
		(fp_line
			(start 0.508 -0.3048)
			(end -0.508 -0.3048)
			(stroke
				(width 0.1)
				(type default)
			)
			(layer "F.Fab")
		)
		(fp_line
			(start -0.508 -0.3048)
			(end -0.508 0.3048)
			(stroke
				(width 0.1)
				(type default)
			)
			(layer "F.Fab")
		)
		(fp_line
			(start 0.508 0.3048)
			(end 0.508 -0.3048)
			(stroke
				(width 0.1)
				(type default)
			)
			(layer "F.Fab")
		)
		(fp_line
			(start -0.508 0.3048)
			(end 0.508 0.3048)
			(stroke
				(width 0.1)
				(type default)
			)
			(layer "F.Fab")
		)
		(pad "1" smd rect
			(at -0.5334 0 90)
			(size 0.7112 0.6096)
			(layers "F.Cu" "F.Mask" "F.Paste")
			(net "XP1R8V_PG_R")
		)
		(pad "2" smd rect
			(at 0.5334 0 90)
			(size 0.7112 0.6096)
			(layers "F.Cu" "F.Mask" "F.Paste")
			(net "XP1R8V_FPGA_PG")
		)
		(zone
			(layer "F.Cu")
			(hatch none 0.5)
			(connect_pads
				(clearance 0)
			)
			(min_thickness 0.25)
			(keepout
				(tracks allowed)
				(vias not_allowed)
				(pads allowed)
				(copperpour not_allowed)
				(footprints allowed)
			)
			(placement
				(enabled no)
				(sheetname "")
			)
			(fill
				(thermal_gap 0.5)
				(thermal_bridge_width 0.5)
				(island_removal_mode 0)
			)
			(polygon
				(pts
					(xy 135.3058 -70.9422) (xy 134.6962 -70.9422) (xy 134.6962 -70.7898) (xy 135.3058 -70.7898)
				)
			)
		)
	)
	(footprint ""
		(layer "F.Cu")
		(at 120.396 -63.2206 90)
		(property "Reference" "C174"
			(at 3.8354 0.16637 90)
			(unlocked yes)
			(layer "F.SilkS")
			(effects
				(font
					(size 0.7874 0.5842)
					(thickness 0.1524)
				)
			)
		)
		(property "Value" "VAL*"
			(at 0.1016 3.769106 90)
			(unlocked yes)
			(layer "F.Fab")
			(hide yes)
			(effects
				(font
					(size 0.7874 0.5842)
					(thickness 0.1524)
				)
			)
		)
		(property "Device Type" "CAPACITOR-G109-0G107-BM,100UF,A"
			(at 0.0762 2.829306 90)
			(unlocked yes)
			(layer "F.Fab")
			(hide yes)
			(effects
				(font
					(size 0.7874 0.5842)
					(thickness 0.1524)
				)
			)
		)
		(property "User Part Number" "PARTNUM*"
			(at 0.2032 5.801106 90)
			(unlocked yes)
			(layer "Cmts.User")
			(hide yes)
			(effects
				(font
					(size 0.7874 0.5842)
					(thickness 0.1524)
				)
			)
		)
		(property "Tolerance" "TOL*"
			(at 0.127 4.734306 90)
			(unlocked yes)
			(layer "Cmts.User")
			(hide yes)
			(effects
				(font
					(size 0.7874 0.5842)
					(thickness 0.1524)
				)
			)
		)
		(duplicate_pad_numbers_are_jumpers no)
		(fp_line
			(start 2.159 -1.5748)
			(end 2.159 1.5748)
			(stroke
				(width 0.1)
				(type default)
			)
			(layer "F.SilkS")
		)
		(fp_line
			(start -2.159 -1.5748)
			(end 2.159 -1.5748)
			(stroke
				(width 0.1)
				(type default)
			)
			(layer "F.SilkS")
		)
		(fp_line
			(start 2.159 1.5748)
			(end -2.159 1.5748)
			(stroke
				(width 0.1)
				(type default)
			)
			(layer "F.SilkS")
		)
		(fp_line
			(start -2.159 1.5748)
			(end -2.159 -1.5748)
			(stroke
				(width 0.1)
				(type default)
			)
			(layer "F.SilkS")
		)
		(fp_rect
			(start -2.159 -1.5748)
			(end 2.159 1.5748)
			(stroke
				(width 0)
				(type default)
			)
			(fill no)
			(layer "F.CrtYd")
		)
		(fp_line
			(start 1.6002 -1.2446)
			(end -1.6002 -1.2446)
			(stroke
				(width 0.1)
				(type default)
			)
			(layer "F.Fab")
		)
		(fp_line
			(start -1.6002 -1.2446)
			(end -1.6002 1.2446)
			(stroke
				(width 0.1)
				(type default)
			)
			(layer "F.Fab")
		)
		(fp_line
			(start 1.6002 1.2446)
			(end 1.6002 -1.2446)
			(stroke
				(width 0.1)
				(type default)
			)
			(layer "F.Fab")
		)
		(fp_line
			(start -1.6002 1.2446)
			(end 1.6002 1.2446)
			(stroke
				(width 0.1)
				(type default)
			)
			(layer "F.Fab")
		)
		(pad "1" smd rect
			(at -1.3335 0 90)
			(size 1.143 2.6416)
			(layers "F.Cu" "F.Mask" "F.Paste")
			(net "XP3R3V_FPGA")
		)
		(pad "2" smd rect
			(at 1.3335 0 90)
			(size 1.143 2.6416)
			(layers "F.Cu" "F.Mask" "F.Paste")
			(net "SG")
		)
		(zone
			(layer "F.Cu")
			(hatch none 0.5)
			(connect_pads
				(clearance 0)
			)
			(min_thickness 0.25)
			(keepout
				(tracks allowed)
				(vias not_allowed)
				(pads allowed)
				(copperpour not_allowed)
				(footprints allowed)
			)
			(placement
				(enabled no)
				(sheetname "")
			)
			(fill
				(thermal_gap 0.5)
				(thermal_bridge_width 0.5)
				(island_removal_mode 0)
			)
			(polygon
				(pts
					(xy 118.999 -62.5348) (xy 121.793 -62.5348) (xy 121.793 -63.9064) (xy 118.999 -63.9064)
				)
			)
		)
	)
	(footprint ""
		(layer "F.Cu")
		(at 16.383 -32.893)
		(property "Reference" "TP34"
			(at 1.69037 2.9972 90)
			(unlocked yes)
			(layer "F.SilkS")
			(effects
				(font
					(size 0.7874 0.5842)
					(thickness 0.1524)
				)
				(justify left)
			)
		)
		(property "Value" ""
			(at 0 0 0)
			(layer "F.Fab")
			(effects
				(font
					(size 1.27 1.27)
				)
			)
		)
		(property "Device Type" "TP_PIONT-TP010CT020B030_PTH-TPA"
			(at -1.341882 0.996696 0)
			(unlocked yes)
			(layer "F.Fab")
			(hide yes)
			(effects
				(font
					(size 0.7874 0.5842)
					(thickness 0.000001)
				)
				(justify left)
			)
		)
		(duplicate_pad_numbers_are_jumpers no)
		(fp_poly
			(pts
				(arc
					(start 0.889 0)
					(mid -0.889 0)
					(end 0.889 0)
				)
			)
			(stroke
				(width 0)
				(type default)
			)
			(fill no)
			(layer "B.CrtYd")
		)
		(fp_poly
			(pts
				(arc
					(start 0.889 0)
					(mid -0.889 0)
					(end 0.889 0)
				)
			)
			(stroke
				(width 0)
				(type default)
			)
			(fill no)
			(layer "F.CrtYd")
		)
		(pad "1" thru_hole circle
			(at 0 0)
			(size 0.508 0.508)
			(drill 0.254)
			(layers "*.Cu" "*.Mask")
			(remove_unused_layers no)
			(net "SMA3_SIG_OUT_BF_EN_N")
			(clearance 0.1016)
			(padstack
				(mode front_inner_back)
				(layer "Inner"
					(shape circle)
					(size 0.508 0.508)
					(clearance 0.1016)
				)
				(layer "B.Cu"
					(shape circle)
					(size 0.762 0.762)
					(clearance -0.0254)
				)
			)
		)
	)
	(footprint ""
		(layer "F.Cu")
		(at 10.922 -81.534 90)
		(property "Reference" "R398"
			(at -2.667 1.05537 90)
			(unlocked yes)
			(layer "F.SilkS")
			(effects
				(font
					(size 0.7874 0.5842)
					(thickness 0.1524)
				)
			)
		)
		(property "Value" "VAL*"
			(at 0.02032 2.13233 90)
			(unlocked yes)
			(layer "F.Fab")
			(hide yes)
			(effects
				(font
					(size 0.7874 0.5842)
					(thickness 0.1524)
				)
			)
		)
		(property "Tolerance" "TOL*"
			(at 0.044704 3.05435 90)
			(unlocked yes)
			(layer "Cmts.User")
			(hide yes)
			(effects
				(font
					(size 0.7874 0.5842)
					(thickness 0.1524)
				)
			)
		)
		(property "User Part Number" "PARTNUM*"
			(at 0.02032 4.024884 90)
			(unlocked yes)
			(layer "Cmts.User")
			(hide yes)
			(effects
				(font
					(size 0.7874 0.5842)
					(thickness 0.1524)
				)
			)
		)
		(property "Device Type" "RESISTOR-G155-133R0-01,33OHM,1%"
			(at 0.008382 1.210564 90)
			(unlocked yes)
			(layer "F.Fab")
			(hide yes)
			(effects
				(font
					(size 0.7874 0.5842)
					(thickness 0.1524)
				)
			)
		)
		(duplicate_pad_numbers_are_jumpers no)
		(fp_line
			(start 1.143 -0.5588)
			(end -1.143 -0.5588)
			(stroke
				(width 0.1)
				(type default)
			)
			(layer "F.SilkS")
		)
		(fp_line
			(start -1.143 -0.5588)
			(end -1.143 0.5588)
			(stroke
				(width 0.1)
				(type default)
			)
			(layer "F.SilkS")
		)
		(fp_line
			(start 1.143 0.5588)
			(end 1.143 -0.5588)
			(stroke
				(width 0.1)
				(type default)
			)
			(layer "F.SilkS")
		)
		(fp_line
			(start -1.143 0.5588)
			(end 1.143 0.5588)
			(stroke
				(width 0.1)
				(type default)
			)
			(layer "F.SilkS")
		)
		(fp_rect
			(start -1.143 -0.5588)
			(end 1.143 0.5588)
			(stroke
				(width 0)
				(type default)
			)
			(fill no)
			(layer "F.CrtYd")
		)
		(fp_line
			(start 0.508 -0.3048)
			(end -0.508 -0.3048)
			(stroke
				(width 0.1)
				(type default)
			)
			(layer "F.Fab")
		)
		(fp_line
			(start -0.508 -0.3048)
			(end -0.508 0.3048)
			(stroke
				(width 0.1)
				(type default)
			)
			(layer "F.Fab")
		)
		(fp_line
			(start 0.508 0.3048)
			(end 0.508 -0.3048)
			(stroke
				(width 0.1)
				(type default)
			)
			(layer "F.Fab")
		)
		(fp_line
			(start -0.508 0.3048)
			(end 0.508 0.3048)
			(stroke
				(width 0.1)
				(type default)
			)
			(layer "F.Fab")
		)
		(pad "1" smd rect
			(at -0.5334 0 90)
			(size 0.7112 0.6096)
			(layers "F.Cu" "F.Mask" "F.Paste")
			(net "GPS_SMA_LED_GREEN_N")
		)
		(pad "2" smd rect
			(at 0.5334 0 90)
			(size 0.7112 0.6096)
			(layers "F.Cu" "F.Mask" "F.Paste")
			(net "UNNAMED_14_LED4PV14_I269_4")
		)
		(zone
			(layer "F.Cu")
			(hatch none 0.5)
			(connect_pads
				(clearance 0)
			)
			(min_thickness 0.25)
			(keepout
				(tracks not_allowed)
				(vias allowed)
				(pads allowed)
				(copperpour not_allowed)
				(footprints allowed)
			)
			(placement
				(enabled no)
				(sheetname "")
			)
			(fill
				(thermal_gap 0.5)
				(thermal_bridge_width 0.5)
				(island_removal_mode 0)
			)
			(polygon
				(pts
					(xy 10.6172 -81.4578) (xy 11.2268 -81.4578) (xy 11.2268 -81.6102) (xy 10.6172 -81.6102)
				)
			)
		)
		(zone
			(layer "F.Cu")
			(hatch none 0.5)
			(connect_pads
				(clearance 0)
			)
			(min_thickness 0.25)
			(keepout
				(tracks allowed)
				(vias not_allowed)
				(pads allowed)
				(copperpour not_allowed)
				(footprints allowed)
			)
			(placement
				(enabled no)
				(sheetname "")
			)
			(fill
				(thermal_gap 0.5)
				(thermal_bridge_width 0.5)
				(island_removal_mode 0)
			)
			(polygon
				(pts
					(xy 10.6172 -81.4578) (xy 11.2268 -81.4578) (xy 11.2268 -81.6102) (xy 10.6172 -81.6102)
				)
			)
		)
	)
	(footprint ""
		(layer "F.Cu")
		(at 7.500112 -9.349994)
		(property "Reference" "ME10"
			(at -4.325112 2.531364 0)
			(unlocked yes)
			(layer "F.SilkS")
			(effects
				(font
					(size 0.7874 0.5842)
					(thickness 0.1524)
				)
			)
		)
		(property "Value" ""
			(at 0 0 0)
			(layer "F.Fab")
			(effects
				(font
					(size 1.27 1.27)
				)
			)
		)
		(property "Device Type" "MEC_MTH8-MTH125C236N_V8-MTH125A"
			(at 0 5.08127 0)
			(unlocked yes)
			(layer "F.Fab")
			(hide yes)
			(effects
				(font
					(size 0.7874 0.5842)
					(thickness 0.1524)
				)
			)
		)
		(duplicate_pad_numbers_are_jumpers no)
		(fp_poly
			(pts
				(arc
					(start 3.5052 0)
					(mid -3.5052 0)
					(end 3.5052 0)
				)
			)
			(stroke
				(width 0)
				(type default)
			)
			(fill no)
			(layer "B.CrtYd")
		)
		(fp_poly
			(pts
				(arc
					(start 3.5052 0)
					(mid -3.5052 0)
					(end 3.5052 0)
				)
			)
			(stroke
				(width 0)
				(type default)
			)
			(fill no)
			(layer "F.CrtYd")
		)
		(fp_circle
			(center 0 0)
			(end 2.9972 0)
			(stroke
				(width 0.1)
				(type default)
			)
			(fill no)
			(layer "B.Fab")
		)
		(fp_circle
			(center 0 0)
			(end 2.9972 0)
			(stroke
				(width 0.1)
				(type default)
			)
			(fill no)
			(layer "F.Fab")
		)
		(pad "" np_thru_hole circle
			(at 0 0)
			(size 2.921 2.921)
			(drill 3.175)
			(layers "*.Cu" "*.Mask")
			(padstack
				(mode front_inner_back)
				(layer "Inner"
					(shape circle)
					(size 2.921 2.921)
					(clearance 0.4445)
				)
				(layer "B.Cu"
					(shape circle)
					(size 2.921 2.921)
				)
			)
		)
		(pad "1" thru_hole circle
			(at 0 -2.4511)
			(size 0.6096 0.6096)
			(drill 0.3048)
			(layers "*.Cu" "*.Mask")
			(remove_unused_layers no)
			(net "SG")
			(padstack
				(mode front_inner_back)
				(layer "Inner"
					(shape circle)
					(size 0.6096 0.6096)
					(clearance 0.1143)
				)
				(layer "B.Cu"
					(shape circle)
					(size 0.6096 0.6096)
				)
			)
		)
		(pad "2" thru_hole circle
			(at 1.733296 -1.733296)
			(size 0.6096 0.6096)
			(drill 0.3048)
			(layers "*.Cu" "*.Mask")
			(remove_unused_layers no)
			(net "SG")
			(padstack
				(mode front_inner_back)
				(layer "Inner"
					(shape circle)
					(size 0.6096 0.6096)
					(clearance 0.1143)
				)
				(layer "B.Cu"
					(shape circle)
					(size 0.6096 0.6096)
				)
			)
		)
		(pad "3" thru_hole circle
			(at 2.4511 0)
			(size 0.6096 0.6096)
			(drill 0.3048)
			(layers "*.Cu" "*.Mask")
			(remove_unused_layers no)
			(net "SG")
			(padstack
				(mode front_inner_back)
				(layer "Inner"
					(shape circle)
					(size 0.6096 0.6096)
					(clearance 0.1143)
				)
				(layer "B.Cu"
					(shape circle)
					(size 0.6096 0.6096)
				)
			)
		)
		(pad "4" thru_hole circle
			(at 1.733296 1.733296)
			(size 0.6096 0.6096)
			(drill 0.3048)
			(layers "*.Cu" "*.Mask")
			(remove_unused_layers no)
			(net "SG")
			(padstack
				(mode front_inner_back)
				(layer "Inner"
					(shape circle)
					(size 0.6096 0.6096)
					(clearance 0.1143)
				)
				(layer "B.Cu"
					(shape circle)
					(size 0.6096 0.6096)
				)
			)
		)
		(pad "5" thru_hole circle
			(at 0 2.4511)
			(size 0.6096 0.6096)
			(drill 0.3048)
			(layers "*.Cu" "*.Mask")
			(remove_unused_layers no)
			(net "SG")
			(padstack
				(mode front_inner_back)
				(layer "Inner"
					(shape circle)
					(size 0.6096 0.6096)
					(clearance 0.1143)
				)
				(layer "B.Cu"
					(shape circle)
					(size 0.6096 0.6096)
				)
			)
		)
		(pad "6" thru_hole circle
			(at -1.733296 1.733296)
			(size 0.6096 0.6096)
			(drill 0.3048)
			(layers "*.Cu" "*.Mask")
			(remove_unused_layers no)
			(net "SG")
			(padstack
				(mode front_inner_back)
				(layer "Inner"
					(shape circle)
					(size 0.6096 0.6096)
					(clearance 0.1143)
				)
				(layer "B.Cu"
					(shape circle)
					(size 0.6096 0.6096)
				)
			)
		)
		(pad "7" thru_hole circle
			(at -2.4511 0)
			(size 0.6096 0.6096)
			(drill 0.3048)
			(layers "*.Cu" "*.Mask")
			(remove_unused_layers no)
			(net "SG")
			(padstack
				(mode front_inner_back)
				(layer "Inner"
					(shape circle)
					(size 0.6096 0.6096)
					(clearance 0.1143)
				)
				(layer "B.Cu"
					(shape circle)
					(size 0.6096 0.6096)
				)
			)
		)
		(pad "8" thru_hole circle
			(at -1.733296 -1.733296)
			(size 0.6096 0.6096)
			(drill 0.3048)
			(layers "*.Cu" "*.Mask")
			(remove_unused_layers no)
			(net "SG")
			(padstack
				(mode front_inner_back)
				(layer "Inner"
					(shape circle)
					(size 0.6096 0.6096)
					(clearance 0.1143)
				)
				(layer "B.Cu"
					(shape circle)
					(size 0.6096 0.6096)
				)
			)
		)
		(zone
			(layers "F.Cu" "B.Cu" "In1.Cu" "In2.Cu" "In3.Cu" "In4.Cu" "In5.Cu" "In6.Cu"
				"In7.Cu" "In8.Cu"
			)
			(hatch none 0.5)
			(connect_pads
				(clearance 0)
			)
			(min_thickness 0.25)
			(keepout
				(tracks not_allowed)
				(vias allowed)
				(pads allowed)
				(copperpour not_allowed)
				(footprints allowed)
			)
			(placement
				(enabled no)
				(sheetname "")
			)
			(fill
				(thermal_gap 0.5)
				(thermal_bridge_width 0.5)
				(island_removal_mode 0)
			)
			(polygon
				(pts
					(arc
						(start 9.392412 -9.349994)
						(mid 5.607812 -9.349994)
						(end 9.392412 -9.349994)
					)
				)
			)
		)
	)
	(footprint ""
		(layer "F.Cu")
		(at 150.381462 -56.8706)
		(property "Reference" "R296"
			(at -1.410462 -3.66903 0)
			(unlocked yes)
			(layer "F.SilkS")
			(effects
				(font
					(size 0.7874 0.5842)
					(thickness 0.1524)
				)
			)
		)
		(property "Value" "VAL*"
			(at 0.02032 2.13233 0)
			(unlocked yes)
			(layer "F.Fab")
			(hide yes)
			(effects
				(font
					(size 0.7874 0.5842)
					(thickness 0.1524)
				)
			)
		)
		(property "Tolerance" "TOL*"
			(at 0.044704 3.05435 0)
			(unlocked yes)
			(layer "Cmts.User")
			(hide yes)
			(effects
				(font
					(size 0.7874 0.5842)
					(thickness 0.1524)
				)
			)
		)
		(property "User Part Number" "PARTNUM*"
			(at 0.02032 4.024884 0)
			(unlocked yes)
			(layer "Cmts.User")
			(hide yes)
			(effects
				(font
					(size 0.7874 0.5842)
					(thickness 0.1524)
				)
			)
		)
		(property "Device Type" "RESISTOR-G155-14701-01,4.7KOHMA"
			(at 0.008382 1.210564 0)
			(unlocked yes)
			(layer "F.Fab")
			(hide yes)
			(effects
				(font
					(size 0.7874 0.5842)
					(thickness 0.1524)
				)
			)
		)
		(duplicate_pad_numbers_are_jumpers no)
		(fp_line
			(start -1.143 -0.5588)
			(end -1.143 0.5588)
			(stroke
				(width 0.1)
				(type default)
			)
			(layer "F.SilkS")
		)
		(fp_line
			(start -1.143 0.5588)
			(end 1.143 0.5588)
			(stroke
				(width 0.1)
				(type default)
			)
			(layer "F.SilkS")
		)
		(fp_line
			(start 1.143 -0.5588)
			(end -1.143 -0.5588)
			(stroke
				(width 0.1)
				(type default)
			)
			(layer "F.SilkS")
		)
		(fp_line
			(start 1.143 0.5588)
			(end 1.143 -0.5588)
			(stroke
				(width 0.1)
				(type default)
			)
			(layer "F.SilkS")
		)
		(fp_rect
			(start 1.143 -0.5588)
			(end -1.143 0.5588)
			(stroke
				(width 0)
				(type default)
			)
			(fill no)
			(layer "F.CrtYd")
		)
		(fp_line
			(start -0.508 -0.3048)
			(end -0.508 0.3048)
			(stroke
				(width 0.1)
				(type default)
			)
			(layer "F.Fab")
		)
		(fp_line
			(start -0.508 0.3048)
			(end 0.508 0.3048)
			(stroke
				(width 0.1)
				(type default)
			)
			(layer "F.Fab")
		)
		(fp_line
			(start 0.508 -0.3048)
			(end -0.508 -0.3048)
			(stroke
				(width 0.1)
				(type default)
			)
			(layer "F.Fab")
		)
		(fp_line
			(start 0.508 0.3048)
			(end 0.508 -0.3048)
			(stroke
				(width 0.1)
				(type default)
			)
			(layer "F.Fab")
		)
		(pad "1" smd rect
			(at -0.5334 0)
			(size 0.7112 0.6096)
			(layers "F.Cu" "F.Mask" "F.Paste")
			(net "XP3R3V_FPGA")
		)
		(pad "2" smd rect
			(at 0.5334 0)
			(size 0.7112 0.6096)
			(layers "F.Cu" "F.Mask" "F.Paste")
			(net "R_SHT3X_RST_N")
		)
		(zone
			(layer "F.Cu")
			(hatch none 0.5)
			(connect_pads
				(clearance 0)
			)
			(min_thickness 0.25)
			(keepout
				(tracks allowed)
				(vias not_allowed)
				(pads allowed)
				(copperpour not_allowed)
				(footprints allowed)
			)
			(placement
				(enabled no)
				(sheetname "")
			)
			(fill
				(thermal_gap 0.5)
				(thermal_bridge_width 0.5)
				(island_removal_mode 0)
			)
			(polygon
				(pts
					(xy 150.457662 -57.1754) (xy 150.305262 -57.1754) (xy 150.305262 -56.5658) (xy 150.457662 -56.5658)
				)
			)
		)
	)
	(footprint ""
		(layer "F.Cu")
		(at 110.9726 -26.7208 90)
		(property "Reference" "C252"
			(at -8.5598 -0.31623 90)
			(unlocked yes)
			(layer "F.SilkS")
			(effects
				(font
					(size 0.7874 0.5842)
					(thickness 0.1524)
				)
			)
		)
		(property "Value" "VAL*"
			(at 0.0762 2.067306 90)
			(unlocked yes)
			(layer "F.Fab")
			(hide yes)
			(effects
				(font
					(size 0.7874 0.5842)
					(thickness 0.1524)
				)
			)
		)
		(property "Device Type" "CAPACITOR-G105-0B104-CK,0.1UF,A"
			(at 0.0508 1.127506 90)
			(unlocked yes)
			(layer "F.Fab")
			(hide yes)
			(effects
				(font
					(size 0.7874 0.5842)
					(thickness 0.1524)
				)
			)
		)
		(property "User Part Number" "PARTNUM*"
			(at 0.1016 4.023106 90)
			(unlocked yes)
			(layer "Cmts.User")
			(hide yes)
			(effects
				(font
					(size 0.7874 0.5842)
					(thickness 0.1524)
				)
			)
		)
		(property "Tolerance" "TOL*"
			(at 0.0762 3.032506 90)
			(unlocked yes)
			(layer "Cmts.User")
			(hide yes)
			(effects
				(font
					(size 0.7874 0.5842)
					(thickness 0.1524)
				)
			)
		)
		(duplicate_pad_numbers_are_jumpers no)
		(fp_line
			(start 1.143 -0.5588)
			(end -1.143 -0.5588)
			(stroke
				(width 0.1)
				(type default)
			)
			(layer "F.SilkS")
		)
		(fp_line
			(start -1.143 -0.5588)
			(end -1.143 0.5588)
			(stroke
				(width 0.1)
				(type default)
			)
			(layer "F.SilkS")
		)
		(fp_line
			(start 1.143 0.5588)
			(end 1.143 -0.5588)
			(stroke
				(width 0.1)
				(type default)
			)
			(layer "F.SilkS")
		)
		(fp_line
			(start -1.143 0.5588)
			(end 1.143 0.5588)
			(stroke
				(width 0.1)
				(type default)
			)
			(layer "F.SilkS")
		)
		(fp_rect
			(start 1.143 -0.5588)
			(end -1.143 0.5588)
			(stroke
				(width 0)
				(type default)
			)
			(fill no)
			(layer "F.CrtYd")
		)
		(fp_line
			(start 0.508 -0.3048)
			(end -0.508 -0.3048)
			(stroke
				(width 0.1)
				(type default)
			)
			(layer "F.Fab")
		)
		(fp_line
			(start -0.508 -0.3048)
			(end -0.508 0.3048)
			(stroke
				(width 0.1)
				(type default)
			)
			(layer "F.Fab")
		)
		(fp_line
			(start 0.508 0.3048)
			(end 0.508 -0.3048)
			(stroke
				(width 0.1)
				(type default)
			)
			(layer "F.Fab")
		)
		(fp_line
			(start -0.508 0.3048)
			(end 0.508 0.3048)
			(stroke
				(width 0.1)
				(type default)
			)
			(layer "F.Fab")
		)
		(pad "1" smd rect
			(at -0.5334 0 90)
			(size 0.7112 0.6096)
			(layers "F.Cu" "F.Mask" "F.Paste")
			(net "OSC_200M_CLKN")
		)
		(pad "2" smd rect
			(at 0.5334 0 90)
			(size 0.7112 0.6096)
			(layers "F.Cu" "F.Mask" "F.Paste")
			(net "MHZ200CLKN_CLKIN")
		)
		(zone
			(layer "F.Cu")
			(hatch none 0.5)
			(connect_pads
				(clearance 0)
			)
			(min_thickness 0.25)
			(keepout
				(tracks allowed)
				(vias not_allowed)
				(pads allowed)
				(copperpour not_allowed)
				(footprints allowed)
			)
			(placement
				(enabled no)
				(sheetname "")
			)
			(fill
				(thermal_gap 0.5)
				(thermal_bridge_width 0.5)
				(island_removal_mode 0)
			)
			(polygon
				(pts
					(xy 110.6678 -26.797) (xy 110.6678 -26.6446) (xy 111.2774 -26.6446) (xy 111.2774 -26.797)
				)
			)
		)
	)
	(footprint ""
		(layer "F.Cu")
		(at 47.117 -78.867)
		(property "Reference" "C300"
			(at 3.175 0.03937 0)
			(unlocked yes)
			(layer "F.SilkS")
			(effects
				(font
					(size 0.7874 0.5842)
					(thickness 0.1524)
				)
			)
		)
		(property "Value" "VAL*"
			(at 0.0762 3.134106 0)
			(unlocked yes)
			(layer "F.Fab")
			(hide yes)
			(effects
				(font
					(size 0.7874 0.5842)
					(thickness 0.1524)
				)
			)
		)
		(property "Tolerance" "TOL*"
			(at 0.0762 4.048506 0)
			(unlocked yes)
			(layer "Cmts.User")
			(hide yes)
			(effects
				(font
					(size 0.7874 0.5842)
					(thickness 0.1524)
				)
			)
		)
		(property "User Part Number" "PARTNUM*"
			(at 0.1016 5.013706 0)
			(unlocked yes)
			(layer "Cmts.User")
			(hide yes)
			(effects
				(font
					(size 0.7874 0.5842)
					(thickness 0.1524)
				)
			)
		)
		(property "Device Type" "CAPACITOR-G107-0F106-EM,10UF,2A"
			(at 0.0508 2.194306 0)
			(unlocked yes)
			(layer "F.Fab")
			(hide yes)
			(effects
				(font
					(size 0.7874 0.5842)
					(thickness 0.1524)
				)
			)
		)
		(duplicate_pad_numbers_are_jumpers no)
		(fp_line
			(start -1.5748 -0.9398)
			(end -1.5748 0.9398)
			(stroke
				(width 0.1)
				(type default)
			)
			(layer "F.SilkS")
		)
		(fp_line
			(start -1.5748 0.9398)
			(end 1.5748 0.9398)
			(stroke
				(width 0.1)
				(type default)
			)
			(layer "F.SilkS")
		)
		(fp_line
			(start 1.5748 -0.9398)
			(end -1.5748 -0.9398)
			(stroke
				(width 0.1)
				(type default)
			)
			(layer "F.SilkS")
		)
		(fp_line
			(start 1.5748 0.9398)
			(end 1.5748 -0.9398)
			(stroke
				(width 0.1)
				(type default)
			)
			(layer "F.SilkS")
		)
		(fp_rect
			(start -1.5748 0.9398)
			(end 1.5748 -0.9398)
			(stroke
				(width 0)
				(type default)
			)
			(fill no)
			(layer "F.CrtYd")
		)
		(fp_line
			(start -1.016 -0.635)
			(end -1.016 0.635)
			(stroke
				(width 0.1)
				(type default)
			)
			(layer "F.Fab")
		)
		(fp_line
			(start -1.016 0.635)
			(end 1.016 0.635)
			(stroke
				(width 0.1)
				(type default)
			)
			(layer "F.Fab")
		)
		(fp_line
			(start 1.016 -0.635)
			(end -1.016 -0.635)
			(stroke
				(width 0.1)
				(type default)
			)
			(layer "F.Fab")
		)
		(fp_line
			(start 1.016 0.635)
			(end 1.016 -0.635)
			(stroke
				(width 0.1)
				(type default)
			)
			(layer "F.Fab")
		)
		(pad "1" smd rect
			(at -0.8382 0)
			(size 0.9652 1.3716)
			(layers "F.Cu" "F.Mask" "F.Paste")
			(net "UNNAMED_525_CAPACITOR_I16_1")
		)
		(pad "2" smd rect
			(at 0.8382 0)
			(size 0.9652 1.3716)
			(layers "F.Cu" "F.Mask" "F.Paste")
			(net "SG")
		)
		(zone
			(layer "F.Cu")
			(hatch none 0.5)
			(connect_pads
				(clearance 0)
			)
			(min_thickness 0.25)
			(keepout
				(tracks not_allowed)
				(vias allowed)
				(pads allowed)
				(copperpour not_allowed)
				(footprints allowed)
			)
			(placement
				(enabled no)
				(sheetname "")
			)
			(fill
				(thermal_gap 0.5)
				(thermal_bridge_width 0.5)
				(island_removal_mode 0)
			)
			(polygon
				(pts
					(xy 46.8884 -78.232) (xy 47.3456 -78.232) (xy 47.3456 -79.502) (xy 46.8884 -79.502)
				)
			)
		)
		(zone
			(layer "F.Cu")
			(hatch none 0.5)
			(connect_pads
				(clearance 0)
			)
			(min_thickness 0.25)
			(keepout
				(tracks allowed)
				(vias not_allowed)
				(pads allowed)
				(copperpour not_allowed)
				(footprints allowed)
			)
			(placement
				(enabled no)
				(sheetname "")
			)
			(fill
				(thermal_gap 0.5)
				(thermal_bridge_width 0.5)
				(island_removal_mode 0)
			)
			(polygon
				(pts
					(xy 46.8884 -78.232) (xy 47.3456 -78.232) (xy 47.3456 -79.502) (xy 46.8884 -79.502)
				)
			)
		)
	)
	(footprint ""
		(layer "F.Cu")
		(at 153.67 -56.515)
		(property "Reference" "C274"
			(at 1.905 2.19837 0)
			(unlocked yes)
			(layer "F.SilkS")
			(effects
				(font
					(size 0.7874 0.5842)
					(thickness 0.1524)
				)
			)
		)
		(property "Value" "VAL*"
			(at 0.0762 2.067306 0)
			(unlocked yes)
			(layer "F.Fab")
			(hide yes)
			(effects
				(font
					(size 0.7874 0.5842)
					(thickness 0.1524)
				)
			)
		)
		(property "Device Type" "CAPACITOR-G105-0C106-BM,10UF,2A"
			(at 0.0508 1.127506 0)
			(unlocked yes)
			(layer "F.Fab")
			(hide yes)
			(effects
				(font
					(size 0.7874 0.5842)
					(thickness 0.1524)
				)
			)
		)
		(property "User Part Number" "PARTNUM*"
			(at 0.1016 4.023106 0)
			(unlocked yes)
			(layer "Cmts.User")
			(hide yes)
			(effects
				(font
					(size 0.7874 0.5842)
					(thickness 0.1524)
				)
			)
		)
		(property "Tolerance" "TOL*"
			(at 0.0762 3.032506 0)
			(unlocked yes)
			(layer "Cmts.User")
			(hide yes)
			(effects
				(font
					(size 0.7874 0.5842)
					(thickness 0.1524)
				)
			)
		)
		(duplicate_pad_numbers_are_jumpers no)
		(fp_line
			(start -1.143 -0.5588)
			(end -1.143 0.5588)
			(stroke
				(width 0.1)
				(type default)
			)
			(layer "F.SilkS")
		)
		(fp_line
			(start -1.143 0.5588)
			(end 1.143 0.5588)
			(stroke
				(width 0.1)
				(type default)
			)
			(layer "F.SilkS")
		)
		(fp_line
			(start 1.143 -0.5588)
			(end -1.143 -0.5588)
			(stroke
				(width 0.1)
				(type default)
			)
			(layer "F.SilkS")
		)
		(fp_line
			(start 1.143 0.5588)
			(end 1.143 -0.5588)
			(stroke
				(width 0.1)
				(type default)
			)
			(layer "F.SilkS")
		)
		(fp_rect
			(start 1.143 -0.5588)
			(end -1.143 0.5588)
			(stroke
				(width 0)
				(type default)
			)
			(fill no)
			(layer "F.CrtYd")
		)
		(fp_line
			(start -0.508 -0.3048)
			(end -0.508 0.3048)
			(stroke
				(width 0.1)
				(type default)
			)
			(layer "F.Fab")
		)
		(fp_line
			(start -0.508 0.3048)
			(end 0.508 0.3048)
			(stroke
				(width 0.1)
				(type default)
			)
			(layer "F.Fab")
		)
		(fp_line
			(start 0.508 -0.3048)
			(end -0.508 -0.3048)
			(stroke
				(width 0.1)
				(type default)
			)
			(layer "F.Fab")
		)
		(fp_line
			(start 0.508 0.3048)
			(end 0.508 -0.3048)
			(stroke
				(width 0.1)
				(type default)
			)
			(layer "F.Fab")
		)
		(pad "1" smd rect
			(at -0.5334 0)
			(size 0.7112 0.6096)
			(layers "F.Cu" "F.Mask" "F.Paste")
			(net "VDD3V3_SHT31A")
		)
		(pad "2" smd rect
			(at 0.5334 0)
			(size 0.7112 0.6096)
			(layers "F.Cu" "F.Mask" "F.Paste")
			(net "SG")
		)
		(zone
			(layer "F.Cu")
			(hatch none 0.5)
			(connect_pads
				(clearance 0)
			)
			(min_thickness 0.25)
			(keepout
				(tracks allowed)
				(vias not_allowed)
				(pads allowed)
				(copperpour not_allowed)
				(footprints allowed)
			)
			(placement
				(enabled no)
				(sheetname "")
			)
			(fill
				(thermal_gap 0.5)
				(thermal_bridge_width 0.5)
				(island_removal_mode 0)
			)
			(polygon
				(pts
					(xy 153.7462 -56.8198) (xy 153.5938 -56.8198) (xy 153.5938 -56.2102) (xy 153.7462 -56.2102)
				)
			)
		)
	)
	(footprint ""
		(layer "F.Cu")
		(at 100.33 -97.028)
		(property "Reference" "TP14"
			(at -1.0414 -1.36525 0)
			(unlocked yes)
			(layer "F.SilkS")
			(effects
				(font
					(size 0.635 0.4064)
					(thickness 0.1524)
				)
				(justify left)
			)
		)
		(property "Value" ""
			(at 0 0 0)
			(layer "F.Fab")
			(effects
				(font
					(size 1.27 1.27)
				)
			)
		)
		(property "Device Type" "TP_PIONT-TP010CT020B030_PTH-TPA"
			(at -1.341882 0.996696 0)
			(unlocked yes)
			(layer "F.Fab")
			(hide yes)
			(effects
				(font
					(size 0.7874 0.5842)
					(thickness 0.000001)
				)
				(justify left)
			)
		)
		(duplicate_pad_numbers_are_jumpers no)
		(fp_poly
			(pts
				(arc
					(start 0.889 0)
					(mid -0.889 0)
					(end 0.889 0)
				)
			)
			(stroke
				(width 0)
				(type default)
			)
			(fill no)
			(layer "B.CrtYd")
		)
		(fp_poly
			(pts
				(arc
					(start 0.889 0)
					(mid -0.889 0)
					(end 0.889 0)
				)
			)
			(stroke
				(width 0)
				(type default)
			)
			(fill no)
			(layer "F.CrtYd")
		)
		(pad "1" thru_hole circle
			(at 0 0)
			(size 0.508 0.508)
			(drill 0.254)
			(layers "*.Cu" "*.Mask")
			(remove_unused_layers no)
			(net "MUX1_SEL")
			(clearance 0.1016)
			(padstack
				(mode front_inner_back)
				(layer "Inner"
					(shape circle)
					(size 0.508 0.508)
					(clearance 0.1016)
				)
				(layer "B.Cu"
					(shape circle)
					(size 0.762 0.762)
					(clearance -0.0254)
				)
			)
		)
	)
	(footprint ""
		(layer "F.Cu")
		(at 106.807 -22.86 -90)
		(property "Reference" "R235"
			(at -2.667 0.34163 90)
			(unlocked yes)
			(layer "F.SilkS")
			(effects
				(font
					(size 0.7874 0.5842)
					(thickness 0.1524)
				)
			)
		)
		(property "Value" "VAL*"
			(at 0.02032 2.13233 270)
			(unlocked yes)
			(layer "F.Fab")
			(hide yes)
			(effects
				(font
					(size 0.7874 0.5842)
					(thickness 0.1524)
				)
			)
		)
		(property "Device Type" "RESISTOR-G155-14701-01,4.7KOHMA"
			(at 0.008382 1.210564 270)
			(unlocked yes)
			(layer "F.Fab")
			(hide yes)
			(effects
				(font
					(size 0.7874 0.5842)
					(thickness 0.1524)
				)
			)
		)
		(property "User Part Number" "PARTNUM*"
			(at 0.02032 4.024884 270)
			(unlocked yes)
			(layer "Cmts.User")
			(hide yes)
			(effects
				(font
					(size 0.7874 0.5842)
					(thickness 0.1524)
				)
			)
		)
		(property "Tolerance" "TOL*"
			(at 0.044704 3.05435 270)
			(unlocked yes)
			(layer "Cmts.User")
			(hide yes)
			(effects
				(font
					(size 0.7874 0.5842)
					(thickness 0.1524)
				)
			)
		)
		(duplicate_pad_numbers_are_jumpers no)
		(fp_line
			(start -1.143 0.5588)
			(end 1.143 0.5588)
			(stroke
				(width 0.1)
				(type default)
			)
			(layer "F.SilkS")
		)
		(fp_line
			(start 1.143 0.5588)
			(end 1.143 -0.5588)
			(stroke
				(width 0.1)
				(type default)
			)
			(layer "F.SilkS")
		)
		(fp_line
			(start -1.143 -0.5588)
			(end -1.143 0.5588)
			(stroke
				(width 0.1)
				(type default)
			)
			(layer "F.SilkS")
		)
		(fp_line
			(start 1.143 -0.5588)
			(end -1.143 -0.5588)
			(stroke
				(width 0.1)
				(type default)
			)
			(layer "F.SilkS")
		)
		(fp_rect
			(start -1.143 0.5588)
			(end 1.143 -0.5588)
			(stroke
				(width 0)
				(type default)
			)
			(fill no)
			(layer "F.CrtYd")
		)
		(fp_line
			(start -0.508 0.3048)
			(end 0.508 0.3048)
			(stroke
				(width 0.1)
				(type default)
			)
			(layer "F.Fab")
		)
		(fp_line
			(start 0.508 0.3048)
			(end 0.508 -0.3048)
			(stroke
				(width 0.1)
				(type default)
			)
			(layer "F.Fab")
		)
		(fp_line
			(start -0.508 -0.3048)
			(end -0.508 0.3048)
			(stroke
				(width 0.1)
				(type default)
			)
			(layer "F.Fab")
		)
		(fp_line
			(start 0.508 -0.3048)
			(end -0.508 -0.3048)
			(stroke
				(width 0.1)
				(type default)
			)
			(layer "F.Fab")
		)
		(pad "1" smd rect
			(at -0.5334 0 270)
			(size 0.7112 0.6096)
			(layers "F.Cu" "F.Mask" "F.Paste")
			(net "VDD3V3_OSC_200M")
		)
		(pad "2" smd rect
			(at 0.5334 0 270)
			(size 0.7112 0.6096)
			(layers "F.Cu" "F.Mask" "F.Paste")
			(net "CLK_200M_OE")
		)
		(zone
			(layer "F.Cu")
			(hatch none 0.5)
			(connect_pads
				(clearance 0)
			)
			(min_thickness 0.25)
			(keepout
				(tracks allowed)
				(vias not_allowed)
				(pads allowed)
				(copperpour not_allowed)
				(footprints allowed)
			)
			(placement
				(enabled no)
				(sheetname "")
			)
			(fill
				(thermal_gap 0.5)
				(thermal_bridge_width 0.5)
				(island_removal_mode 0)
			)
			(polygon
				(pts
					(xy 106.5022 -22.9362) (xy 106.5022 -22.7838) (xy 107.1118 -22.7838) (xy 107.1118 -22.9362)
				)
			)
		)
	)
	(footprint ""
		(layer "F.Cu")
		(at 137.033 -57.3024 -90)
		(property "Reference" "L9"
			(at 0.0762 2.75463 90)
			(unlocked yes)
			(layer "F.SilkS")
			(effects
				(font
					(size 0.7874 0.5842)
					(thickness 0.1524)
				)
				(justify left)
			)
		)
		(property "Value" "VAL*"
			(at -0.9398 3.70967 270)
			(unlocked yes)
			(layer "F.Fab")
			(hide yes)
			(effects
				(font
					(size 0.7874 0.5842)
					(thickness 0.1524)
				)
				(justify left)
			)
		)
		(property "Tolerance" "TOL*"
			(at -0.9906 5.00507 270)
			(unlocked yes)
			(layer "Cmts.User")
			(hide yes)
			(effects
				(font
					(size 0.7874 0.5842)
					(thickness 0.1524)
				)
				(justify left)
			)
		)
		(property "User Part Number" "PARTNUM*"
			(at -2.54 2.46507 270)
			(unlocked yes)
			(layer "Cmts.User")
			(hide yes)
			(effects
				(font
					(size 0.7874 0.5842)
					(thickness 0.1524)
				)
				(justify left)
			)
		)
		(property "Device Type" "FERRITEBEAD-G191-10101-01,26OHA"
			(at -0.9906 1.22047 270)
			(unlocked yes)
			(layer "F.Fab")
			(hide yes)
			(effects
				(font
					(size 0.7874 0.5842)
					(thickness 0.1524)
				)
				(justify left)
			)
		)
		(duplicate_pad_numbers_are_jumpers no)
		(fp_line
			(start -1.3208 0.7112)
			(end -1.3208 -0.7112)
			(stroke
				(width 0.1)
				(type default)
			)
			(layer "F.SilkS")
		)
		(fp_line
			(start 1.3208 0.7112)
			(end -1.3208 0.7112)
			(stroke
				(width 0.1)
				(type default)
			)
			(layer "F.SilkS")
		)
		(fp_line
			(start -1.3208 -0.7112)
			(end 1.3208 -0.7112)
			(stroke
				(width 0.1)
				(type default)
			)
			(layer "F.SilkS")
		)
		(fp_line
			(start 1.3208 -0.7112)
			(end 1.3208 0.7112)
			(stroke
				(width 0.1)
				(type default)
			)
			(layer "F.SilkS")
		)
		(fp_rect
			(start -1.3208 0.7112)
			(end 1.3208 -0.7112)
			(stroke
				(width 0)
				(type default)
			)
			(fill no)
			(layer "F.CrtYd")
		)
		(fp_line
			(start -0.8128 0.4572)
			(end -0.8128 -0.4572)
			(stroke
				(width 0.1)
				(type default)
			)
			(layer "F.Fab")
		)
		(fp_line
			(start 0.8128 0.4572)
			(end -0.8128 0.4572)
			(stroke
				(width 0.1)
				(type default)
			)
			(layer "F.Fab")
		)
		(fp_line
			(start -0.8128 -0.4572)
			(end 0.8128 -0.4572)
			(stroke
				(width 0.1)
				(type default)
			)
			(layer "F.Fab")
		)
		(fp_line
			(start 0.8128 -0.4572)
			(end 0.8128 0.4572)
			(stroke
				(width 0.1)
				(type default)
			)
			(layer "F.Fab")
		)
		(pad "1" smd rect
			(at -0.6858 0 270)
			(size 0.762 0.8636)
			(layers "F.Cu" "F.Mask" "F.Paste")
			(net "XP12R0V")
		)
		(pad "2" smd rect
			(at 0.6858 0 270)
			(size 0.762 0.8636)
			(layers "F.Cu" "F.Mask" "F.Paste")
			(net "VIN_XP1R0V")
		)
		(zone
			(layer "F.Cu")
			(hatch none 0.5)
			(connect_pads
				(clearance 0)
			)
			(min_thickness 0.25)
			(keepout
				(tracks allowed)
				(vias not_allowed)
				(pads allowed)
				(copperpour not_allowed)
				(footprints allowed)
			)
			(placement
				(enabled no)
				(sheetname "")
			)
			(fill
				(thermal_gap 0.5)
				(thermal_bridge_width 0.5)
				(island_removal_mode 0)
			)
			(polygon
				(pts
					(xy 136.5758 -57.4548) (xy 136.5758 -57.15) (xy 137.4902 -57.15) (xy 137.4902 -57.4548)
				)
			)
		)
		(zone
			(layer "F.Cu")
			(hatch none 0.5)
			(connect_pads
				(clearance 0)
			)
			(min_thickness 0.25)
			(keepout
				(tracks not_allowed)
				(vias allowed)
				(pads allowed)
				(copperpour not_allowed)
				(footprints allowed)
			)
			(placement
				(enabled no)
				(sheetname "")
			)
			(fill
				(thermal_gap 0.5)
				(thermal_bridge_width 0.5)
				(island_removal_mode 0)
			)
			(polygon
				(pts
					(xy 136.5758 -57.4548) (xy 136.5758 -57.15) (xy 137.4902 -57.15) (xy 137.4902 -57.4548)
				)
			)
		)
	)
	(footprint ""
		(layer "F.Cu")
		(at 99.3648 -74.803 90)
		(property "Reference" "U20"
			(at 0 2.65557 90)
			(unlocked yes)
			(layer "F.SilkS")
			(effects
				(font
					(size 0.7874 0.5842)
					(thickness 0.1524)
				)
			)
		)
		(property "Value" ""
			(at 0 0 90)
			(layer "F.Fab")
			(effects
				(font
					(size 1.27 1.27)
				)
			)
		)
		(property "Device Type" "ISL80101IRAJZ_DFN10-G222-10136A"
			(at 0.276606 2.583688 90)
			(unlocked yes)
			(layer "F.Fab")
			(hide yes)
			(effects
				(font
					(size 0.7874 0.5842)
					(thickness 0.1524)
				)
			)
		)
		(property "User Part Number" "PARTNUM*"
			(at 0.276606 3.517646 90)
			(unlocked yes)
			(layer "Cmts.User")
			(hide yes)
			(effects
				(font
					(size 0.7874 0.5842)
					(thickness 0.1524)
				)
			)
		)
		(duplicate_pad_numbers_are_jumpers no)
		(fp_line
			(start 2.290318 -1.779016)
			(end 2.290318 1.779016)
			(stroke
				(width 0.1)
				(type default)
			)
			(layer "F.SilkS")
		)
		(fp_line
			(start -2.290318 -1.779016)
			(end 2.290318 -1.779016)
			(stroke
				(width 0.1)
				(type default)
			)
			(layer "F.SilkS")
		)
		(fp_line
			(start 2.290318 1.779016)
			(end -2.290318 1.779016)
			(stroke
				(width 0.1)
				(type default)
			)
			(layer "F.SilkS")
		)
		(fp_line
			(start -2.290318 1.779016)
			(end -2.290318 -1.779016)
			(stroke
				(width 0.1)
				(type default)
			)
			(layer "F.SilkS")
		)
		(fp_poly
			(pts
				(arc
					(start -2.934462 -0.642112)
					(mid -2.934462 -1.404112)
					(end -2.934462 -0.642112)
				)
			)
			(stroke
				(width 0)
				(type default)
			)
			(fill yes)
			(layer "F.SilkS")
		)
		(fp_rect
			(start -0.7239 0.9017)
			(end 0.7239 0.1016)
			(stroke
				(width 0)
				(type default)
			)
			(fill yes)
			(layer "F.Paste")
		)
		(fp_poly
			(pts
				(xy -0.7239 -0.1016)
				(arc
					(start -0.7239 -0.6477)
					(mid -0.290295 -0.468095)
					(end -0.4699 -0.9017)
				)
				(xy 0.7239 -0.9017) (xy 0.7239 -0.1016)
			)
			(stroke
				(width 0)
				(type default)
			)
			(fill yes)
			(layer "F.Paste")
		)
		(fp_poly
			(pts
				(xy -2.544318 2.033016) (xy 2.544318 2.033016) (xy 2.544318 -2.033016) (xy -2.544318 -2.033016)
			)
			(stroke
				(width 0)
				(type default)
			)
			(fill no)
			(layer "F.CrtYd")
		)
		(fp_line
			(start 1.525016 -1.525016)
			(end 1.525016 1.525016)
			(stroke
				(width 0.1)
				(type default)
			)
			(layer "F.Fab")
		)
		(fp_line
			(start -1.525016 -1.525016)
			(end 1.525016 -1.525016)
			(stroke
				(width 0.1)
				(type default)
			)
			(layer "F.Fab")
		)
		(fp_line
			(start 1.525016 1.525016)
			(end -1.525016 1.525016)
			(stroke
				(width 0.1)
				(type default)
			)
			(layer "F.Fab")
		)
		(fp_line
			(start -1.525016 1.525016)
			(end -1.525016 -1.525016)
			(stroke
				(width 0.1)
				(type default)
			)
			(layer "F.Fab")
		)
		(fp_poly
			(pts
				(arc
					(start -2.934462 -0.642112)
					(mid -2.934462 -1.404112)
					(end -2.934462 -0.642112)
				)
			)
			(stroke
				(width 0)
				(type default)
			)
			(fill yes)
			(layer "F.Fab")
		)
		(fp_text user "5"
			(at -2.825496 1.115822 90)
			(unlocked yes)
			(layer "F.SilkS")
			(effects
				(font
					(size 0.7874 0.5842)
					(thickness 0.1524)
				)
			)
		)
		(fp_text user "6"
			(at 2.24663 2.2352 0)
			(unlocked yes)
			(layer "F.SilkS")
			(effects
				(font
					(size 0.7874 0.5842)
					(thickness 0.1524)
				)
			)
		)
		(fp_text user "10"
			(at 2.38633 -1.3208 0)
			(unlocked yes)
			(layer "F.Fab")
			(effects
				(font
					(size 0.7874 0.5842)
					(thickness 0.1524)
				)
			)
		)
		(fp_text user "6"
			(at 2.38633 0.8382 0)
			(unlocked yes)
			(layer "F.Fab")
			(effects
				(font
					(size 0.7874 0.5842)
					(thickness 0.1524)
				)
			)
		)
		(fp_text user "5"
			(at -1.67767 1.9812 0)
			(unlocked yes)
			(layer "F.Fab")
			(effects
				(font
					(size 0.7874 0.5842)
					(thickness 0.1524)
				)
			)
		)
		(pad "1" smd circle
			(at -1.515618 -1.000252 270)
			(size 0 0)
			(layers "F.Cu" "F.Mask" "F.Paste")
			(net "XP1R2V_FPGA")
		)
		(pad "2" smd rect
			(at -1.515618 -0.500126 90)
			(size 1.0414 0.3048)
			(layers "F.Cu" "F.Mask" "F.Paste")
			(net "XP1R2V_FPGA")
		)
		(pad "3" smd rect
			(at -1.515618 0 90)
			(size 1.0414 0.3048)
			(layers "F.Cu" "F.Mask" "F.Paste")
			(net "XP1R2V_FB")
		)
		(pad "4" smd rect
			(at -1.515618 0.500126 90)
			(size 1.0414 0.3048)
			(layers "F.Cu" "F.Mask" "F.Paste")
			(net "XP1R2V_PG_R")
		)
		(pad "5" smd circle
			(at -1.515618 1.000252 90)
			(size 0 0)
			(layers "F.Cu" "F.Mask" "F.Paste")
			(net "SG")
		)
		(pad "6" smd circle
			(at 1.515618 1.000252 90)
			(size 0 0)
			(layers "F.Cu" "F.Mask" "F.Paste")
			(net "XP1R2V_SS")
		)
		(pad "7" smd rect
			(at 1.515618 0.500126 90)
			(size 1.0414 0.3048)
			(layers "F.Cu" "F.Mask" "F.Paste")
			(net "XP1R2V_EN_R")
		)
		(pad "8" smd rect
			(at 1.515618 0 90)
			(size 1.0414 0.3048)
			(layers "F.Cu" "F.Mask" "F.Paste")
			(net "Net_766")
		)
		(pad "9" smd rect
			(at 1.515618 -0.500126 90)
			(size 1.0414 0.3048)
			(layers "F.Cu" "F.Mask" "F.Paste")
			(net "XP1R2V_VIN")
		)
		(pad "10" smd circle
			(at 1.515618 -1.000252 270)
			(size 0 0)
			(layers "F.Cu" "F.Mask" "F.Paste")
			(net "XP1R2V_VIN")
		)
		(pad "11" smd rect
			(at 0 0 90)
			(size 1.4478 1.8034)
			(layers "F.Cu" "F.Mask" "F.Paste")
			(net "SG")
		)
	)
	(footprint ""
		(layer "F.Cu")
		(at 85.974936 -64.3128 90)
		(property "Reference" "C280"
			(at 13.2842 -9.354566 90)
			(unlocked yes)
			(layer "F.SilkS")
			(effects
				(font
					(size 0.7874 0.5842)
					(thickness 0.1524)
				)
			)
		)
		(property "Value" "VAL*"
			(at 0.0762 2.067306 90)
			(unlocked yes)
			(layer "F.Fab")
			(hide yes)
			(effects
				(font
					(size 0.7874 0.5842)
					(thickness 0.1524)
				)
			)
		)
		(property "Device Type" "CAPACITOR-G105-0C106-BM,10UF,2A"
			(at 0.0508 1.127506 90)
			(unlocked yes)
			(layer "F.Fab")
			(hide yes)
			(effects
				(font
					(size 0.7874 0.5842)
					(thickness 0.1524)
				)
			)
		)
		(property "User Part Number" "PARTNUM*"
			(at 0.1016 4.023106 90)
			(unlocked yes)
			(layer "Cmts.User")
			(hide yes)
			(effects
				(font
					(size 0.7874 0.5842)
					(thickness 0.1524)
				)
			)
		)
		(property "Tolerance" "TOL*"
			(at 0.0762 3.032506 90)
			(unlocked yes)
			(layer "Cmts.User")
			(hide yes)
			(effects
				(font
					(size 0.7874 0.5842)
					(thickness 0.1524)
				)
			)
		)
		(duplicate_pad_numbers_are_jumpers no)
		(fp_line
			(start 1.143 -0.5588)
			(end -1.143 -0.5588)
			(stroke
				(width 0.1)
				(type default)
			)
			(layer "F.SilkS")
		)
		(fp_line
			(start -1.143 -0.5588)
			(end -1.143 0.5588)
			(stroke
				(width 0.1)
				(type default)
			)
			(layer "F.SilkS")
		)
		(fp_line
			(start 1.143 0.5588)
			(end 1.143 -0.5588)
			(stroke
				(width 0.1)
				(type default)
			)
			(layer "F.SilkS")
		)
		(fp_line
			(start -1.143 0.5588)
			(end 1.143 0.5588)
			(stroke
				(width 0.1)
				(type default)
			)
			(layer "F.SilkS")
		)
		(fp_rect
			(start -1.143 -0.5588)
			(end 1.143 0.5588)
			(stroke
				(width 0)
				(type default)
			)
			(fill no)
			(layer "F.CrtYd")
		)
		(fp_line
			(start 0.508 -0.3048)
			(end -0.508 -0.3048)
			(stroke
				(width 0.1)
				(type default)
			)
			(layer "F.Fab")
		)
		(fp_line
			(start -0.508 -0.3048)
			(end -0.508 0.3048)
			(stroke
				(width 0.1)
				(type default)
			)
			(layer "F.Fab")
		)
		(fp_line
			(start 0.508 0.3048)
			(end 0.508 -0.3048)
			(stroke
				(width 0.1)
				(type default)
			)
			(layer "F.Fab")
		)
		(fp_line
			(start -0.508 0.3048)
			(end 0.508 0.3048)
			(stroke
				(width 0.1)
				(type default)
			)
			(layer "F.Fab")
		)
		(pad "1" smd rect
			(at -0.5334 0 90)
			(size 0.7112 0.6096)
			(layers "F.Cu" "F.Mask" "F.Paste")
			(net "VDD_BNO085")
		)
		(pad "2" smd rect
			(at 0.5334 0 90)
			(size 0.7112 0.6096)
			(layers "F.Cu" "F.Mask" "F.Paste")
			(net "SG")
		)
		(zone
			(layer "F.Cu")
			(hatch none 0.5)
			(connect_pads
				(clearance 0)
			)
			(min_thickness 0.25)
			(keepout
				(tracks allowed)
				(vias not_allowed)
				(pads allowed)
				(copperpour not_allowed)
				(footprints allowed)
			)
			(placement
				(enabled no)
				(sheetname "")
			)
			(fill
				(thermal_gap 0.5)
				(thermal_bridge_width 0.5)
				(island_removal_mode 0)
			)
			(polygon
				(pts
					(xy 85.670136 -64.2366) (xy 86.279736 -64.2366) (xy 86.279736 -64.389) (xy 85.670136 -64.389)
				)
			)
		)
	)
	(footprint ""
		(layer "F.Cu")
		(at 44.958 -121.539)
		(property "Reference" "SP43"
			(at 0 0 0)
			(layer "F.SilkS")
			(hide yes)
			(effects
				(font
					(size 1.27 1.27)
				)
			)
		)
		(property "Value" ""
			(at 0 0 0)
			(layer "F.Fab")
			(effects
				(font
					(size 1.27 1.27)
				)
			)
		)
		(duplicate_pad_numbers_are_jumpers no)
	)
	(footprint ""
		(layer "F.Cu")
		(at 156.845 -26.543)
		(property "Reference" "U36"
			(at -0.127 2.57937 0)
			(unlocked yes)
			(layer "F.SilkS")
			(effects
				(font
					(size 0.7874 0.5842)
					(thickness 0.1524)
				)
			)
		)
		(property "Value" ""
			(at 0 0 0)
			(layer "F.Fab")
			(effects
				(font
					(size 1.27 1.27)
				)
			)
		)
		(property "Device Type" "LM75BDP_TSSOP8-G220-10215-01"
			(at -0.03175 2.55651 0)
			(unlocked yes)
			(layer "F.Fab")
			(hide yes)
			(effects
				(font
					(size 0.7874 0.5842)
					(thickness 0.1524)
				)
			)
		)
		(property "User Part Number" "PARTNUM*"
			(at -0.037592 3.488182 0)
			(unlocked yes)
			(layer "Cmts.User")
			(hide yes)
			(effects
				(font
					(size 0.7874 0.5842)
					(thickness 0.1524)
				)
			)
		)
		(duplicate_pad_numbers_are_jumpers no)
		(fp_line
			(start -3.3147 -1.45796)
			(end -3.3147 1.45796)
			(stroke
				(width 0.1)
				(type default)
			)
			(layer "F.SilkS")
		)
		(fp_line
			(start -3.3147 1.45796)
			(end -1.778 1.45796)
			(stroke
				(width 0.1)
				(type default)
			)
			(layer "F.SilkS")
		)
		(fp_line
			(start -1.778 -1.778)
			(end -1.778 -1.45796)
			(stroke
				(width 0.1)
				(type default)
			)
			(layer "F.SilkS")
		)
		(fp_line
			(start -1.778 -1.45796)
			(end -3.3147 -1.45796)
			(stroke
				(width 0.1)
				(type default)
			)
			(layer "F.SilkS")
		)
		(fp_line
			(start -1.778 1.45796)
			(end -1.778 1.778)
			(stroke
				(width 0.1)
				(type default)
			)
			(layer "F.SilkS")
		)
		(fp_line
			(start -1.778 1.778)
			(end 1.778 1.778)
			(stroke
				(width 0.1)
				(type default)
			)
			(layer "F.SilkS")
		)
		(fp_line
			(start 1.778 -1.778)
			(end -1.778 -1.778)
			(stroke
				(width 0.1)
				(type default)
			)
			(layer "F.SilkS")
		)
		(fp_line
			(start 1.778 -1.45796)
			(end 1.778 -1.778)
			(stroke
				(width 0.1)
				(type default)
			)
			(layer "F.SilkS")
		)
		(fp_line
			(start 1.778 1.45796)
			(end 3.3147 1.45796)
			(stroke
				(width 0.1)
				(type default)
			)
			(layer "F.SilkS")
		)
		(fp_line
			(start 1.778 1.778)
			(end 1.778 1.45796)
			(stroke
				(width 0.1)
				(type default)
			)
			(layer "F.SilkS")
		)
		(fp_line
			(start 3.3147 -1.45796)
			(end 1.778 -1.45796)
			(stroke
				(width 0.1)
				(type default)
			)
			(layer "F.SilkS")
		)
		(fp_line
			(start 3.3147 1.45796)
			(end 3.3147 -1.45796)
			(stroke
				(width 0.1)
				(type default)
			)
			(layer "F.SilkS")
		)
		(fp_poly
			(pts
				(arc
					(start -3.175 -2.159)
					(mid -3.937 -2.159)
					(end -3.175 -2.159)
				)
			)
			(stroke
				(width 0)
				(type default)
			)
			(fill yes)
			(layer "F.SilkS")
		)
		(fp_rect
			(start -3.5687 2.032)
			(end 3.5687 -2.032)
			(stroke
				(width 0)
				(type default)
			)
			(fill no)
			(layer "F.CrtYd")
		)
		(fp_line
			(start -1.524 -1.524)
			(end 1.524 -1.524)
			(stroke
				(width 0.1)
				(type default)
			)
			(layer "F.Fab")
		)
		(fp_line
			(start -1.524 1.524)
			(end -1.524 -1.524)
			(stroke
				(width 0.1)
				(type default)
			)
			(layer "F.Fab")
		)
		(fp_line
			(start 1.524 -1.524)
			(end 1.524 1.524)
			(stroke
				(width 0.1)
				(type default)
			)
			(layer "F.Fab")
		)
		(fp_line
			(start 1.524 1.524)
			(end -1.524 1.524)
			(stroke
				(width 0.1)
				(type default)
			)
			(layer "F.Fab")
		)
		(fp_poly
			(pts
				(arc
					(start -0.6096 -0.9398)
					(mid -1.3716 -0.9398)
					(end -0.6096 -0.9398)
				)
			)
			(stroke
				(width 0)
				(type default)
			)
			(fill yes)
			(layer "F.Fab")
		)
		(fp_text user "5"
			(at 3.556 2.70637 0)
			(unlocked yes)
			(layer "F.SilkS")
			(effects
				(font
					(size 0.7874 0.5842)
					(thickness 0.1524)
				)
			)
		)
		(fp_text user "8"
			(at 3.937 -2.11963 0)
			(unlocked yes)
			(layer "F.SilkS")
			(effects
				(font
					(size 0.7874 0.5842)
					(thickness 0.1524)
				)
			)
		)
		(fp_text user "4"
			(at -1.8796 1.24587 0)
			(unlocked yes)
			(layer "F.Fab")
			(effects
				(font
					(size 0.7874 0.5842)
					(thickness 0.1524)
				)
			)
		)
		(fp_text user "8"
			(at 2.16281 -0.94996 0)
			(unlocked yes)
			(layer "F.Fab")
			(effects
				(font
					(size 0.7874 0.5842)
					(thickness 0.1524)
				)
			)
		)
		(fp_text user "5"
			(at 2.16281 1.08204 0)
			(unlocked yes)
			(layer "F.Fab")
			(effects
				(font
					(size 0.7874 0.5842)
					(thickness 0.1524)
				)
			)
		)
		(pad "1" smd rect
			(at -2.2987 -0.97536 90)
			(size 0.4572 1.524)
			(layers "F.Cu" "F.Mask" "F.Paste")
			(net "R_LM75B_3_I2C_SDA")
		)
		(pad "2" smd rect
			(at -2.2987 -0.32512 90)
			(size 0.4572 1.524)
			(layers "F.Cu" "F.Mask" "F.Paste")
			(net "LM75B_I2C_SCL")
		)
		(pad "3" smd rect
			(at -2.2987 0.32512 90)
			(size 0.4572 1.524)
			(layers "F.Cu" "F.Mask" "F.Paste")
			(net "FPGA_IN_LM75B_INT3_N")
		)
		(pad "4" smd rect
			(at -2.2987 0.97536 90)
			(size 0.4572 1.524)
			(layers "F.Cu" "F.Mask" "F.Paste")
			(net "SG")
		)
		(pad "5" smd rect
			(at 2.2987 0.97536 90)
			(size 0.4572 1.524)
			(layers "F.Cu" "F.Mask" "F.Paste")
			(net "UNNAMED_6_LM75BDPTSSOP8_I81_A2")
		)
		(pad "6" smd rect
			(at 2.2987 0.32512 90)
			(size 0.4572 1.524)
			(layers "F.Cu" "F.Mask" "F.Paste")
			(net "UNNAMED_6_LM75BDPTSSOP8_I81_A1")
		)
		(pad "7" smd rect
			(at 2.2987 -0.32512 90)
			(size 0.4572 1.524)
			(layers "F.Cu" "F.Mask" "F.Paste")
			(net "UNNAMED_6_LM75BDPTSSOP8_I81_A0")
		)
		(pad "8" smd rect
			(at 2.2987 -0.97536 90)
			(size 0.4572 1.524)
			(layers "F.Cu" "F.Mask" "F.Paste")
			(net "XP3R3V_FPGA")
		)
	)
	(footprint ""
		(layer "F.Cu")
		(at 15.113 -90.805 90)
		(property "Reference" "R442"
			(at 1.27 -1.10363 90)
			(unlocked yes)
			(layer "F.SilkS")
			(effects
				(font
					(size 0.7874 0.5842)
					(thickness 0.1524)
				)
			)
		)
		(property "Value" "VAL*"
			(at 0.02032 2.13233 90)
			(unlocked yes)
			(layer "F.Fab")
			(hide yes)
			(effects
				(font
					(size 0.7874 0.5842)
					(thickness 0.1524)
				)
			)
		)
		(property "Tolerance" "TOL*"
			(at 0.044704 3.05435 90)
			(unlocked yes)
			(layer "Cmts.User")
			(hide yes)
			(effects
				(font
					(size 0.7874 0.5842)
					(thickness 0.1524)
				)
			)
		)
		(property "User Part Number" "PARTNUM*"
			(at 0.02032 4.024884 90)
			(unlocked yes)
			(layer "Cmts.User")
			(hide yes)
			(effects
				(font
					(size 0.7874 0.5842)
					(thickness 0.1524)
				)
			)
		)
		(property "Device Type" "RESISTOR-G155-05101-01,5.1KOHMA"
			(at 0.008382 1.210564 90)
			(unlocked yes)
			(layer "F.Fab")
			(hide yes)
			(effects
				(font
					(size 0.7874 0.5842)
					(thickness 0.1524)
				)
			)
		)
		(duplicate_pad_numbers_are_jumpers no)
		(fp_line
			(start 1.143 -0.5588)
			(end -1.143 -0.5588)
			(stroke
				(width 0.1)
				(type default)
			)
			(layer "F.SilkS")
		)
		(fp_line
			(start -1.143 -0.5588)
			(end -1.143 0.5588)
			(stroke
				(width 0.1)
				(type default)
			)
			(layer "F.SilkS")
		)
		(fp_line
			(start 1.143 0.5588)
			(end 1.143 -0.5588)
			(stroke
				(width 0.1)
				(type default)
			)
			(layer "F.SilkS")
		)
		(fp_line
			(start -1.143 0.5588)
			(end 1.143 0.5588)
			(stroke
				(width 0.1)
				(type default)
			)
			(layer "F.SilkS")
		)
		(fp_poly
			(pts
				(xy -1.143 0.5588) (xy 1.143 0.5588) (xy 1.143 -0.5588) (xy -1.143 -0.5588)
			)
			(stroke
				(width 0)
				(type default)
			)
			(fill no)
			(layer "F.CrtYd")
		)
		(fp_line
			(start 0.508 -0.3048)
			(end -0.508 -0.3048)
			(stroke
				(width 0.1)
				(type default)
			)
			(layer "F.Fab")
		)
		(fp_line
			(start -0.508 -0.3048)
			(end -0.508 0.3048)
			(stroke
				(width 0.1)
				(type default)
			)
			(layer "F.Fab")
		)
		(fp_line
			(start 0.508 0.3048)
			(end 0.508 -0.3048)
			(stroke
				(width 0.1)
				(type default)
			)
			(layer "F.Fab")
		)
		(fp_line
			(start -0.508 0.3048)
			(end 0.508 0.3048)
			(stroke
				(width 0.1)
				(type default)
			)
			(layer "F.Fab")
		)
		(pad "1" smd rect
			(at -0.5334 0 90)
			(size 0.7112 0.6096)
			(layers "F.Cu" "F.Mask" "F.Paste")
			(net "UNNAMED_524_CONNUSB14PGH4FRATH_")
		)
		(pad "2" smd rect
			(at 0.5334 0 90)
			(size 0.7112 0.6096)
			(layers "F.Cu" "F.Mask" "F.Paste")
			(net "SG")
		)
		(zone
			(layer "F.Cu")
			(hatch none 0.5)
			(connect_pads
				(clearance 0)
			)
			(min_thickness 0.25)
			(keepout
				(tracks allowed)
				(vias not_allowed)
				(pads allowed)
				(copperpour not_allowed)
				(footprints allowed)
			)
			(placement
				(enabled no)
				(sheetname "")
			)
			(fill
				(thermal_gap 0.5)
				(thermal_bridge_width 0.5)
				(island_removal_mode 0)
			)
			(polygon
				(pts
					(xy 15.4178 -90.7288) (xy 15.4178 -90.8812) (xy 14.8082 -90.8812) (xy 14.8082 -90.7288)
				)
			)
		)
		(zone
			(layer "F.Cu")
			(hatch none 0.5)
			(connect_pads
				(clearance 0)
			)
			(min_thickness 0.25)
			(keepout
				(tracks not_allowed)
				(vias allowed)
				(pads allowed)
				(copperpour not_allowed)
				(footprints allowed)
			)
			(placement
				(enabled no)
				(sheetname "")
			)
			(fill
				(thermal_gap 0.5)
				(thermal_bridge_width 0.5)
				(island_removal_mode 0)
			)
			(polygon
				(pts
					(xy 15.4178 -90.7288) (xy 15.4178 -90.8812) (xy 14.8082 -90.8812) (xy 14.8082 -90.7288)
				)
			)
		)
	)
	(footprint ""
		(layer "F.Cu")
		(at 85.979 -54.229 180)
		(property "Reference" "TP61"
			(at 0.5842 -1.56337 0)
			(unlocked yes)
			(layer "F.SilkS")
			(effects
				(font
					(size 0.7874 0.5842)
					(thickness 0.1524)
				)
				(justify left)
			)
		)
		(property "Value" ""
			(at 0 0 180)
			(layer "F.Fab")
			(effects
				(font
					(size 1.27 1.27)
				)
			)
		)
		(property "Device Type" "TP_PIONT-TP010CT020B030_PTH-TPA"
			(at -1.341882 0.996696 180)
			(unlocked yes)
			(layer "F.Fab")
			(hide yes)
			(effects
				(font
					(size 0.7874 0.5842)
					(thickness 0.1524)
				)
				(justify left)
			)
		)
		(duplicate_pad_numbers_are_jumpers no)
		(fp_poly
			(pts
				(arc
					(start -0.889 0)
					(mid 0.889 0)
					(end -0.889 0)
				)
			)
			(stroke
				(width 0)
				(type default)
			)
			(fill no)
			(layer "B.CrtYd")
		)
		(fp_poly
			(pts
				(arc
					(start -0.889 0)
					(mid 0.889 0)
					(end -0.889 0)
				)
			)
			(stroke
				(width 0)
				(type default)
			)
			(fill no)
			(layer "F.CrtYd")
		)
		(pad "1" thru_hole circle
			(at 0 0 180)
			(size 0.508 0.508)
			(drill 0.254)
			(layers "*.Cu" "*.Mask")
			(remove_unused_layers no)
			(net "UNNAMED_9_BNO080LGA28_I29_HCS")
			(clearance 0.1016)
			(padstack
				(mode front_inner_back)
				(layer "Inner"
					(shape circle)
					(size 0.508 0.508)
					(clearance 0.1016)
				)
				(layer "B.Cu"
					(shape circle)
					(size 0.762 0.762)
					(clearance -0.0254)
				)
			)
		)
	)
	(footprint ""
		(layer "F.Cu")
		(at 92.583 -37.338 180)
		(property "Reference" "L34"
			(at 1.2065 -1.43637 0)
			(unlocked yes)
			(layer "F.SilkS")
			(effects
				(font
					(size 0.7874 0.5842)
					(thickness 0.1524)
				)
				(justify left)
			)
		)
		(property "Value" "VAL*"
			(at -0.9398 3.70967 180)
			(unlocked yes)
			(layer "F.Fab")
			(hide yes)
			(effects
				(font
					(size 0.7874 0.5842)
					(thickness 0.1524)
				)
				(justify left)
			)
		)
		(property "Device Type" "FERRITEBEAD-G191-10100-01,120OA"
			(at -0.9906 1.22047 180)
			(unlocked yes)
			(layer "F.Fab")
			(hide yes)
			(effects
				(font
					(size 0.7874 0.5842)
					(thickness 0.1524)
				)
				(justify left)
			)
		)
		(property "User Part Number" "PARTNUM*"
			(at -2.54 2.46507 180)
			(unlocked yes)
			(layer "Cmts.User")
			(hide yes)
			(effects
				(font
					(size 0.7874 0.5842)
					(thickness 0.1524)
				)
				(justify left)
			)
		)
		(property "Tolerance" "TOL*"
			(at -0.9906 5.00507 180)
			(unlocked yes)
			(layer "Cmts.User")
			(hide yes)
			(effects
				(font
					(size 0.7874 0.5842)
					(thickness 0.1524)
				)
				(justify left)
			)
		)
		(duplicate_pad_numbers_are_jumpers no)
		(fp_line
			(start 1.3208 0.7112)
			(end -1.3208 0.7112)
			(stroke
				(width 0.1)
				(type default)
			)
			(layer "F.SilkS")
		)
		(fp_line
			(start 1.3208 -0.7112)
			(end 1.3208 0.7112)
			(stroke
				(width 0.1)
				(type default)
			)
			(layer "F.SilkS")
		)
		(fp_line
			(start -1.3208 0.7112)
			(end -1.3208 -0.7112)
			(stroke
				(width 0.1)
				(type default)
			)
			(layer "F.SilkS")
		)
		(fp_line
			(start -1.3208 -0.7112)
			(end 1.3208 -0.7112)
			(stroke
				(width 0.1)
				(type default)
			)
			(layer "F.SilkS")
		)
		(fp_rect
			(start -1.3208 0.7112)
			(end 1.3208 -0.7112)
			(stroke
				(width 0)
				(type default)
			)
			(fill no)
			(layer "F.CrtYd")
		)
		(fp_line
			(start 0.8128 0.4572)
			(end -0.8128 0.4572)
			(stroke
				(width 0.1)
				(type default)
			)
			(layer "F.Fab")
		)
		(fp_line
			(start 0.8128 -0.4572)
			(end 0.8128 0.4572)
			(stroke
				(width 0.1)
				(type default)
			)
			(layer "F.Fab")
		)
		(fp_line
			(start -0.8128 0.4572)
			(end -0.8128 -0.4572)
			(stroke
				(width 0.1)
				(type default)
			)
			(layer "F.Fab")
		)
		(fp_line
			(start -0.8128 -0.4572)
			(end 0.8128 -0.4572)
			(stroke
				(width 0.1)
				(type default)
			)
			(layer "F.Fab")
		)
		(pad "1" smd rect
			(at -0.6858 0 180)
			(size 0.762 0.8636)
			(layers "F.Cu" "F.Mask" "F.Paste")
			(net "XP1R0V_FPGA_MGTAVCC")
		)
		(pad "2" smd rect
			(at 0.6858 0 180)
			(size 0.762 0.8636)
			(layers "F.Cu" "F.Mask" "F.Paste")
			(net "XP1R0V_FPGA")
		)
		(zone
			(layer "F.Cu")
			(hatch none 0.5)
			(connect_pads
				(clearance 0)
			)
			(min_thickness 0.25)
			(keepout
				(tracks not_allowed)
				(vias allowed)
				(pads allowed)
				(copperpour not_allowed)
				(footprints allowed)
			)
			(placement
				(enabled no)
				(sheetname "")
			)
			(fill
				(thermal_gap 0.5)
				(thermal_bridge_width 0.5)
				(island_removal_mode 0)
			)
			(polygon
				(pts
					(xy 92.7354 -37.7952) (xy 92.4306 -37.7952) (xy 92.4306 -36.8808) (xy 92.7354 -36.8808)
				)
			)
		)
		(zone
			(layer "F.Cu")
			(hatch none 0.5)
			(connect_pads
				(clearance 0)
			)
			(min_thickness 0.25)
			(keepout
				(tracks allowed)
				(vias not_allowed)
				(pads allowed)
				(copperpour not_allowed)
				(footprints allowed)
			)
			(placement
				(enabled no)
				(sheetname "")
			)
			(fill
				(thermal_gap 0.5)
				(thermal_bridge_width 0.5)
				(island_removal_mode 0)
			)
			(polygon
				(pts
					(xy 92.7354 -37.7952) (xy 92.4306 -37.7952) (xy 92.4306 -36.8808) (xy 92.7354 -36.8808)
				)
			)
		)
	)
	(footprint ""
		(layer "F.Cu")
		(at 86.106 -58.7756)
		(property "Reference" "U29"
			(at -3.00863 0.1016 90)
			(unlocked yes)
			(layer "F.SilkS")
			(effects
				(font
					(size 0.7874 0.5842)
					(thickness 0.1524)
				)
			)
		)
		(property "Value" ""
			(at 0 0 0)
			(layer "F.Fab")
			(effects
				(font
					(size 1.27 1.27)
				)
			)
		)
		(property "Device Type" "BNO080_LGA_28-A246-00002-FB,BNA"
			(at 0.040894 5.13842 0)
			(unlocked yes)
			(layer "F.Fab")
			(hide yes)
			(effects
				(font
					(size 0.7874 0.5842)
					(thickness 0.1524)
				)
			)
		)
		(property "User Part Number" "PARTNUM*"
			(at 0.040894 6.33222 0)
			(unlocked yes)
			(layer "Cmts.User")
			(hide yes)
			(effects
				(font
					(size 0.7874 0.5842)
					(thickness 0.1524)
				)
			)
		)
		(duplicate_pad_numbers_are_jumpers no)
		(fp_line
			(start -2.159508 -2.858516)
			(end 2.159508 -2.858516)
			(stroke
				(width 0.1)
				(type default)
			)
			(layer "F.SilkS")
		)
		(fp_line
			(start -2.159508 2.858516)
			(end -2.159508 -2.858516)
			(stroke
				(width 0.1)
				(type default)
			)
			(layer "F.SilkS")
		)
		(fp_line
			(start 2.159508 -2.858516)
			(end 2.159508 2.858516)
			(stroke
				(width 0.1)
				(type default)
			)
			(layer "F.SilkS")
		)
		(fp_line
			(start 2.159508 2.858516)
			(end -2.159508 2.858516)
			(stroke
				(width 0.1)
				(type default)
			)
			(layer "F.SilkS")
		)
		(fp_poly
			(pts
				(arc
					(start 3.302 -3.0734)
					(mid 2.286 -3.0734)
					(end 3.302 -3.0734)
				)
			)
			(stroke
				(width 0)
				(type default)
			)
			(fill yes)
			(layer "F.SilkS")
		)
		(fp_rect
			(start -2.413508 3.112516)
			(end 2.413508 -3.112516)
			(stroke
				(width 0)
				(type default)
			)
			(fill no)
			(layer "F.CrtYd")
		)
		(fp_line
			(start -1.89992 -2.599944)
			(end 1.89992 -2.599944)
			(stroke
				(width 0.1)
				(type default)
			)
			(layer "F.Fab")
		)
		(fp_line
			(start -1.89992 2.599944)
			(end -1.89992 -2.599944)
			(stroke
				(width 0.1)
				(type default)
			)
			(layer "F.Fab")
		)
		(fp_line
			(start 1.89992 -2.599944)
			(end 1.89992 2.599944)
			(stroke
				(width 0.1)
				(type default)
			)
			(layer "F.Fab")
		)
		(fp_line
			(start 1.89992 2.599944)
			(end -1.89992 2.599944)
			(stroke
				(width 0.1)
				(type default)
			)
			(layer "F.Fab")
		)
		(fp_poly
			(pts
				(arc
					(start 3.837686 -2.743962)
					(mid 2.821686 -2.743962)
					(end 3.837686 -2.743962)
				)
			)
			(stroke
				(width 0)
				(type default)
			)
			(fill yes)
			(layer "F.Fab")
		)
		(fp_text user "6"
			(at -2.509012 -2.331466 0)
			(unlocked yes)
			(layer "F.SilkS")
			(effects
				(font
					(size 0.635 0.4064)
					(thickness 0.1524)
				)
				(justify right)
			)
		)
		(fp_text user "15"
			(at -2.3114 2.03835 0)
			(unlocked yes)
			(layer "F.SilkS")
			(effects
				(font
					(size 0.635 0.4064)
					(thickness 0.1524)
				)
				(justify right)
			)
		)
		(fp_text user "5"
			(at -0.913638 -3.423666 0)
			(unlocked yes)
			(layer "F.SilkS")
			(effects
				(font
					(size 0.635 0.4064)
					(thickness 0.1524)
				)
			)
		)
		(fp_text user "2"
			(at 0.818134 -3.491738 0)
			(unlocked yes)
			(layer "F.SilkS")
			(effects
				(font
					(size 0.635 0.4064)
					(thickness 0.1524)
				)
			)
		)
		(fp_text user "28"
			(at 2.3114 -2.02565 0)
			(unlocked yes)
			(layer "F.SilkS")
			(effects
				(font
					(size 0.635 0.4064)
					(thickness 0.1524)
				)
				(justify left)
			)
		)
		(fp_text user "20"
			(at 2.413508 1.964182 0)
			(unlocked yes)
			(layer "F.SilkS")
			(effects
				(font
					(size 0.635 0.4064)
					(thickness 0.1524)
				)
				(justify left)
			)
		)
		(fp_text user "6"
			(at -2.509012 -2.400046 0)
			(unlocked yes)
			(layer "F.Fab")
			(effects
				(font
					(size 0.7874 0.5842)
					(thickness 0.1524)
				)
				(justify right)
			)
		)
		(fp_text user "15"
			(at -2.454148 2.372106 0)
			(unlocked yes)
			(layer "F.Fab")
			(effects
				(font
					(size 0.7874 0.5842)
					(thickness 0.1524)
				)
				(justify right)
			)
		)
		(fp_text user "5"
			(at -0.913638 -3.238246 0)
			(unlocked yes)
			(layer "F.Fab")
			(effects
				(font
					(size 0.7874 0.5842)
					(thickness 0.1524)
				)
			)
		)
		(fp_text user "16"
			(at -0.60071 3.35788 0)
			(unlocked yes)
			(layer "F.Fab")
			(effects
				(font
					(size 0.7874 0.5842)
					(thickness 0.1524)
				)
			)
		)
		(fp_text user "2"
			(at 0.818134 -3.306318 0)
			(unlocked yes)
			(layer "F.Fab")
			(effects
				(font
					(size 0.7874 0.5842)
					(thickness 0.1524)
				)
			)
		)
		(fp_text user "19"
			(at 1.36271 3.316986 0)
			(unlocked yes)
			(layer "F.Fab")
			(effects
				(font
					(size 0.7874 0.5842)
					(thickness 0.1524)
				)
			)
		)
		(fp_text user "28"
			(at 2.372868 -1.668526 0)
			(unlocked yes)
			(layer "F.Fab")
			(effects
				(font
					(size 0.7874 0.5842)
					(thickness 0.1524)
				)
				(justify left)
			)
		)
		(fp_text user "20"
			(at 2.413508 1.895602 0)
			(unlocked yes)
			(layer "F.Fab")
			(effects
				(font
					(size 0.7874 0.5842)
					(thickness 0.1524)
				)
				(justify left)
			)
		)
		(pad "1" smd rect
			(at 1.562608 -2.249932)
			(size 0.6858 0.254)
			(layers "F.Cu" "F.Mask" "F.Paste")
			(net "Net_782")
		)
		(pad "2" smd rect
			(at 0.750062 -2.312416)
			(size 0.254 0.5842)
			(layers "F.Cu" "F.Mask" "F.Paste")
			(net "SG")
		)
		(pad "3" smd rect
			(at 0.249936 -2.312416)
			(size 0.254 0.5842)
			(layers "F.Cu" "F.Mask" "F.Paste")
			(net "VDD_BNO085")
		)
		(pad "4" smd rect
			(at -0.249936 -2.312416)
			(size 0.254 0.5842)
			(layers "F.Cu" "F.Mask" "F.Paste")
			(net "R_BNO080_BOOT_N")
		)
		(pad "5" smd rect
			(at -0.750062 -2.312416)
			(size 0.254 0.5842)
			(layers "F.Cu" "F.Mask" "F.Paste")
			(net "UNNAMED_9_BNO080LGA28_I29_PS1")
		)
		(pad "6" smd rect
			(at -1.562608 -2.249932)
			(size 0.6858 0.254)
			(layers "F.Cu" "F.Mask" "F.Paste")
			(net "UNNAMED_9_BNO080LGA28_I29_PS0")
		)
		(pad "7" smd rect
			(at -1.562608 -1.75006)
			(size 0.6858 0.254)
			(layers "F.Cu" "F.Mask" "F.Paste")
			(net "Net_781")
		)
		(pad "8" smd rect
			(at -1.562608 -1.249934)
			(size 0.6858 0.254)
			(layers "F.Cu" "F.Mask" "F.Paste")
			(net "Net_780")
		)
		(pad "9" smd rect
			(at -1.562608 -0.750062)
			(size 0.6858 0.254)
			(layers "F.Cu" "F.Mask" "F.Paste")
			(net "UNNAMED_9_BNO080LGA28_I29_CAP")
		)
		(pad "10" smd rect
			(at -1.562608 -0.249936)
			(size 0.6858 0.254)
			(layers "F.Cu" "F.Mask" "F.Paste")
			(net "UNNAMED_9_BNO080LGA28_I29_CLKSE")
		)
		(pad "11" smd rect
			(at -1.562608 0.249936)
			(size 0.6858 0.254)
			(layers "F.Cu" "F.Mask" "F.Paste")
			(net "R_BNO080_RST_N")
		)
		(pad "12" smd rect
			(at -1.562608 0.750062)
			(size 0.6858 0.254)
			(layers "F.Cu" "F.Mask" "F.Paste")
			(net "Net_779")
		)
		(pad "13" smd rect
			(at -1.562608 1.249934)
			(size 0.6858 0.254)
			(layers "F.Cu" "F.Mask" "F.Paste")
			(net "Net_778")
		)
		(pad "14" smd rect
			(at -1.562608 1.75006)
			(size 0.6858 0.254)
			(layers "F.Cu" "F.Mask" "F.Paste")
			(net "R_BNO080_INT_N")
		)
		(pad "15" smd rect
			(at -1.562608 2.249932)
			(size 0.6858 0.254)
			(layers "F.Cu" "F.Mask" "F.Paste")
			(net "R_BNO080_EVN_SCL")
		)
		(pad "16" smd rect
			(at -0.750062 2.312416)
			(size 0.254 0.5842)
			(layers "F.Cu" "F.Mask" "F.Paste")
			(net "R_BNO080_EVN_SDA")
		)
		(pad "17" smd rect
			(at -0.249936 2.312416)
			(size 0.254 0.5842)
			(layers "F.Cu" "F.Mask" "F.Paste")
			(net "BNO080_SA0")
		)
		(pad "18" smd rect
			(at 0.249936 2.312416)
			(size 0.254 0.5842)
			(layers "F.Cu" "F.Mask" "F.Paste")
			(net "UNNAMED_9_BNO080LGA28_I29_HCS")
		)
		(pad "19" smd rect
			(at 0.750062 2.312416)
			(size 0.254 0.5842)
			(layers "F.Cu" "F.Mask" "F.Paste")
			(net "R_BNO080_I2C_SCL")
		)
		(pad "20" smd rect
			(at 1.562608 2.249932)
			(size 0.6858 0.254)
			(layers "F.Cu" "F.Mask" "F.Paste")
			(net "R_BNO080_I2C_SDA")
		)
		(pad "21" smd rect
			(at 1.562608 1.75006)
			(size 0.6858 0.254)
			(layers "F.Cu" "F.Mask" "F.Paste")
			(net "Net_777")
		)
		(pad "22" smd rect
			(at 1.562608 1.249934)
			(size 0.6858 0.254)
			(layers "F.Cu" "F.Mask" "F.Paste")
			(net "Net_776")
		)
		(pad "23" smd rect
			(at 1.562608 0.750062)
			(size 0.6858 0.254)
			(layers "F.Cu" "F.Mask" "F.Paste")
			(net "Net_775")
		)
		(pad "24" smd rect
			(at 1.562608 0.249936)
			(size 0.6858 0.254)
			(layers "F.Cu" "F.Mask" "F.Paste")
			(net "Net_774")
		)
		(pad "25" smd rect
			(at 1.562608 -0.249936)
			(size 0.6858 0.254)
			(layers "F.Cu" "F.Mask" "F.Paste")
			(net "SG")
		)
		(pad "26" smd rect
			(at 1.562608 -0.750062)
			(size 0.6858 0.254)
			(layers "F.Cu" "F.Mask" "F.Paste")
			(net "UNNAMED_9_BNO080LGA28_I29_XOUT3")
		)
		(pad "27" smd rect
			(at 1.562608 -1.249934)
			(size 0.6858 0.254)
			(layers "F.Cu" "F.Mask" "F.Paste")
			(net "UNNAMED_9_CAPACITOR_I17_1")
		)
		(pad "28" smd rect
			(at 1.562608 -1.75006)
			(size 0.6858 0.254)
			(layers "F.Cu" "F.Mask" "F.Paste")
			(net "VDD_BNO085")
		)
	)
	(footprint ""
		(layer "F.Cu")
		(at 20.32 -26.67 180)
		(property "Reference" "R388"
			(at -3.429 -0.67437 0)
			(unlocked yes)
			(layer "F.SilkS")
			(effects
				(font
					(size 0.7874 0.5842)
					(thickness 0.1524)
				)
			)
		)
		(property "Value" "VAL*"
			(at 0.02032 2.13233 180)
			(unlocked yes)
			(layer "F.Fab")
			(hide yes)
			(effects
				(font
					(size 0.7874 0.5842)
					(thickness 0.1524)
				)
			)
		)
		(property "Tolerance" "TOL*"
			(at 0.044704 3.05435 180)
			(unlocked yes)
			(layer "Cmts.User")
			(hide yes)
			(effects
				(font
					(size 0.7874 0.5842)
					(thickness 0.1524)
				)
			)
		)
		(property "User Part Number" "PARTNUM*"
			(at 0.02032 4.024884 180)
			(unlocked yes)
			(layer "Cmts.User")
			(hide yes)
			(effects
				(font
					(size 0.7874 0.5842)
					(thickness 0.1524)
				)
			)
		)
		(property "Device Type" "RESISTOR-G155-133R0-01,33OHM,1%"
			(at 0.008382 1.210564 180)
			(unlocked yes)
			(layer "F.Fab")
			(hide yes)
			(effects
				(font
					(size 0.7874 0.5842)
					(thickness 0.1524)
				)
			)
		)
		(duplicate_pad_numbers_are_jumpers no)
		(fp_line
			(start 1.143 0.5588)
			(end 1.143 -0.5588)
			(stroke
				(width 0.1)
				(type default)
			)
			(layer "F.SilkS")
		)
		(fp_line
			(start 1.143 -0.5588)
			(end -1.143 -0.5588)
			(stroke
				(width 0.1)
				(type default)
			)
			(layer "F.SilkS")
		)
		(fp_line
			(start -1.143 0.5588)
			(end 1.143 0.5588)
			(stroke
				(width 0.1)
				(type default)
			)
			(layer "F.SilkS")
		)
		(fp_line
			(start -1.143 -0.5588)
			(end -1.143 0.5588)
			(stroke
				(width 0.1)
				(type default)
			)
			(layer "F.SilkS")
		)
		(fp_rect
			(start -1.143 -0.5588)
			(end 1.143 0.5588)
			(stroke
				(width 0)
				(type default)
			)
			(fill no)
			(layer "F.CrtYd")
		)
		(fp_line
			(start 0.508 0.3048)
			(end 0.508 -0.3048)
			(stroke
				(width 0.1)
				(type default)
			)
			(layer "F.Fab")
		)
		(fp_line
			(start 0.508 -0.3048)
			(end -0.508 -0.3048)
			(stroke
				(width 0.1)
				(type default)
			)
			(layer "F.Fab")
		)
		(fp_line
			(start -0.508 0.3048)
			(end 0.508 0.3048)
			(stroke
				(width 0.1)
				(type default)
			)
			(layer "F.Fab")
		)
		(fp_line
			(start -0.508 -0.3048)
			(end -0.508 0.3048)
			(stroke
				(width 0.1)
				(type default)
			)
			(layer "F.Fab")
		)
		(pad "1" smd rect
			(at -0.5334 0 180)
			(size 0.7112 0.6096)
			(layers "F.Cu" "F.Mask" "F.Paste")
			(net "SMA2_LED_BLUE_N")
		)
		(pad "2" smd rect
			(at 0.5334 0 180)
			(size 0.7112 0.6096)
			(layers "F.Cu" "F.Mask" "F.Paste")
			(net "UNNAMED_14_LED4PV14_I266_1")
		)
		(zone
			(layer "F.Cu")
			(hatch none 0.5)
			(connect_pads
				(clearance 0)
			)
			(min_thickness 0.25)
			(keepout
				(tracks not_allowed)
				(vias allowed)
				(pads allowed)
				(copperpour not_allowed)
				(footprints allowed)
			)
			(placement
				(enabled no)
				(sheetname "")
			)
			(fill
				(thermal_gap 0.5)
				(thermal_bridge_width 0.5)
				(island_removal_mode 0)
			)
			(polygon
				(pts
					(xy 20.3962 -26.3652) (xy 20.3962 -26.9748) (xy 20.2438 -26.9748) (xy 20.2438 -26.3652)
				)
			)
		)
		(zone
			(layer "F.Cu")
			(hatch none 0.5)
			(connect_pads
				(clearance 0)
			)
			(min_thickness 0.25)
			(keepout
				(tracks allowed)
				(vias not_allowed)
				(pads allowed)
				(copperpour not_allowed)
				(footprints allowed)
			)
			(placement
				(enabled no)
				(sheetname "")
			)
			(fill
				(thermal_gap 0.5)
				(thermal_bridge_width 0.5)
				(island_removal_mode 0)
			)
			(polygon
				(pts
					(xy 20.3962 -26.3652) (xy 20.3962 -26.9748) (xy 20.2438 -26.9748) (xy 20.2438 -26.3652)
				)
			)
		)
	)
	(footprint ""
		(layer "F.Cu")
		(at 162.56 -24.511 180)
		(property "Reference" "R410"
			(at -0.508 -1.56337 0)
			(unlocked yes)
			(layer "F.SilkS")
			(effects
				(font
					(size 0.7874 0.5842)
					(thickness 0.1524)
				)
			)
		)
		(property "Value" "VAL*"
			(at 0.02032 2.13233 180)
			(unlocked yes)
			(layer "F.Fab")
			(hide yes)
			(effects
				(font
					(size 0.7874 0.5842)
					(thickness 0.1524)
				)
			)
		)
		(property "Tolerance" "TOL*"
			(at 0.044704 3.05435 180)
			(unlocked yes)
			(layer "Cmts.User")
			(hide yes)
			(effects
				(font
					(size 0.7874 0.5842)
					(thickness 0.1524)
				)
			)
		)
		(property "User Part Number" "PARTNUM*"
			(at 0.02032 4.024884 180)
			(unlocked yes)
			(layer "Cmts.User")
			(hide yes)
			(effects
				(font
					(size 0.7874 0.5842)
					(thickness 0.1524)
				)
			)
		)
		(property "Device Type" "RESISTOR-G155-14701-01,4.7KOHMA"
			(at 0.008382 1.210564 180)
			(unlocked yes)
			(layer "F.Fab")
			(hide yes)
			(effects
				(font
					(size 0.7874 0.5842)
					(thickness 0.1524)
				)
			)
		)
		(duplicate_pad_numbers_are_jumpers no)
		(fp_line
			(start 1.143 0.5588)
			(end 1.143 -0.5588)
			(stroke
				(width 0.1)
				(type default)
			)
			(layer "F.SilkS")
		)
		(fp_line
			(start 1.143 -0.5588)
			(end -1.143 -0.5588)
			(stroke
				(width 0.1)
				(type default)
			)
			(layer "F.SilkS")
		)
		(fp_line
			(start -1.143 0.5588)
			(end 1.143 0.5588)
			(stroke
				(width 0.1)
				(type default)
			)
			(layer "F.SilkS")
		)
		(fp_line
			(start -1.143 -0.5588)
			(end -1.143 0.5588)
			(stroke
				(width 0.1)
				(type default)
			)
			(layer "F.SilkS")
		)
		(fp_rect
			(start 1.143 0.5588)
			(end -1.143 -0.5588)
			(stroke
				(width 0)
				(type default)
			)
			(fill no)
			(layer "F.CrtYd")
		)
		(fp_line
			(start 0.508 0.3048)
			(end 0.508 -0.3048)
			(stroke
				(width 0.1)
				(type default)
			)
			(layer "F.Fab")
		)
		(fp_line
			(start 0.508 -0.3048)
			(end -0.508 -0.3048)
			(stroke
				(width 0.1)
				(type default)
			)
			(layer "F.Fab")
		)
		(fp_line
			(start -0.508 0.3048)
			(end 0.508 0.3048)
			(stroke
				(width 0.1)
				(type default)
			)
			(layer "F.Fab")
		)
		(fp_line
			(start -0.508 -0.3048)
			(end -0.508 0.3048)
			(stroke
				(width 0.1)
				(type default)
			)
			(layer "F.Fab")
		)
		(pad "1" smd rect
			(at -0.5334 0 180)
			(size 0.7112 0.6096)
			(layers "F.Cu" "F.Mask" "F.Paste")
			(net "XP3R3V_FPGA")
		)
		(pad "2" smd rect
			(at 0.5334 0 180)
			(size 0.7112 0.6096)
			(layers "F.Cu" "F.Mask" "F.Paste")
			(net "UNNAMED_6_LM75BDPTSSOP8_I81_A2")
		)
		(zone
			(layer "F.Cu")
			(hatch none 0.5)
			(connect_pads
				(clearance 0)
			)
			(min_thickness 0.25)
			(keepout
				(tracks allowed)
				(vias not_allowed)
				(pads allowed)
				(copperpour not_allowed)
				(footprints allowed)
			)
			(placement
				(enabled no)
				(sheetname "")
			)
			(fill
				(thermal_gap 0.5)
				(thermal_bridge_width 0.5)
				(island_removal_mode 0)
			)
			(polygon
				(pts
					(xy 162.4838 -24.8158) (xy 162.4838 -24.2062) (xy 162.6362 -24.2062) (xy 162.6362 -24.8158)
				)
			)
		)
		(zone
			(layer "F.Cu")
			(hatch none 0.5)
			(connect_pads
				(clearance 0)
			)
			(min_thickness 0.25)
			(keepout
				(tracks not_allowed)
				(vias allowed)
				(pads allowed)
				(copperpour not_allowed)
				(footprints allowed)
			)
			(placement
				(enabled no)
				(sheetname "")
			)
			(fill
				(thermal_gap 0.5)
				(thermal_bridge_width 0.5)
				(island_removal_mode 0)
			)
			(polygon
				(pts
					(xy 162.4838 -24.8158) (xy 162.4838 -24.2062) (xy 162.6362 -24.2062) (xy 162.6362 -24.8158)
				)
			)
		)
	)
	(footprint ""
		(layer "F.Cu")
		(at 153.924 -59.0296 180)
		(property "Reference" "L17"
			(at 0 1.51003 0)
			(unlocked yes)
			(layer "F.SilkS")
			(effects
				(font
					(size 0.7874 0.5842)
					(thickness 0.1524)
				)
			)
		)
		(property "Value" "VAL*"
			(at 0.014732 2.526538 180)
			(unlocked yes)
			(layer "F.Fab")
			(hide yes)
			(effects
				(font
					(size 0.7874 0.5842)
					(thickness 0.000001)
				)
			)
		)
		(property "Tolerance" "TOL*"
			(at 0.014732 3.503676 180)
			(unlocked yes)
			(layer "Cmts.User")
			(hide yes)
			(effects
				(font
					(size 0.7874 0.5842)
					(thickness 0.000001)
				)
			)
		)
		(property "User Part Number" "PARTNUM*"
			(at 0.02794 4.480814 180)
			(unlocked yes)
			(layer "Cmts.User")
			(hide yes)
			(effects
				(font
					(size 0.7874 0.5842)
					(thickness 0.000001)
				)
			)
		)
		(property "Device Type" "FERRITEBEAD-G191-10097-01,600OA"
			(at 0.014732 1.600708 180)
			(unlocked yes)
			(layer "F.Fab")
			(hide yes)
			(effects
				(font
					(size 0.7874 0.5842)
					(thickness 0.000001)
				)
			)
		)
		(duplicate_pad_numbers_are_jumpers no)
		(fp_line
			(start 1.3208 0.7112)
			(end -1.3208 0.7112)
			(stroke
				(width 0.1)
				(type default)
			)
			(layer "F.SilkS")
		)
		(fp_line
			(start 1.3208 -0.7112)
			(end 1.3208 0.7112)
			(stroke
				(width 0.1)
				(type default)
			)
			(layer "F.SilkS")
		)
		(fp_line
			(start -1.3208 0.7112)
			(end -1.3208 -0.7112)
			(stroke
				(width 0.1)
				(type default)
			)
			(layer "F.SilkS")
		)
		(fp_line
			(start -1.3208 -0.7112)
			(end 1.3208 -0.7112)
			(stroke
				(width 0.1)
				(type default)
			)
			(layer "F.SilkS")
		)
		(fp_rect
			(start -1.3208 0.7112)
			(end 1.3208 -0.7112)
			(stroke
				(width 0)
				(type default)
			)
			(fill no)
			(layer "F.CrtYd")
		)
		(fp_line
			(start 0.8128 0.4572)
			(end -0.8128 0.4572)
			(stroke
				(width 0.1)
				(type default)
			)
			(layer "F.Fab")
		)
		(fp_line
			(start 0.8128 -0.4572)
			(end 0.8128 0.4572)
			(stroke
				(width 0.1)
				(type default)
			)
			(layer "F.Fab")
		)
		(fp_line
			(start -0.8128 0.4572)
			(end -0.8128 -0.4572)
			(stroke
				(width 0.1)
				(type default)
			)
			(layer "F.Fab")
		)
		(fp_line
			(start -0.8128 -0.4572)
			(end 0.8128 -0.4572)
			(stroke
				(width 0.1)
				(type default)
			)
			(layer "F.Fab")
		)
		(pad "1" smd rect
			(at -0.6858 0 180)
			(size 0.762 0.8636)
			(layers "F.Cu" "F.Mask" "F.Paste")
			(net "XP3R3V_FPGA")
		)
		(pad "2" smd rect
			(at 0.6858 0 180)
			(size 0.762 0.8636)
			(layers "F.Cu" "F.Mask" "F.Paste")
			(net "VDD3V3_SHT31A")
		)
		(zone
			(layer "F.Cu")
			(hatch none 0.5)
			(connect_pads
				(clearance 0)
			)
			(min_thickness 0.25)
			(keepout
				(tracks allowed)
				(vias not_allowed)
				(pads allowed)
				(copperpour not_allowed)
				(footprints allowed)
			)
			(placement
				(enabled no)
				(sheetname "")
			)
			(fill
				(thermal_gap 0.5)
				(thermal_bridge_width 0.5)
				(island_removal_mode 0)
			)
			(polygon
				(pts
					(xy 154.0764 -59.4868) (xy 153.7716 -59.4868) (xy 153.7716 -58.5724) (xy 154.0764 -58.5724)
				)
			)
		)
		(zone
			(layer "F.Cu")
			(hatch none 0.5)
			(connect_pads
				(clearance 0)
			)
			(min_thickness 0.25)
			(keepout
				(tracks not_allowed)
				(vias allowed)
				(pads allowed)
				(copperpour not_allowed)
				(footprints allowed)
			)
			(placement
				(enabled no)
				(sheetname "")
			)
			(fill
				(thermal_gap 0.5)
				(thermal_bridge_width 0.5)
				(island_removal_mode 0)
			)
			(polygon
				(pts
					(xy 154.0764 -59.4868) (xy 153.7716 -59.4868) (xy 153.7716 -58.5724) (xy 154.0764 -58.5724)
				)
			)
		)
	)
	(footprint ""
		(layer "F.Cu")
		(at 124.587 -44.831 180)
		(property "Reference" "R211"
			(at -3.048 1.35763 0)
			(unlocked yes)
			(layer "F.SilkS")
			(effects
				(font
					(size 0.7874 0.5842)
					(thickness 0.1524)
				)
			)
		)
		(property "Value" "VAL*"
			(at 0.02032 2.13233 180)
			(unlocked yes)
			(layer "F.Fab")
			(hide yes)
			(effects
				(font
					(size 0.7874 0.5842)
					(thickness 0.1524)
				)
			)
		)
		(property "Device Type" "RESISTOR-G155-11000-01,100OHM,A"
			(at 0.008382 1.210564 180)
			(unlocked yes)
			(layer "F.Fab")
			(hide yes)
			(effects
				(font
					(size 0.7874 0.5842)
					(thickness 0.1524)
				)
			)
		)
		(property "User Part Number" "PARTNUM*"
			(at 0.02032 4.024884 180)
			(unlocked yes)
			(layer "Cmts.User")
			(hide yes)
			(effects
				(font
					(size 0.7874 0.5842)
					(thickness 0.1524)
				)
			)
		)
		(property "Tolerance" "TOL*"
			(at 0.044704 3.05435 180)
			(unlocked yes)
			(layer "Cmts.User")
			(hide yes)
			(effects
				(font
					(size 0.7874 0.5842)
					(thickness 0.1524)
				)
			)
		)
		(duplicate_pad_numbers_are_jumpers no)
		(fp_line
			(start 1.143 0.5588)
			(end 1.143 -0.5588)
			(stroke
				(width 0.1)
				(type default)
			)
			(layer "F.SilkS")
		)
		(fp_line
			(start 1.143 -0.5588)
			(end -1.143 -0.5588)
			(stroke
				(width 0.1)
				(type default)
			)
			(layer "F.SilkS")
		)
		(fp_line
			(start -1.143 0.5588)
			(end 1.143 0.5588)
			(stroke
				(width 0.1)
				(type default)
			)
			(layer "F.SilkS")
		)
		(fp_line
			(start -1.143 -0.5588)
			(end -1.143 0.5588)
			(stroke
				(width 0.1)
				(type default)
			)
			(layer "F.SilkS")
		)
		(fp_rect
			(start 1.143 0.5588)
			(end -1.143 -0.5588)
			(stroke
				(width 0)
				(type default)
			)
			(fill no)
			(layer "F.CrtYd")
		)
		(fp_line
			(start 0.508 0.3048)
			(end 0.508 -0.3048)
			(stroke
				(width 0.1)
				(type default)
			)
			(layer "F.Fab")
		)
		(fp_line
			(start 0.508 -0.3048)
			(end -0.508 -0.3048)
			(stroke
				(width 0.1)
				(type default)
			)
			(layer "F.Fab")
		)
		(fp_line
			(start -0.508 0.3048)
			(end 0.508 0.3048)
			(stroke
				(width 0.1)
				(type default)
			)
			(layer "F.Fab")
		)
		(fp_line
			(start -0.508 -0.3048)
			(end -0.508 0.3048)
			(stroke
				(width 0.1)
				(type default)
			)
			(layer "F.Fab")
		)
		(pad "1" smd rect
			(at -0.5334 0 180)
			(size 0.7112 0.6096)
			(layers "F.Cu" "F.Mask" "F.Paste")
			(net "XP3R3V_FPGA")
		)
		(pad "2" smd rect
			(at 0.5334 0 180)
			(size 0.7112 0.6096)
			(layers "F.Cu" "F.Mask" "F.Paste")
			(net "FPGA_M0")
		)
		(zone
			(layer "F.Cu")
			(hatch none 0.5)
			(connect_pads
				(clearance 0)
			)
			(min_thickness 0.25)
			(keepout
				(tracks allowed)
				(vias not_allowed)
				(pads allowed)
				(copperpour not_allowed)
				(footprints allowed)
			)
			(placement
				(enabled no)
				(sheetname "")
			)
			(fill
				(thermal_gap 0.5)
				(thermal_bridge_width 0.5)
				(island_removal_mode 0)
			)
			(polygon
				(pts
					(xy 124.5108 -45.1358) (xy 124.5108 -44.5262) (xy 124.6632 -44.5262) (xy 124.6632 -45.1358)
				)
			)
		)
	)
	(footprint ""
		(layer "F.Cu")
		(at 44.069 -130.429)
		(property "Reference" "SP64"
			(at 0 0 0)
			(layer "F.SilkS")
			(hide yes)
			(effects
				(font
					(size 1.27 1.27)
				)
			)
		)
		(property "Value" ""
			(at 0 0 0)
			(layer "F.Fab")
			(effects
				(font
					(size 1.27 1.27)
				)
			)
		)
		(duplicate_pad_numbers_are_jumpers no)
	)
	(footprint ""
		(layer "F.Cu")
		(at 131.6482 -65.8368 180)
		(property "Reference" "C197"
			(at -0.635 -4.10337 0)
			(unlocked yes)
			(layer "F.SilkS")
			(effects
				(font
					(size 0.7874 0.5842)
					(thickness 0.1524)
				)
			)
		)
		(property "Value" "VAL*"
			(at 0.0762 2.067306 180)
			(unlocked yes)
			(layer "F.Fab")
			(hide yes)
			(effects
				(font
					(size 0.7874 0.5842)
					(thickness 0.1524)
				)
			)
		)
		(property "Device Type" "CAPACITOR-G105-0B104-EK,0.1UF,A"
			(at 0.0508 1.127506 180)
			(unlocked yes)
			(layer "F.Fab")
			(hide yes)
			(effects
				(font
					(size 0.7874 0.5842)
					(thickness 0.1524)
				)
			)
		)
		(property "User Part Number" "PARTNUM*"
			(at 0.1016 4.023106 180)
			(unlocked yes)
			(layer "Cmts.User")
			(hide yes)
			(effects
				(font
					(size 0.7874 0.5842)
					(thickness 0.1524)
				)
			)
		)
		(property "Tolerance" "TOL*"
			(at 0.0762 3.032506 180)
			(unlocked yes)
			(layer "Cmts.User")
			(hide yes)
			(effects
				(font
					(size 0.7874 0.5842)
					(thickness 0.1524)
				)
			)
		)
		(duplicate_pad_numbers_are_jumpers no)
		(fp_line
			(start 1.143 0.5588)
			(end 1.143 -0.5588)
			(stroke
				(width 0.1)
				(type default)
			)
			(layer "F.SilkS")
		)
		(fp_line
			(start 1.143 -0.5588)
			(end -1.143 -0.5588)
			(stroke
				(width 0.1)
				(type default)
			)
			(layer "F.SilkS")
		)
		(fp_line
			(start -1.143 0.5588)
			(end 1.143 0.5588)
			(stroke
				(width 0.1)
				(type default)
			)
			(layer "F.SilkS")
		)
		(fp_line
			(start -1.143 -0.5588)
			(end -1.143 0.5588)
			(stroke
				(width 0.1)
				(type default)
			)
			(layer "F.SilkS")
		)
		(fp_rect
			(start -1.143 0.5588)
			(end 1.143 -0.5588)
			(stroke
				(width 0)
				(type default)
			)
			(fill no)
			(layer "F.CrtYd")
		)
		(fp_line
			(start 0.508 0.3048)
			(end 0.508 -0.3048)
			(stroke
				(width 0.1)
				(type default)
			)
			(layer "F.Fab")
		)
		(fp_line
			(start 0.508 -0.3048)
			(end -0.508 -0.3048)
			(stroke
				(width 0.1)
				(type default)
			)
			(layer "F.Fab")
		)
		(fp_line
			(start -0.508 0.3048)
			(end 0.508 0.3048)
			(stroke
				(width 0.1)
				(type default)
			)
			(layer "F.Fab")
		)
		(fp_line
			(start -0.508 -0.3048)
			(end -0.508 0.3048)
			(stroke
				(width 0.1)
				(type default)
			)
			(layer "F.Fab")
		)
		(pad "1" smd rect
			(at -0.5334 0 180)
			(size 0.7112 0.6096)
			(layers "F.Cu" "F.Mask" "F.Paste")
			(net "XP1R8V_FPGA")
		)
		(pad "2" smd rect
			(at 0.5334 0 180)
			(size 0.7112 0.6096)
			(layers "F.Cu" "F.Mask" "F.Paste")
			(net "SG")
		)
		(zone
			(layer "F.Cu")
			(hatch none 0.5)
			(connect_pads
				(clearance 0)
			)
			(min_thickness 0.25)
			(keepout
				(tracks allowed)
				(vias not_allowed)
				(pads allowed)
				(copperpour not_allowed)
				(footprints allowed)
			)
			(placement
				(enabled no)
				(sheetname "")
			)
			(fill
				(thermal_gap 0.5)
				(thermal_bridge_width 0.5)
				(island_removal_mode 0)
			)
			(polygon
				(pts
					(xy 131.7244 -66.1416) (xy 131.572 -66.1416) (xy 131.572 -65.532) (xy 131.7244 -65.532)
				)
			)
		)
	)
	(footprint ""
		(layer "F.Cu")
		(at 103.632 -83.058)
		(property "Reference" "TP13"
			(at -0.7112 -1.35763 0)
			(unlocked yes)
			(layer "F.SilkS")
			(effects
				(font
					(size 0.7874 0.5842)
					(thickness 0.1524)
				)
				(justify left)
			)
		)
		(property "Value" ""
			(at 0 0 0)
			(layer "F.Fab")
			(effects
				(font
					(size 1.27 1.27)
				)
			)
		)
		(property "Device Type" "TP_PIONT-TP010CT020B030_PTH-TPA"
			(at -1.341882 0.996696 0)
			(unlocked yes)
			(layer "F.Fab")
			(hide yes)
			(effects
				(font
					(size 0.7874 0.5842)
					(thickness 0.000001)
				)
				(justify left)
			)
		)
		(duplicate_pad_numbers_are_jumpers no)
		(fp_poly
			(pts
				(arc
					(start 0.889 0)
					(mid -0.889 0)
					(end 0.889 0)
				)
			)
			(stroke
				(width 0)
				(type default)
			)
			(fill no)
			(layer "B.CrtYd")
		)
		(fp_poly
			(pts
				(arc
					(start 0.889 0)
					(mid -0.889 0)
					(end 0.889 0)
				)
			)
			(stroke
				(width 0)
				(type default)
			)
			(fill no)
			(layer "F.CrtYd")
		)
		(pad "1" thru_hole circle
			(at 0 0)
			(size 0.508 0.508)
			(drill 0.254)
			(layers "*.Cu" "*.Mask")
			(remove_unused_layers no)
			(net "MUX2_SEL")
			(clearance 0.1016)
			(padstack
				(mode front_inner_back)
				(layer "Inner"
					(shape circle)
					(size 0.508 0.508)
					(clearance 0.1016)
				)
				(layer "B.Cu"
					(shape circle)
					(size 0.762 0.762)
					(clearance -0.0254)
				)
			)
		)
	)
	(footprint ""
		(layer "F.Cu")
		(at 124.079 -89.535 90)
		(property "Reference" "R113"
			(at -3.429 0.16637 90)
			(unlocked yes)
			(layer "F.SilkS")
			(effects
				(font
					(size 0.7874 0.5842)
					(thickness 0.1524)
				)
			)
		)
		(property "Value" "VAL*"
			(at 0.02032 2.13233 90)
			(unlocked yes)
			(layer "F.Fab")
			(hide yes)
			(effects
				(font
					(size 0.7874 0.5842)
					(thickness 0.1524)
				)
			)
		)
		(property "Tolerance" "TOL*"
			(at 0.044704 3.05435 90)
			(unlocked yes)
			(layer "Cmts.User")
			(hide yes)
			(effects
				(font
					(size 0.7874 0.5842)
					(thickness 0.1524)
				)
			)
		)
		(property "User Part Number" "PARTNUM*"
			(at 0.02032 4.024884 90)
			(unlocked yes)
			(layer "Cmts.User")
			(hide yes)
			(effects
				(font
					(size 0.7874 0.5842)
					(thickness 0.1524)
				)
			)
		)
		(property "Device Type" "RESISTOR-G155-133R0-01,33OHM,1%"
			(at 0.008382 1.210564 90)
			(unlocked yes)
			(layer "F.Fab")
			(hide yes)
			(effects
				(font
					(size 0.7874 0.5842)
					(thickness 0.1524)
				)
			)
		)
		(duplicate_pad_numbers_are_jumpers no)
		(fp_line
			(start 1.143 -0.5588)
			(end -1.143 -0.5588)
			(stroke
				(width 0.1)
				(type default)
			)
			(layer "F.SilkS")
		)
		(fp_line
			(start -1.143 -0.5588)
			(end -1.143 0.5588)
			(stroke
				(width 0.1)
				(type default)
			)
			(layer "F.SilkS")
		)
		(fp_line
			(start 1.143 0.5588)
			(end 1.143 -0.5588)
			(stroke
				(width 0.1)
				(type default)
			)
			(layer "F.SilkS")
		)
		(fp_line
			(start -1.143 0.5588)
			(end 1.143 0.5588)
			(stroke
				(width 0.1)
				(type default)
			)
			(layer "F.SilkS")
		)
		(fp_rect
			(start 1.143 -0.5588)
			(end -1.143 0.5588)
			(stroke
				(width 0)
				(type default)
			)
			(fill no)
			(layer "F.CrtYd")
		)
		(fp_line
			(start 0.508 -0.3048)
			(end -0.508 -0.3048)
			(stroke
				(width 0.1)
				(type default)
			)
			(layer "F.Fab")
		)
		(fp_line
			(start -0.508 -0.3048)
			(end -0.508 0.3048)
			(stroke
				(width 0.1)
				(type default)
			)
			(layer "F.Fab")
		)
		(fp_line
			(start 0.508 0.3048)
			(end 0.508 -0.3048)
			(stroke
				(width 0.1)
				(type default)
			)
			(layer "F.Fab")
		)
		(fp_line
			(start -0.508 0.3048)
			(end 0.508 0.3048)
			(stroke
				(width 0.1)
				(type default)
			)
			(layer "F.Fab")
		)
		(pad "1" smd rect
			(at -0.5334 0 90)
			(size 0.7112 0.6096)
			(layers "F.Cu" "F.Mask" "F.Paste")
			(net "DBG_UART_GPS_RXD")
		)
		(pad "2" smd rect
			(at 0.5334 0 90)
			(size 0.7112 0.6096)
			(layers "F.Cu" "F.Mask" "F.Paste")
			(net "GPS_UART_RXD")
		)
		(zone
			(layer "F.Cu")
			(hatch none 0.5)
			(connect_pads
				(clearance 0)
			)
			(min_thickness 0.25)
			(keepout
				(tracks allowed)
				(vias not_allowed)
				(pads allowed)
				(copperpour not_allowed)
				(footprints allowed)
			)
			(placement
				(enabled no)
				(sheetname "")
			)
			(fill
				(thermal_gap 0.5)
				(thermal_bridge_width 0.5)
				(island_removal_mode 0)
			)
			(polygon
				(pts
					(xy 123.7742 -89.6112) (xy 123.7742 -89.4588) (xy 124.3838 -89.4588) (xy 124.3838 -89.6112)
				)
			)
		)
	)
	(footprint ""
		(layer "F.Cu")
		(at 125.499876 -104.650032)
		(property "Reference" "ME3"
			(at -5.929376 -0.085598 0)
			(unlocked yes)
			(layer "F.SilkS")
			(effects
				(font
					(size 0.7874 0.5842)
					(thickness 0.1524)
				)
				(justify left)
			)
		)
		(property "Value" ""
			(at 0 0 0)
			(layer "F.Fab")
			(effects
				(font
					(size 1.27 1.27)
				)
			)
		)
		(property "Device Type" "NUT-G340-10437-01"
			(at -1.4732 4.226306 0)
			(unlocked yes)
			(layer "F.Fab")
			(hide yes)
			(effects
				(font
					(size 0.7874 0.5842)
					(thickness 0.1524)
				)
				(justify left)
			)
		)
		(property "User Part Number" "PARTNUM*"
			(at -3.048 5.242306 0)
			(unlocked yes)
			(layer "Cmts.User")
			(hide yes)
			(effects
				(font
					(size 0.7874 0.5842)
					(thickness 0.1524)
				)
				(justify left)
			)
		)
		(duplicate_pad_numbers_are_jumpers no)
		(fp_circle
			(center 0 0)
			(end 3.3528 0)
			(stroke
				(width 0.1)
				(type default)
			)
			(fill no)
			(layer "F.SilkS")
		)
		(fp_poly
			(pts
				(arc
					(start -2.102612 -0.1524)
					(mid -1.490671 -1.490671)
					(end -0.1524 -2.102612)
				)
				(arc
					(start -0.1524 -3.171444)
					(mid -2.245137 -2.245137)
					(end -3.171444 -0.1524)
				)
			)
			(stroke
				(width 0)
				(type default)
			)
			(fill yes)
			(layer "F.Paste")
		)
		(fp_poly
			(pts
				(arc
					(start -0.1524 2.102612)
					(mid -1.490671 1.490671)
					(end -2.102612 0.1524)
				)
				(arc
					(start -3.171444 0.1524)
					(mid -2.245137 2.245137)
					(end -0.1524 3.171444)
				)
			)
			(stroke
				(width 0)
				(type default)
			)
			(fill yes)
			(layer "F.Paste")
		)
		(fp_poly
			(pts
				(arc
					(start 0.1524 -2.102612)
					(mid 1.490671 -1.490671)
					(end 2.102612 -0.1524)
				)
				(arc
					(start 3.171444 -0.1524)
					(mid 2.245137 -2.245137)
					(end 0.1524 -3.171444)
				)
			)
			(stroke
				(width 0)
				(type default)
			)
			(fill yes)
			(layer "F.Paste")
		)
		(fp_poly
			(pts
				(arc
					(start 2.102612 0.1524)
					(mid 1.490671 1.490671)
					(end 0.1524 2.102612)
				)
				(arc
					(start 0.1524 3.171444)
					(mid 2.245137 2.245137)
					(end 3.171444 0.1524)
				)
			)
			(stroke
				(width 0)
				(type default)
			)
			(fill yes)
			(layer "F.Paste")
		)
		(fp_rect
			(start -7.5946 7.5946)
			(end 7.5946 -7.5946)
			(stroke
				(width 0)
				(type default)
			)
			(fill no)
			(layer "B.CrtYd")
		)
		(fp_poly
			(pts
				(arc
					(start 3.6068 0)
					(mid -3.6068 0)
					(end 3.6068 0)
				)
			)
			(stroke
				(width 0)
				(type default)
			)
			(fill no)
			(layer "F.CrtYd")
		)
		(fp_circle
			(center 0 0)
			(end 2.8448 0)
			(stroke
				(width 0.1)
				(type default)
			)
			(fill no)
			(layer "F.Fab")
		)
		(pad "1" thru_hole circle
			(at 0 0)
			(size 6.1976 6.1976)
			(drill 4.2164)
			(layers "*.Cu" "*.Mask")
			(remove_unused_layers no)
			(net "SG")
			(padstack
				(mode front_inner_back)
				(layer "Inner"
					(shape circle)
					(size 5.0292 5.0292)
					(clearance -0.1143)
				)
				(layer "B.Cu"
					(shape circle)
					(size 5.0292 5.0292)
				)
			)
		)
	)
	(footprint ""
		(layer "F.Cu")
		(at 12.192 -37.211 90)
		(property "Reference" "R367"
			(at -1.27 -3.26263 90)
			(unlocked yes)
			(layer "F.SilkS")
			(effects
				(font
					(size 0.7874 0.5842)
					(thickness 0.1524)
				)
			)
		)
		(property "Value" "VAL*"
			(at 0.02032 2.13233 90)
			(unlocked yes)
			(layer "F.Fab")
			(hide yes)
			(effects
				(font
					(size 0.7874 0.5842)
					(thickness 0.1524)
				)
			)
		)
		(property "Tolerance" "TOL*"
			(at 0.044704 3.05435 90)
			(unlocked yes)
			(layer "Cmts.User")
			(hide yes)
			(effects
				(font
					(size 0.7874 0.5842)
					(thickness 0.1524)
				)
			)
		)
		(property "User Part Number" "PARTNUM*"
			(at 0.02032 4.024884 90)
			(unlocked yes)
			(layer "Cmts.User")
			(hide yes)
			(effects
				(font
					(size 0.7874 0.5842)
					(thickness 0.1524)
				)
			)
		)
		(property "Device Type" "RESISTOR-G155-149R9-01,49.9OHMA"
			(at 0.008382 1.210564 90)
			(unlocked yes)
			(layer "F.Fab")
			(hide yes)
			(effects
				(font
					(size 0.7874 0.5842)
					(thickness 0.1524)
				)
			)
		)
		(duplicate_pad_numbers_are_jumpers no)
		(fp_line
			(start 1.143 -0.5588)
			(end -1.143 -0.5588)
			(stroke
				(width 0.1)
				(type default)
			)
			(layer "F.SilkS")
		)
		(fp_line
			(start -1.143 -0.5588)
			(end -1.143 0.5588)
			(stroke
				(width 0.1)
				(type default)
			)
			(layer "F.SilkS")
		)
		(fp_line
			(start 1.143 0.5588)
			(end 1.143 -0.5588)
			(stroke
				(width 0.1)
				(type default)
			)
			(layer "F.SilkS")
		)
		(fp_line
			(start -1.143 0.5588)
			(end 1.143 0.5588)
			(stroke
				(width 0.1)
				(type default)
			)
			(layer "F.SilkS")
		)
		(fp_poly
			(pts
				(xy -1.143 0.5588) (xy 1.143 0.5588) (xy 1.143 -0.5588) (xy -1.143 -0.5588)
			)
			(stroke
				(width 0)
				(type default)
			)
			(fill no)
			(layer "F.CrtYd")
		)
		(fp_line
			(start 0.508 -0.3048)
			(end -0.508 -0.3048)
			(stroke
				(width 0.1)
				(type default)
			)
			(layer "F.Fab")
		)
		(fp_line
			(start -0.508 -0.3048)
			(end -0.508 0.3048)
			(stroke
				(width 0.1)
				(type default)
			)
			(layer "F.Fab")
		)
		(fp_line
			(start 0.508 0.3048)
			(end 0.508 -0.3048)
			(stroke
				(width 0.1)
				(type default)
			)
			(layer "F.Fab")
		)
		(fp_line
			(start -0.508 0.3048)
			(end 0.508 0.3048)
			(stroke
				(width 0.1)
				(type default)
			)
			(layer "F.Fab")
		)
		(pad "1" smd rect
			(at -0.5334 0 90)
			(size 0.7112 0.6096)
			(layers "F.Cu" "F.Mask" "F.Paste")
			(net "BF_ANT3_IN")
		)
		(pad "2" smd rect
			(at 0.5334 0 90)
			(size 0.7112 0.6096)
			(layers "F.Cu" "F.Mask" "F.Paste")
			(net "ANT3_IN")
		)
		(zone
			(layer "F.Cu")
			(hatch none 0.5)
			(connect_pads
				(clearance 0)
			)
			(min_thickness 0.25)
			(keepout
				(tracks allowed)
				(vias not_allowed)
				(pads allowed)
				(copperpour not_allowed)
				(footprints allowed)
			)
			(placement
				(enabled no)
				(sheetname "")
			)
			(fill
				(thermal_gap 0.5)
				(thermal_bridge_width 0.5)
				(island_removal_mode 0)
			)
			(polygon
				(pts
					(xy 12.4968 -37.1348) (xy 12.4968 -37.2872) (xy 11.8872 -37.2872) (xy 11.8872 -37.1348)
				)
			)
		)
		(zone
			(layer "F.Cu")
			(hatch none 0.5)
			(connect_pads
				(clearance 0)
			)
			(min_thickness 0.25)
			(keepout
				(tracks not_allowed)
				(vias allowed)
				(pads allowed)
				(copperpour not_allowed)
				(footprints allowed)
			)
			(placement
				(enabled no)
				(sheetname "")
			)
			(fill
				(thermal_gap 0.5)
				(thermal_bridge_width 0.5)
				(island_removal_mode 0)
			)
			(polygon
				(pts
					(xy 12.4968 -37.1348) (xy 12.4968 -37.2872) (xy 11.8872 -37.2872) (xy 11.8872 -37.1348)
				)
			)
		)
	)
	(footprint ""
		(layer "F.Cu")
		(at 84.328 -93.599 90)
		(property "Reference" "C21"
			(at -3.81 -3.89763 90)
			(unlocked yes)
			(layer "F.SilkS")
			(effects
				(font
					(size 0.7874 0.5842)
					(thickness 0.1524)
				)
			)
		)
		(property "Value" "VAL*"
			(at 0.0762 3.134106 90)
			(unlocked yes)
			(layer "F.Fab")
			(hide yes)
			(effects
				(font
					(size 0.7874 0.5842)
					(thickness 0.1524)
				)
			)
		)
		(property "Tolerance" "TOL*"
			(at 0.0762 4.048506 90)
			(unlocked yes)
			(layer "Cmts.User")
			(hide yes)
			(effects
				(font
					(size 0.7874 0.5842)
					(thickness 0.1524)
				)
			)
		)
		(property "User Part Number" "PARTNUM*"
			(at 0.1016 5.013706 90)
			(unlocked yes)
			(layer "Cmts.User")
			(hide yes)
			(effects
				(font
					(size 0.7874 0.5842)
					(thickness 0.1524)
				)
			)
		)
		(property "Device Type" "CAPACITOR-G107-0F226-CM,22UF,2A"
			(at 0.0508 2.194306 90)
			(unlocked yes)
			(layer "F.Fab")
			(hide yes)
			(effects
				(font
					(size 0.7874 0.5842)
					(thickness 0.1524)
				)
			)
		)
		(duplicate_pad_numbers_are_jumpers no)
		(fp_line
			(start 1.5748 -0.9398)
			(end -1.5748 -0.9398)
			(stroke
				(width 0.1)
				(type default)
			)
			(layer "F.SilkS")
		)
		(fp_line
			(start -1.5748 -0.9398)
			(end -1.5748 0.9398)
			(stroke
				(width 0.1)
				(type default)
			)
			(layer "F.SilkS")
		)
		(fp_line
			(start 1.5748 0.9398)
			(end 1.5748 -0.9398)
			(stroke
				(width 0.1)
				(type default)
			)
			(layer "F.SilkS")
		)
		(fp_line
			(start -1.5748 0.9398)
			(end 1.5748 0.9398)
			(stroke
				(width 0.1)
				(type default)
			)
			(layer "F.SilkS")
		)
		(fp_rect
			(start -1.5748 -0.9398)
			(end 1.5748 0.9398)
			(stroke
				(width 0)
				(type default)
			)
			(fill no)
			(layer "F.CrtYd")
		)
		(fp_line
			(start 1.016 -0.635)
			(end -1.016 -0.635)
			(stroke
				(width 0.1)
				(type default)
			)
			(layer "F.Fab")
		)
		(fp_line
			(start -1.016 -0.635)
			(end -1.016 0.635)
			(stroke
				(width 0.1)
				(type default)
			)
			(layer "F.Fab")
		)
		(fp_line
			(start 1.016 0.635)
			(end 1.016 -0.635)
			(stroke
				(width 0.1)
				(type default)
			)
			(layer "F.Fab")
		)
		(fp_line
			(start -1.016 0.635)
			(end 1.016 0.635)
			(stroke
				(width 0.1)
				(type default)
			)
			(layer "F.Fab")
		)
		(pad "1" smd rect
			(at -0.8382 0 90)
			(size 0.9652 1.3716)
			(layers "F.Cu" "F.Mask" "F.Paste")
			(net "XP3R3V")
		)
		(pad "2" smd rect
			(at 0.8382 0 90)
			(size 0.9652 1.3716)
			(layers "F.Cu" "F.Mask" "F.Paste")
			(net "SG")
		)
		(zone
			(layer "F.Cu")
			(hatch none 0.5)
			(connect_pads
				(clearance 0)
			)
			(min_thickness 0.25)
			(keepout
				(tracks allowed)
				(vias not_allowed)
				(pads allowed)
				(copperpour not_allowed)
				(footprints allowed)
			)
			(placement
				(enabled no)
				(sheetname "")
			)
			(fill
				(thermal_gap 0.5)
				(thermal_bridge_width 0.5)
				(island_removal_mode 0)
			)
			(polygon
				(pts
					(xy 83.693 -93.3704) (xy 84.963 -93.3704) (xy 84.963 -93.8276) (xy 83.693 -93.8276)
				)
			)
		)
	)
	(footprint ""
		(layer "F.Cu")
		(at 82.7786 -50.546 -90)
		(property "Reference" "R276"
			(at 14.478 1.09093 90)
			(unlocked yes)
			(layer "F.SilkS")
			(effects
				(font
					(size 0.7874 0.5842)
					(thickness 0.1524)
				)
			)
		)
		(property "Value" "VAL*"
			(at 0.02032 2.13233 270)
			(unlocked yes)
			(layer "F.Fab")
			(hide yes)
			(effects
				(font
					(size 0.7874 0.5842)
					(thickness 0.1524)
				)
			)
		)
		(property "Tolerance" "TOL*"
			(at 0.044704 3.05435 270)
			(unlocked yes)
			(layer "Cmts.User")
			(hide yes)
			(effects
				(font
					(size 0.7874 0.5842)
					(thickness 0.1524)
				)
			)
		)
		(property "User Part Number" "PARTNUM*"
			(at 0.02032 4.024884 270)
			(unlocked yes)
			(layer "Cmts.User")
			(hide yes)
			(effects
				(font
					(size 0.7874 0.5842)
					(thickness 0.1524)
				)
			)
		)
		(property "Device Type" "RESISTOR-G155-11000-01,100OHM,A"
			(at 0.008382 1.210564 270)
			(unlocked yes)
			(layer "F.Fab")
			(hide yes)
			(effects
				(font
					(size 0.7874 0.5842)
					(thickness 0.1524)
				)
			)
		)
		(duplicate_pad_numbers_are_jumpers no)
		(fp_line
			(start -1.143 0.5588)
			(end 1.143 0.5588)
			(stroke
				(width 0.1)
				(type default)
			)
			(layer "F.SilkS")
		)
		(fp_line
			(start 1.143 0.5588)
			(end 1.143 -0.5588)
			(stroke
				(width 0.1)
				(type default)
			)
			(layer "F.SilkS")
		)
		(fp_line
			(start -1.143 -0.5588)
			(end -1.143 0.5588)
			(stroke
				(width 0.1)
				(type default)
			)
			(layer "F.SilkS")
		)
		(fp_line
			(start 1.143 -0.5588)
			(end -1.143 -0.5588)
			(stroke
				(width 0.1)
				(type default)
			)
			(layer "F.SilkS")
		)
		(fp_rect
			(start 1.143 0.5588)
			(end -1.143 -0.5588)
			(stroke
				(width 0)
				(type default)
			)
			(fill no)
			(layer "F.CrtYd")
		)
		(fp_line
			(start -0.508 0.3048)
			(end 0.508 0.3048)
			(stroke
				(width 0.1)
				(type default)
			)
			(layer "F.Fab")
		)
		(fp_line
			(start 0.508 0.3048)
			(end 0.508 -0.3048)
			(stroke
				(width 0.1)
				(type default)
			)
			(layer "F.Fab")
		)
		(fp_line
			(start -0.508 -0.3048)
			(end -0.508 0.3048)
			(stroke
				(width 0.1)
				(type default)
			)
			(layer "F.Fab")
		)
		(fp_line
			(start 0.508 -0.3048)
			(end -0.508 -0.3048)
			(stroke
				(width 0.1)
				(type default)
			)
			(layer "F.Fab")
		)
		(pad "1" smd rect
			(at -0.5334 0 270)
			(size 0.7112 0.6096)
			(layers "F.Cu" "F.Mask" "F.Paste")
			(net "FPGA_OUT_MAC_PPS_IN0P")
		)
		(pad "2" smd rect
			(at 0.5334 0 270)
			(size 0.7112 0.6096)
			(layers "F.Cu" "F.Mask" "F.Paste")
			(net "FPGA_OUT_MAC_PPS_IN0N")
		)
		(zone
			(layer "F.Cu")
			(hatch none 0.5)
			(connect_pads
				(clearance 0)
			)
			(min_thickness 0.25)
			(keepout
				(tracks allowed)
				(vias not_allowed)
				(pads allowed)
				(copperpour not_allowed)
				(footprints allowed)
			)
			(placement
				(enabled no)
				(sheetname "")
			)
			(fill
				(thermal_gap 0.5)
				(thermal_bridge_width 0.5)
				(island_removal_mode 0)
			)
			(polygon
				(pts
					(xy 82.4738 -50.4698) (xy 83.0834 -50.4698) (xy 83.0834 -50.6222) (xy 82.4738 -50.6222)
				)
			)
		)
	)
	(footprint ""
		(layer "F.Cu")
		(at 1.500124 -24.5999 90)
		(property "Reference" "DS15"
			(at 2.66573 0.785876 0)
			(unlocked yes)
			(layer "F.SilkS")
			(effects
				(font
					(size 0.7874 0.5842)
					(thickness 0.1524)
				)
			)
		)
		(property "Value" ""
			(at 0 0 90)
			(layer "F.Fab")
			(effects
				(font
					(size 1.27 1.27)
				)
			)
		)
		(property "User Part Number" "PARTNUM*"
			(at 0.015494 4.486402 90)
			(unlocked yes)
			(layer "Cmts.User")
			(hide yes)
			(effects
				(font
					(size 0.7874 0.5842)
					(thickness 0.1524)
				)
			)
		)
		(property "Device Type" "LED_4P_V14-G170-10189-01"
			(at 0.015494 3.292602 90)
			(unlocked yes)
			(layer "F.Fab")
			(hide yes)
			(effects
				(font
					(size 0.7874 0.5842)
					(thickness 0.1524)
				)
			)
		)
		(duplicate_pad_numbers_are_jumpers no)
		(fp_line
			(start 1.378966 -0.829056)
			(end -1.378966 -0.829056)
			(stroke
				(width 0.1)
				(type default)
			)
			(layer "F.SilkS")
		)
		(fp_line
			(start -1.378966 -0.829056)
			(end -1.378966 -0.452628)
			(stroke
				(width 0.1)
				(type default)
			)
			(layer "F.SilkS")
		)
		(fp_line
			(start 1.998218 -0.452628)
			(end 1.378966 -0.452628)
			(stroke
				(width 0.1)
				(type default)
			)
			(layer "F.SilkS")
		)
		(fp_line
			(start 1.378966 -0.452628)
			(end 1.378966 -0.829056)
			(stroke
				(width 0.1)
				(type default)
			)
			(layer "F.SilkS")
		)
		(fp_line
			(start -1.378966 -0.452628)
			(end -1.998218 -0.452628)
			(stroke
				(width 0.1)
				(type default)
			)
			(layer "F.SilkS")
		)
		(fp_line
			(start -1.998218 -0.452628)
			(end -1.998218 1.103884)
			(stroke
				(width 0.1)
				(type default)
			)
			(layer "F.SilkS")
		)
		(fp_line
			(start 1.998218 1.103884)
			(end 1.998218 -0.452628)
			(stroke
				(width 0.1)
				(type default)
			)
			(layer "F.SilkS")
		)
		(fp_line
			(start -1.998218 1.103884)
			(end 1.998218 1.103884)
			(stroke
				(width 0.1)
				(type default)
			)
			(layer "F.SilkS")
		)
		(fp_poly
			(pts
				(xy 0.918464 -1.698498) (xy 1.223264 -1.46939) (xy 0.994664 -1.46939) (xy 0.994664 -1.24079) (xy 0.842264 -1.24079)
				(xy 0.842264 -1.46939) (xy 0.613664 -1.46939)
			)
			(stroke
				(width 0)
				(type default)
			)
			(fill yes)
			(layer "F.SilkS")
		)
		(fp_poly
			(pts
				(xy -0.73406 -1.677416) (xy -0.42926 -1.448308) (xy -0.65786 -1.448308) (xy -0.65786 -1.219708)
				(xy -0.81026 -1.219708) (xy -0.81026 -1.448308) (xy -1.03886 -1.448308)
			)
			(stroke
				(width 0)
				(type default)
			)
			(fill yes)
			(layer "F.SilkS")
		)
		(fp_poly
			(pts
				(xy -2.252218 1.357884) (xy -2.252218 -0.706628) (xy -1.632966 -0.706628) (xy -1.632966 -1.083056)
				(xy 1.632966 -1.083056) (xy 1.632966 -0.706628) (xy 2.252218 -0.706628) (xy 2.252218 1.357884)
			)
			(stroke
				(width 0)
				(type default)
			)
			(fill no)
			(layer "F.CrtYd")
		)
		(fp_line
			(start 1.124966 -0.575056)
			(end -1.124966 -0.575056)
			(stroke
				(width 0.1)
				(type default)
			)
			(layer "F.Fab")
		)
		(fp_line
			(start -1.124966 -0.575056)
			(end -1.124966 -0.075184)
			(stroke
				(width 0.1)
				(type default)
			)
			(layer "F.Fab")
		)
		(fp_line
			(start 1.325118 -0.075184)
			(end 1.124966 -0.075184)
			(stroke
				(width 0.1)
				(type default)
			)
			(layer "F.Fab")
		)
		(fp_line
			(start 1.124966 -0.075184)
			(end 1.124966 -0.575056)
			(stroke
				(width 0.1)
				(type default)
			)
			(layer "F.Fab")
		)
		(fp_line
			(start -1.124966 -0.075184)
			(end -1.325118 -0.075184)
			(stroke
				(width 0.1)
				(type default)
			)
			(layer "F.Fab")
		)
		(fp_line
			(start -1.325118 -0.075184)
			(end -1.325118 0.574802)
			(stroke
				(width 0.1)
				(type default)
			)
			(layer "F.Fab")
		)
		(fp_line
			(start 1.325118 0.574802)
			(end 1.325118 -0.075184)
			(stroke
				(width 0.1)
				(type default)
			)
			(layer "F.Fab")
		)
		(fp_line
			(start -1.325118 0.574802)
			(end 1.325118 0.574802)
			(stroke
				(width 0.1)
				(type default)
			)
			(layer "F.Fab")
		)
		(fp_poly
			(pts
				(xy 0.918464 -1.698498) (xy 1.223264 -1.46939) (xy 0.994664 -1.46939) (xy 0.994664 -1.24079) (xy 0.842264 -1.24079)
				(xy 0.842264 -1.46939) (xy 0.613664 -1.46939)
			)
			(stroke
				(width 0)
				(type default)
			)
			(fill yes)
			(layer "F.Fab")
		)
		(fp_poly
			(pts
				(xy -0.73406 -1.677416) (xy -0.42926 -1.448308) (xy -0.65786 -1.448308) (xy -0.65786 -1.219708)
				(xy -0.81026 -1.219708) (xy -0.81026 -1.448308) (xy -1.03886 -1.448308)
			)
			(stroke
				(width 0)
				(type default)
			)
			(fill yes)
			(layer "F.Fab")
		)
		(fp_text user "1"
			(at -2.2479 0.182626 90)
			(unlocked yes)
			(layer "F.SilkS")
			(effects
				(font
					(size 0.635 0.4064)
					(thickness 0.1524)
				)
			)
		)
		(fp_text user "3"
			(at 0.44196 1.833626 90)
			(unlocked yes)
			(layer "F.SilkS")
			(effects
				(font
					(size 0.635 0.4064)
					(thickness 0.1524)
				)
			)
		)
		(fp_text user "2"
			(at -0.8509 1.833626 90)
			(unlocked yes)
			(layer "F.SilkS")
			(effects
				(font
					(size 0.635 0.4064)
					(thickness 0.1524)
				)
			)
		)
		(fp_text user "4"
			(at 1.93929 1.420876 0)
			(unlocked yes)
			(layer "F.Fab")
			(effects
				(font
					(size 0.7874 0.5842)
					(thickness 0.1524)
				)
			)
		)
		(fp_text user "3"
			(at 0.79629 1.420876 0)
			(unlocked yes)
			(layer "F.Fab")
			(effects
				(font
					(size 0.7874 0.5842)
					(thickness 0.1524)
				)
			)
		)
		(fp_text user "2"
			(at -0.34671 1.420876 0)
			(unlocked yes)
			(layer "F.Fab")
			(effects
				(font
					(size 0.7874 0.5842)
					(thickness 0.1524)
				)
			)
		)
		(fp_text user "1"
			(at -1.39827 1.547876 0)
			(unlocked yes)
			(layer "F.Fab")
			(effects
				(font
					(size 0.7874 0.5842)
					(thickness 0.1524)
				)
			)
		)
		(pad "1" smd rect
			(at -1.325118 0.245872 90)
			(size 0.8382 0.889)
			(layers "F.Cu" "F.Mask" "F.Paste")
			(net "UNNAMED_14_LED4PV14_I266_1")
		)
		(pad "2" smd rect
			(at -0.424942 0.595884 90)
			(size 0.4572 0.508)
			(layers "F.Cu" "F.Mask" "F.Paste")
			(net "XP3R3V_FPGA")
		)
		(pad "3" smd rect
			(at 0.424942 0.595884 90)
			(size 0.4572 0.508)
			(layers "F.Cu" "F.Mask" "F.Paste")
			(net "UNNAMED_14_LED4PV14_I266_3")
		)
		(pad "4" smd rect
			(at 1.325118 0.245872 90)
			(size 0.8382 0.889)
			(layers "F.Cu" "F.Mask" "F.Paste")
			(net "UNNAMED_14_LED4PV14_I266_4")
		)
	)
	(footprint ""
		(layer "F.Cu")
		(at 60.325 -133.477)
		(property "Reference" "SP37"
			(at 0 0 0)
			(layer "F.SilkS")
			(hide yes)
			(effects
				(font
					(size 1.27 1.27)
				)
			)
		)
		(property "Value" ""
			(at 0 0 0)
			(layer "F.Fab")
			(effects
				(font
					(size 1.27 1.27)
				)
			)
		)
		(duplicate_pad_numbers_are_jumpers no)
	)
	(footprint ""
		(layer "F.Cu")
		(at 126.238 -39.116)
		(property "Reference" "TP62"
			(at -0.60325 0.5334 90)
			(unlocked yes)
			(layer "F.SilkS")
			(effects
				(font
					(size 0.635 0.4064)
					(thickness 0.1524)
				)
				(justify left)
			)
		)
		(property "Value" ""
			(at 0 0 0)
			(layer "F.Fab")
			(effects
				(font
					(size 1.27 1.27)
				)
			)
		)
		(property "Device Type" "TP_PIONT-TP010CT020B030_PTH-TPA"
			(at -1.341882 0.996696 0)
			(unlocked yes)
			(layer "F.Fab")
			(hide yes)
			(effects
				(font
					(size 0.7874 0.5842)
					(thickness 0.000001)
				)
				(justify left)
			)
		)
		(duplicate_pad_numbers_are_jumpers no)
		(fp_poly
			(pts
				(arc
					(start 0.889 0)
					(mid -0.889 0)
					(end 0.889 0)
				)
			)
			(stroke
				(width 0)
				(type default)
			)
			(fill no)
			(layer "B.CrtYd")
		)
		(fp_poly
			(pts
				(arc
					(start 0.889 0)
					(mid -0.889 0)
					(end 0.889 0)
				)
			)
			(stroke
				(width 0)
				(type default)
			)
			(fill no)
			(layer "F.CrtYd")
		)
		(pad "1" thru_hole circle
			(at 0 0)
			(size 0.508 0.508)
			(drill 0.254)
			(layers "*.Cu" "*.Mask")
			(remove_unused_layers no)
			(net "R_MAC_BITEOUT")
			(clearance 0.1016)
			(padstack
				(mode front_inner_back)
				(layer "Inner"
					(shape circle)
					(size 0.508 0.508)
					(clearance 0.1016)
				)
				(layer "B.Cu"
					(shape circle)
					(size 0.762 0.762)
					(clearance -0.0254)
				)
			)
		)
	)
	(footprint ""
		(layer "F.Cu")
		(at 19.685 -21.0312 -90)
		(property "Reference" "U19"
			(at -1.9558 -2.70637 90)
			(unlocked yes)
			(layer "F.SilkS")
			(effects
				(font
					(size 0.7874 0.5842)
					(thickness 0.1524)
				)
			)
		)
		(property "Value" ""
			(at 0 0 270)
			(layer "F.Fab")
			(effects
				(font
					(size 1.27 1.27)
				)
			)
		)
		(property "Device Type" "24LC16BT_I_ST_TSSOP8-G221-1017A"
			(at 0.0254 2.56667 270)
			(unlocked yes)
			(layer "F.Fab")
			(hide yes)
			(effects
				(font
					(size 0.7874 0.5842)
					(thickness 0.000001)
				)
			)
		)
		(property "User Part Number" "PARTNUM*"
			(at 0 3.45567 270)
			(unlocked yes)
			(layer "Cmts.User")
			(hide yes)
			(effects
				(font
					(size 0.7874 0.5842)
					(thickness 0.000001)
				)
			)
		)
		(duplicate_pad_numbers_are_jumpers no)
		(fp_line
			(start -4.0767 1.8034)
			(end -4.0767 -1.8034)
			(stroke
				(width 0.1)
				(type default)
			)
			(layer "F.SilkS")
		)
		(fp_line
			(start 4.0767 1.8034)
			(end -4.0767 1.8034)
			(stroke
				(width 0.1)
				(type default)
			)
			(layer "F.SilkS")
		)
		(fp_line
			(start -4.0767 -1.8034)
			(end 4.0767 -1.8034)
			(stroke
				(width 0.1)
				(type default)
			)
			(layer "F.SilkS")
		)
		(fp_line
			(start 4.0767 -1.8034)
			(end 4.0767 1.8034)
			(stroke
				(width 0.1)
				(type default)
			)
			(layer "F.SilkS")
		)
		(fp_poly
			(pts
				(arc
					(start -4.1148 -2.794)
					(mid -4.1148 -2.032)
					(end -4.1148 -2.794)
				)
			)
			(stroke
				(width 0)
				(type default)
			)
			(fill yes)
			(layer "F.SilkS")
		)
		(fp_poly
			(pts
				(xy -4.3307 2.0574) (xy 4.3307 2.0574) (xy 4.3307 -2.0574) (xy -4.3307 -2.0574)
			)
			(stroke
				(width 0)
				(type default)
			)
			(fill no)
			(layer "F.CrtYd")
		)
		(fp_line
			(start -2.2479 1.5494)
			(end -2.2479 -1.5494)
			(stroke
				(width 0.1)
				(type default)
			)
			(layer "F.Fab")
		)
		(fp_line
			(start 2.2479 1.5494)
			(end -2.2479 1.5494)
			(stroke
				(width 0.1)
				(type default)
			)
			(layer "F.Fab")
		)
		(fp_line
			(start -2.2479 -1.5494)
			(end 2.2479 -1.5494)
			(stroke
				(width 0.1)
				(type default)
			)
			(layer "F.Fab")
		)
		(fp_line
			(start 2.2479 -1.5494)
			(end 2.2479 1.5494)
			(stroke
				(width 0.1)
				(type default)
			)
			(layer "F.Fab")
		)
		(fp_poly
			(pts
				(arc
					(start -1.778 -1.397)
					(mid -1.778 -0.635)
					(end -1.778 -1.397)
				)
			)
			(stroke
				(width 0)
				(type default)
			)
			(fill yes)
			(layer "F.Fab")
		)
		(fp_text user "5"
			(at 5.01015 1.9431 0)
			(unlocked yes)
			(layer "F.SilkS")
			(effects
				(font
					(size 0.635 0.4064)
					(thickness 0.1524)
				)
				(justify left)
			)
		)
		(fp_text user "4"
			(at -4.76885 1.8161 0)
			(unlocked yes)
			(layer "F.SilkS")
			(effects
				(font
					(size 0.635 0.4064)
					(thickness 0.1524)
				)
				(justify left)
			)
		)
		(fp_text user "8"
			(at 3.61315 -2.1209 0)
			(unlocked yes)
			(layer "F.SilkS")
			(effects
				(font
					(size 0.635 0.4064)
					(thickness 0.1524)
				)
				(justify left)
			)
		)
		(fp_text user "5"
			(at 4.826 1.294384 90)
			(unlocked yes)
			(layer "F.Fab")
			(effects
				(font
					(size 0.7874 0.5842)
					(thickness 0.1524)
				)
				(justify left)
			)
		)
		(fp_text user "4"
			(at -4.6736 1.218184 90)
			(unlocked yes)
			(layer "F.Fab")
			(effects
				(font
					(size 0.7874 0.5842)
					(thickness 0.1524)
				)
				(justify left)
			)
		)
		(fp_text user "8"
			(at 4.826 -0.813816 90)
			(unlocked yes)
			(layer "F.Fab")
			(effects
				(font
					(size 0.7874 0.5842)
					(thickness 0.1524)
				)
				(justify left)
			)
		)
		(pad "1" smd rect
			(at -3.0353 -0.975106 270)
			(size 1.5748 0.3556)
			(layers "F.Cu" "F.Mask" "F.Paste")
			(net "UNNAMED_5_24LC16BTISTTSSOP8_I15")
		)
		(pad "2" smd rect
			(at -3.0353 -0.32512 270)
			(size 1.5748 0.3556)
			(layers "F.Cu" "F.Mask" "F.Paste")
			(net "UNNAMED_5_24LC16BTISTTSSOP8_I_1")
		)
		(pad "3" smd rect
			(at -3.0353 0.324866 270)
			(size 1.5748 0.3556)
			(layers "F.Cu" "F.Mask" "F.Paste")
			(net "UNNAMED_5_24LC16BTISTTSSOP8_I_2")
		)
		(pad "4" smd rect
			(at -3.0353 0.974852 270)
			(size 1.5748 0.3556)
			(layers "F.Cu" "F.Mask" "F.Paste")
			(net "SG")
		)
		(pad "5" smd rect
			(at 3.0353 0.974852 270)
			(size 1.5748 0.3556)
			(layers "F.Cu" "F.Mask" "F.Paste")
			(net "SEC_EEPROM_SDA")
		)
		(pad "6" smd rect
			(at 3.0353 0.324866 270)
			(size 1.5748 0.3556)
			(layers "F.Cu" "F.Mask" "F.Paste")
			(net "EEPROM_SCL")
		)
		(pad "7" smd rect
			(at 3.0353 -0.32512 270)
			(size 1.5748 0.3556)
			(layers "F.Cu" "F.Mask" "F.Paste")
			(net "SEC_EEPROM_WP")
		)
		(pad "8" smd rect
			(at 3.0353 -0.975106 270)
			(size 1.5748 0.3556)
			(layers "F.Cu" "F.Mask" "F.Paste")
			(net "XP3R3V_FPGA")
		)
	)
	(footprint ""
		(layer "F.Cu")
		(at 96.266 -24.638 180)
		(property "Reference" "C247"
			(at 12.065 -0.29337 0)
			(unlocked yes)
			(layer "F.SilkS")
			(effects
				(font
					(size 0.7874 0.5842)
					(thickness 0.1524)
				)
			)
		)
		(property "Value" "VAL*"
			(at 0.0762 2.067306 180)
			(unlocked yes)
			(layer "F.Fab")
			(hide yes)
			(effects
				(font
					(size 0.7874 0.5842)
					(thickness 0.1524)
				)
			)
		)
		(property "Tolerance" "TOL*"
			(at 0.0762 3.032506 180)
			(unlocked yes)
			(layer "Cmts.User")
			(hide yes)
			(effects
				(font
					(size 0.7874 0.5842)
					(thickness 0.1524)
				)
			)
		)
		(property "User Part Number" "PARTNUM*"
			(at 0.1016 4.023106 180)
			(unlocked yes)
			(layer "Cmts.User")
			(hide yes)
			(effects
				(font
					(size 0.7874 0.5842)
					(thickness 0.1524)
				)
			)
		)
		(property "Device Type" "CAPACITOR-G105-0C106-BM,10UF,2A"
			(at 0.0508 1.127506 180)
			(unlocked yes)
			(layer "F.Fab")
			(hide yes)
			(effects
				(font
					(size 0.7874 0.5842)
					(thickness 0.1524)
				)
			)
		)
		(duplicate_pad_numbers_are_jumpers no)
		(fp_line
			(start 1.143 0.5588)
			(end 1.143 -0.5588)
			(stroke
				(width 0.1)
				(type default)
			)
			(layer "F.SilkS")
		)
		(fp_line
			(start 1.143 -0.5588)
			(end -1.143 -0.5588)
			(stroke
				(width 0.1)
				(type default)
			)
			(layer "F.SilkS")
		)
		(fp_line
			(start -1.143 0.5588)
			(end 1.143 0.5588)
			(stroke
				(width 0.1)
				(type default)
			)
			(layer "F.SilkS")
		)
		(fp_line
			(start -1.143 -0.5588)
			(end -1.143 0.5588)
			(stroke
				(width 0.1)
				(type default)
			)
			(layer "F.SilkS")
		)
		(fp_rect
			(start 1.143 -0.5588)
			(end -1.143 0.5588)
			(stroke
				(width 0)
				(type default)
			)
			(fill no)
			(layer "F.CrtYd")
		)
		(fp_line
			(start 0.508 0.3048)
			(end 0.508 -0.3048)
			(stroke
				(width 0.1)
				(type default)
			)
			(layer "F.Fab")
		)
		(fp_line
			(start 0.508 -0.3048)
			(end -0.508 -0.3048)
			(stroke
				(width 0.1)
				(type default)
			)
			(layer "F.Fab")
		)
		(fp_line
			(start -0.508 0.3048)
			(end 0.508 0.3048)
			(stroke
				(width 0.1)
				(type default)
			)
			(layer "F.Fab")
		)
		(fp_line
			(start -0.508 -0.3048)
			(end -0.508 0.3048)
			(stroke
				(width 0.1)
				(type default)
			)
			(layer "F.Fab")
		)
		(pad "1" smd rect
			(at -0.5334 0 180)
			(size 0.7112 0.6096)
			(layers "F.Cu" "F.Mask" "F.Paste")
			(net "VDD3V3_OSC_125M")
		)
		(pad "2" smd rect
			(at 0.5334 0 180)
			(size 0.7112 0.6096)
			(layers "F.Cu" "F.Mask" "F.Paste")
			(net "SG")
		)
		(zone
			(layer "F.Cu")
			(hatch none 0.5)
			(connect_pads
				(clearance 0)
			)
			(min_thickness 0.25)
			(keepout
				(tracks allowed)
				(vias not_allowed)
				(pads allowed)
				(copperpour not_allowed)
				(footprints allowed)
			)
			(placement
				(enabled no)
				(sheetname "")
			)
			(fill
				(thermal_gap 0.5)
				(thermal_bridge_width 0.5)
				(island_removal_mode 0)
			)
			(polygon
				(pts
					(xy 96.1898 -24.3332) (xy 96.3422 -24.3332) (xy 96.3422 -24.9428) (xy 96.1898 -24.9428)
				)
			)
		)
	)
	(footprint ""
		(layer "F.Cu")
		(at 90.0684 -64.3636 -90)
		(property "Reference" "C279"
			(at -13.1064 9.63803 90)
			(unlocked yes)
			(layer "F.SilkS")
			(effects
				(font
					(size 0.7874 0.5842)
					(thickness 0.1524)
				)
			)
		)
		(property "Value" "VAL*"
			(at 0.0762 2.067306 270)
			(unlocked yes)
			(layer "F.Fab")
			(hide yes)
			(effects
				(font
					(size 0.7874 0.5842)
					(thickness 0.1524)
				)
			)
		)
		(property "Device Type" "CAPACITOR-G105-0B104-EK,0.1UF,A"
			(at 0.0508 1.127506 270)
			(unlocked yes)
			(layer "F.Fab")
			(hide yes)
			(effects
				(font
					(size 0.7874 0.5842)
					(thickness 0.1524)
				)
			)
		)
		(property "User Part Number" "PARTNUM*"
			(at 0.1016 4.023106 270)
			(unlocked yes)
			(layer "Cmts.User")
			(hide yes)
			(effects
				(font
					(size 0.7874 0.5842)
					(thickness 0.1524)
				)
			)
		)
		(property "Tolerance" "TOL*"
			(at 0.0762 3.032506 270)
			(unlocked yes)
			(layer "Cmts.User")
			(hide yes)
			(effects
				(font
					(size 0.7874 0.5842)
					(thickness 0.1524)
				)
			)
		)
		(duplicate_pad_numbers_are_jumpers no)
		(fp_line
			(start -1.143 0.5588)
			(end 1.143 0.5588)
			(stroke
				(width 0.1)
				(type default)
			)
			(layer "F.SilkS")
		)
		(fp_line
			(start 1.143 0.5588)
			(end 1.143 -0.5588)
			(stroke
				(width 0.1)
				(type default)
			)
			(layer "F.SilkS")
		)
		(fp_line
			(start -1.143 -0.5588)
			(end -1.143 0.5588)
			(stroke
				(width 0.1)
				(type default)
			)
			(layer "F.SilkS")
		)
		(fp_line
			(start 1.143 -0.5588)
			(end -1.143 -0.5588)
			(stroke
				(width 0.1)
				(type default)
			)
			(layer "F.SilkS")
		)
		(fp_rect
			(start 1.143 0.5588)
			(end -1.143 -0.5588)
			(stroke
				(width 0)
				(type default)
			)
			(fill no)
			(layer "F.CrtYd")
		)
		(fp_line
			(start -0.508 0.3048)
			(end 0.508 0.3048)
			(stroke
				(width 0.1)
				(type default)
			)
			(layer "F.Fab")
		)
		(fp_line
			(start 0.508 0.3048)
			(end 0.508 -0.3048)
			(stroke
				(width 0.1)
				(type default)
			)
			(layer "F.Fab")
		)
		(fp_line
			(start -0.508 -0.3048)
			(end -0.508 0.3048)
			(stroke
				(width 0.1)
				(type default)
			)
			(layer "F.Fab")
		)
		(fp_line
			(start 0.508 -0.3048)
			(end -0.508 -0.3048)
			(stroke
				(width 0.1)
				(type default)
			)
			(layer "F.Fab")
		)
		(pad "1" smd rect
			(at -0.5334 0 270)
			(size 0.7112 0.6096)
			(layers "F.Cu" "F.Mask" "F.Paste")
			(net "XP3R3V_FPGA")
		)
		(pad "2" smd rect
			(at 0.5334 0 270)
			(size 0.7112 0.6096)
			(layers "F.Cu" "F.Mask" "F.Paste")
			(net "SG")
		)
		(zone
			(layer "F.Cu")
			(hatch none 0.5)
			(connect_pads
				(clearance 0)
			)
			(min_thickness 0.25)
			(keepout
				(tracks allowed)
				(vias not_allowed)
				(pads allowed)
				(copperpour not_allowed)
				(footprints allowed)
			)
			(placement
				(enabled no)
				(sheetname "")
			)
			(fill
				(thermal_gap 0.5)
				(thermal_bridge_width 0.5)
				(island_removal_mode 0)
			)
			(polygon
				(pts
					(xy 89.7636 -64.2874) (xy 90.3732 -64.2874) (xy 90.3732 -64.4398) (xy 89.7636 -64.4398)
				)
			)
		)
	)
	(footprint ""
		(layer "F.Cu")
		(at 20.484592 -71.374 90)
		(property "Reference" "R71"
			(at 0.254 1.144778 90)
			(unlocked yes)
			(layer "F.SilkS")
			(effects
				(font
					(size 0.7874 0.5842)
					(thickness 0.1524)
				)
			)
		)
		(property "Value" "VAL*"
			(at 0.02032 2.13233 90)
			(unlocked yes)
			(layer "F.Fab")
			(hide yes)
			(effects
				(font
					(size 0.7874 0.5842)
					(thickness 0.1524)
				)
			)
		)
		(property "Tolerance" "TOL*"
			(at 0.044704 3.05435 90)
			(unlocked yes)
			(layer "Cmts.User")
			(hide yes)
			(effects
				(font
					(size 0.7874 0.5842)
					(thickness 0.1524)
				)
			)
		)
		(property "User Part Number" "PARTNUM*"
			(at 0.02032 4.024884 90)
			(unlocked yes)
			(layer "Cmts.User")
			(hide yes)
			(effects
				(font
					(size 0.7874 0.5842)
					(thickness 0.1524)
				)
			)
		)
		(property "Device Type" "RESISTOR-G155-14701-01,4.7KOHMA"
			(at 0.008382 1.210564 90)
			(unlocked yes)
			(layer "F.Fab")
			(hide yes)
			(effects
				(font
					(size 0.7874 0.5842)
					(thickness 0.1524)
				)
			)
		)
		(duplicate_pad_numbers_are_jumpers no)
		(fp_line
			(start 1.143 -0.5588)
			(end -1.143 -0.5588)
			(stroke
				(width 0.1)
				(type default)
			)
			(layer "F.SilkS")
		)
		(fp_line
			(start -1.143 -0.5588)
			(end -1.143 0.5588)
			(stroke
				(width 0.1)
				(type default)
			)
			(layer "F.SilkS")
		)
		(fp_line
			(start 1.143 0.5588)
			(end 1.143 -0.5588)
			(stroke
				(width 0.1)
				(type default)
			)
			(layer "F.SilkS")
		)
		(fp_line
			(start -1.143 0.5588)
			(end 1.143 0.5588)
			(stroke
				(width 0.1)
				(type default)
			)
			(layer "F.SilkS")
		)
		(fp_rect
			(start 1.143 -0.5588)
			(end -1.143 0.5588)
			(stroke
				(width 0)
				(type default)
			)
			(fill no)
			(layer "F.CrtYd")
		)
		(fp_line
			(start 0.508 -0.3048)
			(end -0.508 -0.3048)
			(stroke
				(width 0.1)
				(type default)
			)
			(layer "F.Fab")
		)
		(fp_line
			(start -0.508 -0.3048)
			(end -0.508 0.3048)
			(stroke
				(width 0.1)
				(type default)
			)
			(layer "F.Fab")
		)
		(fp_line
			(start 0.508 0.3048)
			(end 0.508 -0.3048)
			(stroke
				(width 0.1)
				(type default)
			)
			(layer "F.Fab")
		)
		(fp_line
			(start -0.508 0.3048)
			(end 0.508 0.3048)
			(stroke
				(width 0.1)
				(type default)
			)
			(layer "F.Fab")
		)
		(pad "1" smd rect
			(at -0.5334 0 90)
			(size 0.7112 0.6096)
			(layers "F.Cu" "F.Mask" "F.Paste")
			(net "XP1R8V_ICP10100")
		)
		(pad "2" smd rect
			(at 0.5334 0 90)
			(size 0.7112 0.6096)
			(layers "F.Cu" "F.Mask" "F.Paste")
			(net "BF_ICP10100_I2C_SCL")
		)
		(zone
			(layer "F.Cu")
			(hatch none 0.5)
			(connect_pads
				(clearance 0)
			)
			(min_thickness 0.25)
			(keepout
				(tracks allowed)
				(vias not_allowed)
				(pads allowed)
				(copperpour not_allowed)
				(footprints allowed)
			)
			(placement
				(enabled no)
				(sheetname "")
			)
			(fill
				(thermal_gap 0.5)
				(thermal_bridge_width 0.5)
				(island_removal_mode 0)
			)
			(polygon
				(pts
					(xy 20.179792 -71.4502) (xy 20.179792 -71.2978) (xy 20.789392 -71.2978) (xy 20.789392 -71.4502)
				)
			)
		)
	)
	(footprint ""
		(layer "F.Cu")
		(at 139.954 -59.436 -90)
		(property "Reference" "C258"
			(at -3.175 1.61163 90)
			(unlocked yes)
			(layer "F.SilkS")
			(effects
				(font
					(size 0.7874 0.5842)
					(thickness 0.1524)
				)
			)
		)
		(property "Value" "VAL*"
			(at 0.193548 2.13614 270)
			(unlocked yes)
			(layer "F.Fab")
			(hide yes)
			(effects
				(font
					(size 0.7874 0.5842)
					(thickness 0.1524)
				)
			)
		)
		(property "Tolerance" "TOL*"
			(at 0.216154 3.1496 270)
			(unlocked yes)
			(layer "Cmts.User")
			(hide yes)
			(effects
				(font
					(size 0.7874 0.5842)
					(thickness 0.1524)
				)
			)
		)
		(property "Device Type" "CAPACITOR-G104-0B103-EK,0.01UFA"
			(at 0.184404 1.180592 270)
			(unlocked yes)
			(layer "F.Fab")
			(hide yes)
			(effects
				(font
					(size 0.7874 0.5842)
					(thickness 0.1524)
				)
			)
		)
		(property "User Part Number" "PARTNUM*"
			(at 0.216154 4.185666 270)
			(unlocked yes)
			(layer "Cmts.User")
			(hide yes)
			(effects
				(font
					(size 0.7874 0.5842)
					(thickness 0.1524)
				)
			)
		)
		(duplicate_pad_numbers_are_jumpers no)
		(fp_line
			(start -0.671322 0.4445)
			(end -0.671322 -0.4445)
			(stroke
				(width 0.1)
				(type default)
			)
			(layer "F.SilkS")
		)
		(fp_line
			(start 0.671322 0.4445)
			(end -0.671322 0.4445)
			(stroke
				(width 0.1)
				(type default)
			)
			(layer "F.SilkS")
		)
		(fp_line
			(start -0.671322 -0.4445)
			(end 0.671322 -0.4445)
			(stroke
				(width 0.1)
				(type default)
			)
			(layer "F.SilkS")
		)
		(fp_line
			(start 0.671322 -0.4445)
			(end 0.671322 0.4445)
			(stroke
				(width 0.1)
				(type default)
			)
			(layer "F.SilkS")
		)
		(fp_rect
			(start 0.671322 0.4445)
			(end -0.671322 -0.4445)
			(stroke
				(width 0)
				(type default)
			)
			(fill no)
			(layer "F.CrtYd")
		)
		(fp_line
			(start -0.31496 0.1651)
			(end 0.31496 0.1651)
			(stroke
				(width 0.1)
				(type default)
			)
			(layer "F.Fab")
		)
		(fp_line
			(start 0.31496 0.1651)
			(end 0.31496 -0.1651)
			(stroke
				(width 0.1)
				(type default)
			)
			(layer "F.Fab")
		)
		(fp_line
			(start -0.31496 -0.1651)
			(end -0.31496 0.1651)
			(stroke
				(width 0.1)
				(type default)
			)
			(layer "F.Fab")
		)
		(fp_line
			(start 0.31496 -0.1651)
			(end -0.31496 -0.1651)
			(stroke
				(width 0.1)
				(type default)
			)
			(layer "F.Fab")
		)
		(pad "1" smd rect
			(at -0.264922 0 270)
			(size 0.3048 0.381)
			(layers "F.Cu" "F.Mask" "F.Paste")
			(net "SG")
		)
		(pad "2" smd rect
			(at 0.264922 0 270)
			(size 0.3048 0.381)
			(layers "F.Cu" "F.Mask" "F.Paste")
			(net "XP1R0V_PG")
		)
		(zone
			(layer "F.Cu")
			(hatch none 0.5)
			(connect_pads
				(clearance 0)
			)
			(min_thickness 0.25)
			(keepout
				(tracks allowed)
				(vias not_allowed)
				(pads allowed)
				(copperpour not_allowed)
				(footprints allowed)
			)
			(placement
				(enabled no)
				(sheetname "")
			)
			(fill
				(thermal_gap 0.5)
				(thermal_bridge_width 0.5)
				(island_removal_mode 0)
			)
			(polygon
				(pts
					(xy 139.7635 -59.323478) (xy 140.1445 -59.323478) (xy 140.1445 -59.548522) (xy 139.7635 -59.548522)
				)
			)
		)
	)
	(footprint ""
		(layer "F.Cu")
		(at 18.415 -82.423 180)
		(property "Reference" "R471"
			(at 0.635 -2.32537 0)
			(unlocked yes)
			(layer "F.SilkS")
			(effects
				(font
					(size 0.7874 0.5842)
					(thickness 0.1524)
				)
			)
		)
		(property "Value" "VAL*"
			(at 0.02032 2.13233 180)
			(unlocked yes)
			(layer "F.Fab")
			(hide yes)
			(effects
				(font
					(size 0.7874 0.5842)
					(thickness 0.1524)
				)
			)
		)
		(property "Tolerance" "TOL*"
			(at 0.044704 3.05435 180)
			(unlocked yes)
			(layer "Cmts.User")
			(hide yes)
			(effects
				(font
					(size 0.7874 0.5842)
					(thickness 0.1524)
				)
			)
		)
		(property "User Part Number" "PARTNUM*"
			(at 0.02032 4.024884 180)
			(unlocked yes)
			(layer "Cmts.User")
			(hide yes)
			(effects
				(font
					(size 0.7874 0.5842)
					(thickness 0.1524)
				)
			)
		)
		(property "Device Type" "RESISTOR-G155-100R0-J0,0OHM,-"
			(at 0.008382 1.210564 180)
			(unlocked yes)
			(layer "F.Fab")
			(hide yes)
			(effects
				(font
					(size 0.7874 0.5842)
					(thickness 0.1524)
				)
			)
		)
		(duplicate_pad_numbers_are_jumpers no)
		(fp_line
			(start 1.143 0.5588)
			(end 1.143 -0.5588)
			(stroke
				(width 0.1)
				(type default)
			)
			(layer "F.SilkS")
		)
		(fp_line
			(start 1.143 -0.5588)
			(end -1.143 -0.5588)
			(stroke
				(width 0.1)
				(type default)
			)
			(layer "F.SilkS")
		)
		(fp_line
			(start -1.143 0.5588)
			(end 1.143 0.5588)
			(stroke
				(width 0.1)
				(type default)
			)
			(layer "F.SilkS")
		)
		(fp_line
			(start -1.143 -0.5588)
			(end -1.143 0.5588)
			(stroke
				(width 0.1)
				(type default)
			)
			(layer "F.SilkS")
		)
		(fp_poly
			(pts
				(xy -1.143 0.5588) (xy 1.143 0.5588) (xy 1.143 -0.5588) (xy -1.143 -0.5588)
			)
			(stroke
				(width 0)
				(type default)
			)
			(fill no)
			(layer "F.CrtYd")
		)
		(fp_line
			(start 0.508 0.3048)
			(end 0.508 -0.3048)
			(stroke
				(width 0.1)
				(type default)
			)
			(layer "F.Fab")
		)
		(fp_line
			(start 0.508 -0.3048)
			(end -0.508 -0.3048)
			(stroke
				(width 0.1)
				(type default)
			)
			(layer "F.Fab")
		)
		(fp_line
			(start -0.508 0.3048)
			(end 0.508 0.3048)
			(stroke
				(width 0.1)
				(type default)
			)
			(layer "F.Fab")
		)
		(fp_line
			(start -0.508 -0.3048)
			(end -0.508 0.3048)
			(stroke
				(width 0.1)
				(type default)
			)
			(layer "F.Fab")
		)
		(pad "1" smd rect
			(at -0.5334 0 180)
			(size 0.7112 0.6096)
			(layers "F.Cu" "F.Mask" "F.Paste")
			(net "R_FT4232_I2C_SCL")
		)
		(pad "2" smd rect
			(at 0.5334 0 180)
			(size 0.7112 0.6096)
			(layers "F.Cu" "F.Mask" "F.Paste")
			(net "FT4232_I2C_SCL")
		)
		(zone
			(layer "F.Cu")
			(hatch none 0.5)
			(connect_pads
				(clearance 0)
			)
			(min_thickness 0.25)
			(keepout
				(tracks not_allowed)
				(vias allowed)
				(pads allowed)
				(copperpour not_allowed)
				(footprints allowed)
			)
			(placement
				(enabled no)
				(sheetname "")
			)
			(fill
				(thermal_gap 0.5)
				(thermal_bridge_width 0.5)
				(island_removal_mode 0)
			)
			(polygon
				(pts
					(xy 18.4912 -82.7278) (xy 18.3388 -82.7278) (xy 18.3388 -82.1182) (xy 18.4912 -82.1182)
				)
			)
		)
		(zone
			(layer "F.Cu")
			(hatch none 0.5)
			(connect_pads
				(clearance 0)
			)
			(min_thickness 0.25)
			(keepout
				(tracks allowed)
				(vias not_allowed)
				(pads allowed)
				(copperpour not_allowed)
				(footprints allowed)
			)
			(placement
				(enabled no)
				(sheetname "")
			)
			(fill
				(thermal_gap 0.5)
				(thermal_bridge_width 0.5)
				(island_removal_mode 0)
			)
			(polygon
				(pts
					(xy 18.4912 -82.7278) (xy 18.3388 -82.7278) (xy 18.3388 -82.1182) (xy 18.4912 -82.1182)
				)
			)
		)
	)
	(footprint ""
		(layer "F.Cu")
		(at 106.807 -58.293)
		(property "Reference" "TP187"
			(at 3.20675 2.0828 90)
			(unlocked yes)
			(layer "F.SilkS")
			(effects
				(font
					(size 0.635 0.4064)
					(thickness 0.1524)
				)
				(justify left)
			)
		)
		(property "Value" ""
			(at 0 0 0)
			(layer "F.Fab")
			(effects
				(font
					(size 1.27 1.27)
				)
			)
		)
		(property "Device Type" "TP_PIONT-TP010CT020B030_PTH-TPA"
			(at -1.341882 0.996696 0)
			(unlocked yes)
			(layer "F.Fab")
			(hide yes)
			(effects
				(font
					(size 0.7874 0.5842)
					(thickness 0.1524)
				)
				(justify left)
			)
		)
		(duplicate_pad_numbers_are_jumpers no)
		(fp_poly
			(pts
				(arc
					(start 0.889 0)
					(mid -0.889 0)
					(end 0.889 0)
				)
			)
			(stroke
				(width 0)
				(type default)
			)
			(fill no)
			(layer "B.CrtYd")
		)
		(fp_poly
			(pts
				(arc
					(start 0.889 0)
					(mid -0.889 0)
					(end 0.889 0)
				)
			)
			(stroke
				(width 0)
				(type default)
			)
			(fill no)
			(layer "F.CrtYd")
		)
		(pad "1" thru_hole circle
			(at 0 0)
			(size 0.508 0.508)
			(drill 0.254)
			(layers "*.Cu" "*.Mask")
			(remove_unused_layers no)
			(net "IO_L24P_16")
			(clearance 0.1016)
			(padstack
				(mode front_inner_back)
				(layer "Inner"
					(shape circle)
					(size 0.508 0.508)
					(clearance 0.1016)
				)
				(layer "B.Cu"
					(shape circle)
					(size 0.762 0.762)
					(clearance -0.0254)
				)
			)
		)
	)
	(footprint ""
		(layer "F.Cu")
		(at 81.0006 -53.594 180)
		(property "Reference" "R83"
			(at 0.9906 -14.64437 0)
			(unlocked yes)
			(layer "F.SilkS")
			(effects
				(font
					(size 0.7874 0.5842)
					(thickness 0.1524)
				)
			)
		)
		(property "Value" "VAL*"
			(at 0.02032 2.13233 180)
			(unlocked yes)
			(layer "F.Fab")
			(hide yes)
			(effects
				(font
					(size 0.7874 0.5842)
					(thickness 0.1524)
				)
			)
		)
		(property "Device Type" "RESISTOR-G155-100R0-J0,0OHM,-"
			(at 0.008382 1.210564 180)
			(unlocked yes)
			(layer "F.Fab")
			(hide yes)
			(effects
				(font
					(size 0.7874 0.5842)
					(thickness 0.1524)
				)
			)
		)
		(property "User Part Number" "PARTNUM*"
			(at 0.02032 4.024884 180)
			(unlocked yes)
			(layer "Cmts.User")
			(hide yes)
			(effects
				(font
					(size 0.7874 0.5842)
					(thickness 0.1524)
				)
			)
		)
		(property "Tolerance" "TOL*"
			(at 0.044704 3.05435 180)
			(unlocked yes)
			(layer "Cmts.User")
			(hide yes)
			(effects
				(font
					(size 0.7874 0.5842)
					(thickness 0.1524)
				)
			)
		)
		(duplicate_pad_numbers_are_jumpers no)
		(fp_line
			(start 1.143 0.5588)
			(end 1.143 -0.5588)
			(stroke
				(width 0.1)
				(type default)
			)
			(layer "F.SilkS")
		)
		(fp_line
			(start 1.143 -0.5588)
			(end -1.143 -0.5588)
			(stroke
				(width 0.1)
				(type default)
			)
			(layer "F.SilkS")
		)
		(fp_line
			(start -1.143 0.5588)
			(end 1.143 0.5588)
			(stroke
				(width 0.1)
				(type default)
			)
			(layer "F.SilkS")
		)
		(fp_line
			(start -1.143 -0.5588)
			(end -1.143 0.5588)
			(stroke
				(width 0.1)
				(type default)
			)
			(layer "F.SilkS")
		)
		(fp_rect
			(start 1.143 -0.5588)
			(end -1.143 0.5588)
			(stroke
				(width 0)
				(type default)
			)
			(fill no)
			(layer "F.CrtYd")
		)
		(fp_line
			(start 0.508 0.3048)
			(end 0.508 -0.3048)
			(stroke
				(width 0.1)
				(type default)
			)
			(layer "F.Fab")
		)
		(fp_line
			(start 0.508 -0.3048)
			(end -0.508 -0.3048)
			(stroke
				(width 0.1)
				(type default)
			)
			(layer "F.Fab")
		)
		(fp_line
			(start -0.508 0.3048)
			(end 0.508 0.3048)
			(stroke
				(width 0.1)
				(type default)
			)
			(layer "F.Fab")
		)
		(fp_line
			(start -0.508 -0.3048)
			(end -0.508 0.3048)
			(stroke
				(width 0.1)
				(type default)
			)
			(layer "F.Fab")
		)
		(pad "1" smd rect
			(at -0.5334 0 180)
			(size 0.7112 0.6096)
			(layers "F.Cu" "F.Mask" "F.Paste")
			(net "FPGA_OUT_MAC_PPS_IN1P")
		)
		(pad "2" smd rect
			(at 0.5334 0 180)
			(size 0.7112 0.6096)
			(layers "F.Cu" "F.Mask" "F.Paste")
			(net "R_MAC_PPS_IN1P")
		)
		(zone
			(layer "F.Cu")
			(hatch none 0.5)
			(connect_pads
				(clearance 0)
			)
			(min_thickness 0.25)
			(keepout
				(tracks allowed)
				(vias not_allowed)
				(pads allowed)
				(copperpour not_allowed)
				(footprints allowed)
			)
			(placement
				(enabled no)
				(sheetname "")
			)
			(fill
				(thermal_gap 0.5)
				(thermal_bridge_width 0.5)
				(island_removal_mode 0)
			)
			(polygon
				(pts
					(xy 80.9244 -53.2892) (xy 81.0768 -53.2892) (xy 81.0768 -53.8988) (xy 80.9244 -53.8988)
				)
			)
		)
	)
	(footprint ""
		(layer "F.Cu")
		(at 113.919 -61.976 90)
		(property "Reference" "R234"
			(at 3.302 0.29337 90)
			(unlocked yes)
			(layer "F.SilkS")
			(effects
				(font
					(size 0.7874 0.5842)
					(thickness 0.1524)
				)
			)
		)
		(property "Value" "VAL*"
			(at 0.02032 2.13233 90)
			(unlocked yes)
			(layer "F.Fab")
			(hide yes)
			(effects
				(font
					(size 0.7874 0.5842)
					(thickness 0.1524)
				)
			)
		)
		(property "Tolerance" "TOL*"
			(at 0.044704 3.05435 90)
			(unlocked yes)
			(layer "Cmts.User")
			(hide yes)
			(effects
				(font
					(size 0.7874 0.5842)
					(thickness 0.1524)
				)
			)
		)
		(property "User Part Number" "PARTNUM*"
			(at 0.02032 4.024884 90)
			(unlocked yes)
			(layer "Cmts.User")
			(hide yes)
			(effects
				(font
					(size 0.7874 0.5842)
					(thickness 0.1524)
				)
			)
		)
		(property "Device Type" "RESISTOR-G155-133R0-01,33OHM,1%"
			(at 0.008382 1.210564 90)
			(unlocked yes)
			(layer "F.Fab")
			(hide yes)
			(effects
				(font
					(size 0.7874 0.5842)
					(thickness 0.1524)
				)
			)
		)
		(duplicate_pad_numbers_are_jumpers no)
		(fp_line
			(start 1.143 -0.5588)
			(end -1.143 -0.5588)
			(stroke
				(width 0.1)
				(type default)
			)
			(layer "F.SilkS")
		)
		(fp_line
			(start -1.143 -0.5588)
			(end -1.143 0.5588)
			(stroke
				(width 0.1)
				(type default)
			)
			(layer "F.SilkS")
		)
		(fp_line
			(start 1.143 0.5588)
			(end 1.143 -0.5588)
			(stroke
				(width 0.1)
				(type default)
			)
			(layer "F.SilkS")
		)
		(fp_line
			(start -1.143 0.5588)
			(end 1.143 0.5588)
			(stroke
				(width 0.1)
				(type default)
			)
			(layer "F.SilkS")
		)
		(fp_poly
			(pts
				(xy -1.143 0.5588) (xy 1.143 0.5588) (xy 1.143 -0.5588) (xy -1.143 -0.5588)
			)
			(stroke
				(width 0)
				(type default)
			)
			(fill no)
			(layer "F.CrtYd")
		)
		(fp_line
			(start 0.508 -0.3048)
			(end -0.508 -0.3048)
			(stroke
				(width 0.1)
				(type default)
			)
			(layer "F.Fab")
		)
		(fp_line
			(start -0.508 -0.3048)
			(end -0.508 0.3048)
			(stroke
				(width 0.1)
				(type default)
			)
			(layer "F.Fab")
		)
		(fp_line
			(start 0.508 0.3048)
			(end 0.508 -0.3048)
			(stroke
				(width 0.1)
				(type default)
			)
			(layer "F.Fab")
		)
		(fp_line
			(start -0.508 0.3048)
			(end 0.508 0.3048)
			(stroke
				(width 0.1)
				(type default)
			)
			(layer "F.Fab")
		)
		(pad "1" smd rect
			(at -0.5334 0 90)
			(size 0.7112 0.6096)
			(layers "F.Cu" "F.Mask" "F.Paste")
			(net "FPGA_D00_MOSI")
		)
		(pad "2" smd rect
			(at 0.5334 0 90)
			(size 0.7112 0.6096)
			(layers "F.Cu" "F.Mask" "F.Paste")
			(net "FPGA_FLASH_DQ0_MOSI")
		)
		(zone
			(layer "F.Cu")
			(hatch none 0.5)
			(connect_pads
				(clearance 0)
			)
			(min_thickness 0.25)
			(keepout
				(tracks allowed)
				(vias not_allowed)
				(pads allowed)
				(copperpour not_allowed)
				(footprints allowed)
			)
			(placement
				(enabled no)
				(sheetname "")
			)
			(fill
				(thermal_gap 0.5)
				(thermal_bridge_width 0.5)
				(island_removal_mode 0)
			)
			(polygon
				(pts
					(xy 114.2238 -61.8998) (xy 114.2238 -62.0522) (xy 113.6142 -62.0522) (xy 113.6142 -61.8998)
				)
			)
		)
		(zone
			(layer "F.Cu")
			(hatch none 0.5)
			(connect_pads
				(clearance 0)
			)
			(min_thickness 0.25)
			(keepout
				(tracks not_allowed)
				(vias allowed)
				(pads allowed)
				(copperpour not_allowed)
				(footprints allowed)
			)
			(placement
				(enabled no)
				(sheetname "")
			)
			(fill
				(thermal_gap 0.5)
				(thermal_bridge_width 0.5)
				(island_removal_mode 0)
			)
			(polygon
				(pts
					(xy 114.2238 -61.8998) (xy 114.2238 -62.0522) (xy 113.6142 -62.0522) (xy 113.6142 -61.8998)
				)
			)
		)
	)
	(footprint ""
		(layer "F.Cu")
		(at 163.926774 -53.600096 90)
		(property "Reference" "J11"
			(at 5.12953 0.284226 0)
			(unlocked yes)
			(layer "F.SilkS")
			(effects
				(font
					(size 0.7874 0.5842)
					(thickness 0.1524)
				)
			)
		)
		(property "Value" ""
			(at 0 0 90)
			(layer "F.Fab")
			(effects
				(font
					(size 1.27 1.27)
				)
			)
		)
		(property "User Part Number" "PARTNUM*"
			(at 0.205486 7.130034 90)
			(unlocked yes)
			(layer "Cmts.User")
			(hide yes)
			(effects
				(font
					(size 0.7874 0.5842)
					(thickness 0.1524)
				)
			)
		)
		(property "Device Type" "CONN_USB_1X5_G2_GH4_F_RA_SMT-GA"
			(at 0.205486 5.936234 90)
			(unlocked yes)
			(layer "F.Fab")
			(hide yes)
			(effects
				(font
					(size 0.7874 0.5842)
					(thickness 0.1524)
				)
			)
		)
		(duplicate_pad_numbers_are_jumpers no)
		(fp_line
			(start 4.354068 -2.102866)
			(end 4.354068 4.129024)
			(stroke
				(width 0.1)
				(type default)
			)
			(layer "F.SilkS")
		)
		(fp_line
			(start -4.354068 -2.102866)
			(end 4.354068 -2.102866)
			(stroke
				(width 0.1)
				(type default)
			)
			(layer "F.SilkS")
		)
		(fp_line
			(start 4.354068 4.129024)
			(end -4.354068 4.129024)
			(stroke
				(width 0.1)
				(type default)
			)
			(layer "F.SilkS")
		)
		(fp_line
			(start -4.354068 4.129024)
			(end -4.354068 -2.102866)
			(stroke
				(width 0.1)
				(type default)
			)
			(layer "F.SilkS")
		)
		(fp_rect
			(start -9.18972 -6.928866)
			(end 9.18972 7.607554)
			(stroke
				(width 0)
				(type default)
			)
			(fill no)
			(layer "B.CrtYd")
		)
		(fp_rect
			(start -4.608068 -2.356866)
			(end 4.608068 4.383024)
			(stroke
				(width 0)
				(type default)
			)
			(fill no)
			(layer "F.CrtYd")
		)
		(fp_line
			(start 3.849878 -1.42494)
			(end 3.849878 3.875024)
			(stroke
				(width 0.1)
				(type default)
			)
			(layer "F.Fab")
		)
		(fp_line
			(start -3.849878 -1.42494)
			(end 3.849878 -1.42494)
			(stroke
				(width 0.1)
				(type default)
			)
			(layer "F.Fab")
		)
		(fp_line
			(start 3.849878 3.875024)
			(end -3.849878 3.875024)
			(stroke
				(width 0.1)
				(type default)
			)
			(layer "F.Fab")
		)
		(fp_line
			(start -3.849878 3.875024)
			(end -3.849878 -1.42494)
			(stroke
				(width 0.1)
				(type default)
			)
			(layer "F.Fab")
		)
		(fp_text user "1"
			(at -1.442466 -2.636774 0)
			(unlocked yes)
			(layer "F.SilkS")
			(effects
				(font
					(size 0.7874 0.5842)
					(thickness 0.1524)
				)
			)
		)
		(fp_text user "5"
			(at 1.986534 -2.509774 0)
			(unlocked yes)
			(layer "F.SilkS")
			(effects
				(font
					(size 0.7874 0.5842)
					(thickness 0.1524)
				)
			)
		)
		(fp_text user "GH2"
			(at 5.6769 -1.708404 90)
			(unlocked yes)
			(layer "F.SilkS")
			(effects
				(font
					(size 0.7874 0.5842)
					(thickness 0.1524)
				)
			)
		)
		(fp_text user "GH1"
			(at -5.467096 -1.581404 90)
			(unlocked yes)
			(layer "F.SilkS")
			(effects
				(font
					(size 0.7874 0.5842)
					(thickness 0.1524)
				)
			)
		)
		(fp_text user "GH3"
			(at -5.467096 1.720596 90)
			(unlocked yes)
			(layer "F.SilkS")
			(effects
				(font
					(size 0.7874 0.5842)
					(thickness 0.1524)
				)
			)
		)
		(fp_text user "GH4"
			(at 5.6769 1.974596 90)
			(unlocked yes)
			(layer "F.SilkS")
			(effects
				(font
					(size 0.7874 0.5842)
					(thickness 0.1524)
				)
			)
		)
		(fp_text user "1"
			(at -1.403096 -2.343404 90)
			(unlocked yes)
			(layer "F.Fab")
			(effects
				(font
					(size 0.7874 0.5842)
					(thickness 0.1524)
				)
			)
		)
		(fp_text user "5"
			(at 1.430274 -2.29997 90)
			(unlocked yes)
			(layer "F.Fab")
			(effects
				(font
					(size 0.7874 0.5842)
					(thickness 0.1524)
				)
			)
		)
		(fp_text user "GH1"
			(at -2.806954 -2.080768 90)
			(unlocked yes)
			(layer "F.Fab")
			(effects
				(font
					(size 0.7874 0.5842)
					(thickness 0.1524)
				)
			)
		)
		(fp_text user "GH2"
			(at 3.168904 -1.962404 90)
			(unlocked yes)
			(layer "F.Fab")
			(effects
				(font
					(size 0.7874 0.5842)
					(thickness 0.1524)
				)
			)
		)
		(fp_text user "GH4"
			(at 5.2959 2.088896 90)
			(unlocked yes)
			(layer "F.Fab")
			(effects
				(font
					(size 0.7874 0.5842)
					(thickness 0.1524)
				)
			)
		)
		(fp_text user "GH3"
			(at -5.2451 2.215896 90)
			(unlocked yes)
			(layer "F.Fab")
			(effects
				(font
					(size 0.7874 0.5842)
					(thickness 0.1524)
				)
			)
		)
		(fp_text user "G2"
			(at 1.14935 3.052318 90)
			(unlocked yes)
			(layer "F.Fab")
			(effects
				(font
					(size 0.7874 0.5842)
					(thickness 0.1524)
				)
			)
		)
		(fp_text user "G1"
			(at -0.88773 3.07086 90)
			(unlocked yes)
			(layer "F.Fab")
			(effects
				(font
					(size 0.7874 0.5842)
					(thickness 0.1524)
				)
			)
		)
		(pad "1" smd rect
			(at -1.299972 -1.100074 90)
			(size 0.4064 1.3462)
			(layers "F.Cu" "F.Mask" "F.Paste")
			(net "XP5R0V_USB_CONN")
		)
		(pad "2" smd rect
			(at -0.649986 -1.100074 90)
			(size 0.4064 1.3462)
			(layers "F.Cu" "F.Mask" "F.Paste")
			(net "CONN_MICRO_USB_DM")
		)
		(pad "3" smd rect
			(at 0 -1.100074 90)
			(size 0.4064 1.3462)
			(layers "F.Cu" "F.Mask" "F.Paste")
			(net "CONN_MICRO_USB_DP")
		)
		(pad "4" smd rect
			(at 0.649986 -1.100074 90)
			(size 0.4064 1.3462)
			(layers "F.Cu" "F.Mask" "F.Paste")
			(net "Net_748")
		)
		(pad "5" smd rect
			(at 1.299972 -1.100074 90)
			(size 0.4064 1.3462)
			(layers "F.Cu" "F.Mask" "F.Paste")
			(net "SG")
		)
		(pad "G1" smd rect
			(at -0.999998 1.575054 90)
			(size 1.4986 1.905)
			(layers "F.Cu" "F.Mask" "F.Paste")
			(net "SG")
		)
		(pad "G2" smd rect
			(at 0.999998 1.575054 90)
			(size 1.4986 1.905)
			(layers "F.Cu" "F.Mask" "F.Paste")
			(net "SG")
		)
		(pad "GH1" thru_hole circle
			(at -2.500122 -1.124966 90)
			(size 1.4478 1.4478)
			(drill 0.8382)
			(layers "*.Cu" "*.Mask")
			(remove_unused_layers no)
			(net "SG")
			(padstack
				(mode front_inner_back)
				(layer "Inner"
					(shape circle)
					(size 1.4478 1.4478)
					(clearance -0.0127)
				)
				(layer "B.Cu"
					(shape circle)
					(size 1.4478 1.4478)
				)
			)
		)
		(pad "GH2" thru_hole circle
			(at 2.500122 -1.124966 90)
			(size 1.4478 1.4478)
			(drill 0.8382)
			(layers "*.Cu" "*.Mask")
			(remove_unused_layers no)
			(net "SG")
			(padstack
				(mode front_inner_back)
				(layer "Inner"
					(shape circle)
					(size 1.4478 1.4478)
					(clearance -0.0127)
				)
				(layer "B.Cu"
					(shape circle)
					(size 1.4478 1.4478)
				)
			)
		)
		(pad "GH3" thru_hole circle
			(at -3.50012 1.575054 90)
			(size 0 0)
			(drill oval 0.6096 1.2954)
			(layers "*.Cu" "*.Mask")
			(remove_unused_layers no)
			(net "SG")
			(padstack
				(mode front_inner_back)
				(layer "Inner"
					(shape oval)
					(size 1.2192 1.905)
					(clearance -0.0127)
				)
				(layer "B.Cu"
					(shape oval)
					(size 1.2192 1.905)
				)
			)
		)
		(pad "GH4" thru_hole circle
			(at 3.50012 1.575054 90)
			(size 0 0)
			(drill oval 0.6096 1.2954)
			(layers "*.Cu" "*.Mask")
			(remove_unused_layers no)
			(net "SG")
			(padstack
				(mode front_inner_back)
				(layer "Inner"
					(shape oval)
					(size 1.2192 1.905)
					(clearance -0.0127)
				)
				(layer "B.Cu"
					(shape oval)
					(size 1.2192 1.905)
				)
			)
		)
	)
	(footprint ""
		(layer "F.Cu")
		(at 135.6614 -100.5078)
		(property "Reference" "R11"
			(at -2.0574 -0.29083 0)
			(unlocked yes)
			(layer "F.SilkS")
			(effects
				(font
					(size 0.7874 0.5842)
					(thickness 0.1524)
				)
			)
		)
		(property "Value" "VAL*"
			(at 0.02032 2.13233 0)
			(unlocked yes)
			(layer "F.Fab")
			(hide yes)
			(effects
				(font
					(size 0.7874 0.5842)
					(thickness 0.1524)
				)
			)
		)
		(property "Device Type" "RESISTOR-G155-01203-01,120KOHMA"
			(at 0.008382 1.210564 0)
			(unlocked yes)
			(layer "F.Fab")
			(hide yes)
			(effects
				(font
					(size 0.7874 0.5842)
					(thickness 0.1524)
				)
			)
		)
		(property "User Part Number" "PARTNUM*"
			(at 0.02032 4.024884 0)
			(unlocked yes)
			(layer "Cmts.User")
			(hide yes)
			(effects
				(font
					(size 0.7874 0.5842)
					(thickness 0.1524)
				)
			)
		)
		(property "Tolerance" "TOL*"
			(at 0.044704 3.05435 0)
			(unlocked yes)
			(layer "Cmts.User")
			(hide yes)
			(effects
				(font
					(size 0.7874 0.5842)
					(thickness 0.1524)
				)
			)
		)
		(duplicate_pad_numbers_are_jumpers no)
		(fp_line
			(start -1.143 -0.5588)
			(end -1.143 0.5588)
			(stroke
				(width 0.1)
				(type default)
			)
			(layer "F.SilkS")
		)
		(fp_line
			(start -1.143 0.5588)
			(end 1.143 0.5588)
			(stroke
				(width 0.1)
				(type default)
			)
			(layer "F.SilkS")
		)
		(fp_line
			(start 1.143 -0.5588)
			(end -1.143 -0.5588)
			(stroke
				(width 0.1)
				(type default)
			)
			(layer "F.SilkS")
		)
		(fp_line
			(start 1.143 0.5588)
			(end 1.143 -0.5588)
			(stroke
				(width 0.1)
				(type default)
			)
			(layer "F.SilkS")
		)
		(fp_rect
			(start -1.143 0.5588)
			(end 1.143 -0.5588)
			(stroke
				(width 0)
				(type default)
			)
			(fill no)
			(layer "F.CrtYd")
		)
		(fp_line
			(start -0.508 -0.3048)
			(end -0.508 0.3048)
			(stroke
				(width 0.1)
				(type default)
			)
			(layer "F.Fab")
		)
		(fp_line
			(start -0.508 0.3048)
			(end 0.508 0.3048)
			(stroke
				(width 0.1)
				(type default)
			)
			(layer "F.Fab")
		)
		(fp_line
			(start 0.508 -0.3048)
			(end -0.508 -0.3048)
			(stroke
				(width 0.1)
				(type default)
			)
			(layer "F.Fab")
		)
		(fp_line
			(start 0.508 0.3048)
			(end 0.508 -0.3048)
			(stroke
				(width 0.1)
				(type default)
			)
			(layer "F.Fab")
		)
		(pad "1" smd rect
			(at -0.5334 0)
			(size 0.7112 0.6096)
			(layers "F.Cu" "F.Mask" "F.Paste")
			(net "XP12R0V_IN")
		)
		(pad "2" smd rect
			(at 0.5334 0)
			(size 0.7112 0.6096)
			(layers "F.Cu" "F.Mask" "F.Paste")
			(net "XP12R0V_A_OV")
		)
		(zone
			(layer "F.Cu")
			(hatch none 0.5)
			(connect_pads
				(clearance 0)
			)
			(min_thickness 0.25)
			(keepout
				(tracks allowed)
				(vias not_allowed)
				(pads allowed)
				(copperpour not_allowed)
				(footprints allowed)
			)
			(placement
				(enabled no)
				(sheetname "")
			)
			(fill
				(thermal_gap 0.5)
				(thermal_bridge_width 0.5)
				(island_removal_mode 0)
			)
			(polygon
				(pts
					(xy 135.5852 -100.203) (xy 135.7376 -100.203) (xy 135.7376 -100.8126) (xy 135.5852 -100.8126)
				)
			)
		)
	)
	(footprint ""
		(layer "F.Cu")
		(at 105.8418 -72.517 180)
		(property "Reference" "C240"
			(at -0.3302 -4.09067 0)
			(unlocked yes)
			(layer "F.SilkS")
			(effects
				(font
					(size 0.7874 0.5842)
					(thickness 0.1524)
				)
			)
		)
		(property "Value" "VAL*"
			(at 0.0762 3.134106 180)
			(unlocked yes)
			(layer "F.Fab")
			(hide yes)
			(effects
				(font
					(size 0.7874 0.5842)
					(thickness 0.1524)
				)
			)
		)
		(property "Device Type" "CAPACITOR-G107-0F226-CM,22UF,2A"
			(at 0.0508 2.194306 180)
			(unlocked yes)
			(layer "F.Fab")
			(hide yes)
			(effects
				(font
					(size 0.7874 0.5842)
					(thickness 0.1524)
				)
			)
		)
		(property "User Part Number" "PARTNUM*"
			(at 0.1016 5.013706 180)
			(unlocked yes)
			(layer "Cmts.User")
			(hide yes)
			(effects
				(font
					(size 0.7874 0.5842)
					(thickness 0.1524)
				)
			)
		)
		(property "Tolerance" "TOL*"
			(at 0.0762 4.048506 180)
			(unlocked yes)
			(layer "Cmts.User")
			(hide yes)
			(effects
				(font
					(size 0.7874 0.5842)
					(thickness 0.1524)
				)
			)
		)
		(duplicate_pad_numbers_are_jumpers no)
		(fp_line
			(start 1.5748 0.9398)
			(end 1.5748 -0.9398)
			(stroke
				(width 0.1)
				(type default)
			)
			(layer "F.SilkS")
		)
		(fp_line
			(start 1.5748 -0.9398)
			(end -1.5748 -0.9398)
			(stroke
				(width 0.1)
				(type default)
			)
			(layer "F.SilkS")
		)
		(fp_line
			(start -1.5748 0.9398)
			(end 1.5748 0.9398)
			(stroke
				(width 0.1)
				(type default)
			)
			(layer "F.SilkS")
		)
		(fp_line
			(start -1.5748 -0.9398)
			(end -1.5748 0.9398)
			(stroke
				(width 0.1)
				(type default)
			)
			(layer "F.SilkS")
		)
		(fp_rect
			(start -1.5748 0.9398)
			(end 1.5748 -0.9398)
			(stroke
				(width 0)
				(type default)
			)
			(fill no)
			(layer "F.CrtYd")
		)
		(fp_line
			(start 1.016 0.635)
			(end 1.016 -0.635)
			(stroke
				(width 0.1)
				(type default)
			)
			(layer "F.Fab")
		)
		(fp_line
			(start 1.016 -0.635)
			(end -1.016 -0.635)
			(stroke
				(width 0.1)
				(type default)
			)
			(layer "F.Fab")
		)
		(fp_line
			(start -1.016 0.635)
			(end 1.016 0.635)
			(stroke
				(width 0.1)
				(type default)
			)
			(layer "F.Fab")
		)
		(fp_line
			(start -1.016 -0.635)
			(end -1.016 0.635)
			(stroke
				(width 0.1)
				(type default)
			)
			(layer "F.Fab")
		)
		(pad "1" smd rect
			(at -0.8382 0 180)
			(size 0.9652 1.3716)
			(layers "F.Cu" "F.Mask" "F.Paste")
			(net "XP3R3V_FPGA")
		)
		(pad "2" smd rect
			(at 0.8382 0 180)
			(size 0.9652 1.3716)
			(layers "F.Cu" "F.Mask" "F.Paste")
			(net "SG")
		)
		(zone
			(layer "F.Cu")
			(hatch none 0.5)
			(connect_pads
				(clearance 0)
			)
			(min_thickness 0.25)
			(keepout
				(tracks allowed)
				(vias not_allowed)
				(pads allowed)
				(copperpour not_allowed)
				(footprints allowed)
			)
			(placement
				(enabled no)
				(sheetname "")
			)
			(fill
				(thermal_gap 0.5)
				(thermal_bridge_width 0.5)
				(island_removal_mode 0)
			)
			(polygon
				(pts
					(xy 106.0704 -73.152) (xy 105.6132 -73.152) (xy 105.6132 -71.882) (xy 106.0704 -71.882)
				)
			)
		)
	)
	(footprint ""
		(layer "F.Cu")
		(at 162.569906 -16.599916)
		(property "Reference" "ME12"
			(at 0.371094 -4.188714 0)
			(unlocked yes)
			(layer "F.SilkS")
			(effects
				(font
					(size 0.7874 0.5842)
					(thickness 0.1524)
				)
			)
		)
		(property "Value" ""
			(at 0 0 0)
			(layer "F.Fab")
			(effects
				(font
					(size 1.27 1.27)
				)
			)
		)
		(property "Device Type" "MEC_MTH8-MTH125C236N_V8-MTH125A"
			(at 0 5.08127 0)
			(unlocked yes)
			(layer "F.Fab")
			(hide yes)
			(effects
				(font
					(size 0.7874 0.5842)
					(thickness 0.1524)
				)
			)
		)
		(duplicate_pad_numbers_are_jumpers no)
		(fp_poly
			(pts
				(arc
					(start 3.5052 0)
					(mid -3.5052 0)
					(end 3.5052 0)
				)
			)
			(stroke
				(width 0)
				(type default)
			)
			(fill no)
			(layer "B.CrtYd")
		)
		(fp_poly
			(pts
				(arc
					(start 3.5052 0)
					(mid -3.5052 0)
					(end 3.5052 0)
				)
			)
			(stroke
				(width 0)
				(type default)
			)
			(fill no)
			(layer "F.CrtYd")
		)
		(fp_circle
			(center 0 0)
			(end 2.9972 0)
			(stroke
				(width 0.1)
				(type default)
			)
			(fill no)
			(layer "B.Fab")
		)
		(fp_circle
			(center 0 0)
			(end 2.9972 0)
			(stroke
				(width 0.1)
				(type default)
			)
			(fill no)
			(layer "F.Fab")
		)
		(pad "" np_thru_hole circle
			(at 0 0)
			(size 2.921 2.921)
			(drill 3.175)
			(layers "*.Cu" "*.Mask")
			(padstack
				(mode front_inner_back)
				(layer "Inner"
					(shape circle)
					(size 2.921 2.921)
					(clearance 0.4445)
				)
				(layer "B.Cu"
					(shape circle)
					(size 2.921 2.921)
				)
			)
		)
		(pad "1" thru_hole circle
			(at 0 -2.4511)
			(size 0.6096 0.6096)
			(drill 0.3048)
			(layers "*.Cu" "*.Mask")
			(remove_unused_layers no)
			(net "SG")
			(padstack
				(mode front_inner_back)
				(layer "Inner"
					(shape circle)
					(size 0.6096 0.6096)
					(clearance 0.1143)
				)
				(layer "B.Cu"
					(shape circle)
					(size 0.6096 0.6096)
				)
			)
		)
		(pad "2" thru_hole circle
			(at 1.733296 -1.733296)
			(size 0.6096 0.6096)
			(drill 0.3048)
			(layers "*.Cu" "*.Mask")
			(remove_unused_layers no)
			(net "SG")
			(padstack
				(mode front_inner_back)
				(layer "Inner"
					(shape circle)
					(size 0.6096 0.6096)
					(clearance 0.1143)
				)
				(layer "B.Cu"
					(shape circle)
					(size 0.6096 0.6096)
				)
			)
		)
		(pad "3" thru_hole circle
			(at 2.4511 0)
			(size 0.6096 0.6096)
			(drill 0.3048)
			(layers "*.Cu" "*.Mask")
			(remove_unused_layers no)
			(net "SG")
			(padstack
				(mode front_inner_back)
				(layer "Inner"
					(shape circle)
					(size 0.6096 0.6096)
					(clearance 0.1143)
				)
				(layer "B.Cu"
					(shape circle)
					(size 0.6096 0.6096)
				)
			)
		)
		(pad "4" thru_hole circle
			(at 1.733296 1.733296)
			(size 0.6096 0.6096)
			(drill 0.3048)
			(layers "*.Cu" "*.Mask")
			(remove_unused_layers no)
			(net "SG")
			(padstack
				(mode front_inner_back)
				(layer "Inner"
					(shape circle)
					(size 0.6096 0.6096)
					(clearance 0.1143)
				)
				(layer "B.Cu"
					(shape circle)
					(size 0.6096 0.6096)
				)
			)
		)
		(pad "5" thru_hole circle
			(at 0 2.4511)
			(size 0.6096 0.6096)
			(drill 0.3048)
			(layers "*.Cu" "*.Mask")
			(remove_unused_layers no)
			(net "SG")
			(padstack
				(mode front_inner_back)
				(layer "Inner"
					(shape circle)
					(size 0.6096 0.6096)
					(clearance 0.1143)
				)
				(layer "B.Cu"
					(shape circle)
					(size 0.6096 0.6096)
				)
			)
		)
		(pad "6" thru_hole circle
			(at -1.733296 1.733296)
			(size 0.6096 0.6096)
			(drill 0.3048)
			(layers "*.Cu" "*.Mask")
			(remove_unused_layers no)
			(net "SG")
			(padstack
				(mode front_inner_back)
				(layer "Inner"
					(shape circle)
					(size 0.6096 0.6096)
					(clearance 0.1143)
				)
				(layer "B.Cu"
					(shape circle)
					(size 0.6096 0.6096)
				)
			)
		)
		(pad "7" thru_hole circle
			(at -2.4511 0)
			(size 0.6096 0.6096)
			(drill 0.3048)
			(layers "*.Cu" "*.Mask")
			(remove_unused_layers no)
			(net "SG")
			(padstack
				(mode front_inner_back)
				(layer "Inner"
					(shape circle)
					(size 0.6096 0.6096)
					(clearance 0.1143)
				)
				(layer "B.Cu"
					(shape circle)
					(size 0.6096 0.6096)
				)
			)
		)
		(pad "8" thru_hole circle
			(at -1.733296 -1.733296)
			(size 0.6096 0.6096)
			(drill 0.3048)
			(layers "*.Cu" "*.Mask")
			(remove_unused_layers no)
			(net "SG")
			(padstack
				(mode front_inner_back)
				(layer "Inner"
					(shape circle)
					(size 0.6096 0.6096)
					(clearance 0.1143)
				)
				(layer "B.Cu"
					(shape circle)
					(size 0.6096 0.6096)
				)
			)
		)
		(zone
			(layers "F.Cu" "B.Cu" "In1.Cu" "In2.Cu" "In3.Cu" "In4.Cu" "In5.Cu" "In6.Cu"
				"In7.Cu" "In8.Cu"
			)
			(hatch none 0.5)
			(connect_pads
				(clearance 0)
			)
			(min_thickness 0.25)
			(keepout
				(tracks not_allowed)
				(vias allowed)
				(pads allowed)
				(copperpour not_allowed)
				(footprints allowed)
			)
			(placement
				(enabled no)
				(sheetname "")
			)
			(fill
				(thermal_gap 0.5)
				(thermal_bridge_width 0.5)
				(island_removal_mode 0)
			)
			(polygon
				(pts
					(arc
						(start 164.462206 -16.599916)
						(mid 160.677606 -16.599916)
						(end 164.462206 -16.599916)
					)
				)
			)
		)
	)
	(footprint ""
		(layer "F.Cu")
		(at 8.382 -81.534 90)
		(property "Reference" "R399"
			(at -2.667 -0.59563 90)
			(unlocked yes)
			(layer "F.SilkS")
			(effects
				(font
					(size 0.7874 0.5842)
					(thickness 0.1524)
				)
			)
		)
		(property "Value" "VAL*"
			(at 0.02032 2.13233 90)
			(unlocked yes)
			(layer "F.Fab")
			(hide yes)
			(effects
				(font
					(size 0.7874 0.5842)
					(thickness 0.1524)
				)
			)
		)
		(property "Tolerance" "TOL*"
			(at 0.044704 3.05435 90)
			(unlocked yes)
			(layer "Cmts.User")
			(hide yes)
			(effects
				(font
					(size 0.7874 0.5842)
					(thickness 0.1524)
				)
			)
		)
		(property "User Part Number" "PARTNUM*"
			(at 0.02032 4.024884 90)
			(unlocked yes)
			(layer "Cmts.User")
			(hide yes)
			(effects
				(font
					(size 0.7874 0.5842)
					(thickness 0.1524)
				)
			)
		)
		(property "Device Type" "RESISTOR-G155-133R0-01,33OHM,1%"
			(at 0.008382 1.210564 90)
			(unlocked yes)
			(layer "F.Fab")
			(hide yes)
			(effects
				(font
					(size 0.7874 0.5842)
					(thickness 0.1524)
				)
			)
		)
		(duplicate_pad_numbers_are_jumpers no)
		(fp_line
			(start 1.143 -0.5588)
			(end -1.143 -0.5588)
			(stroke
				(width 0.1)
				(type default)
			)
			(layer "F.SilkS")
		)
		(fp_line
			(start -1.143 -0.5588)
			(end -1.143 0.5588)
			(stroke
				(width 0.1)
				(type default)
			)
			(layer "F.SilkS")
		)
		(fp_line
			(start 1.143 0.5588)
			(end 1.143 -0.5588)
			(stroke
				(width 0.1)
				(type default)
			)
			(layer "F.SilkS")
		)
		(fp_line
			(start -1.143 0.5588)
			(end 1.143 0.5588)
			(stroke
				(width 0.1)
				(type default)
			)
			(layer "F.SilkS")
		)
		(fp_rect
			(start -1.143 -0.5588)
			(end 1.143 0.5588)
			(stroke
				(width 0)
				(type default)
			)
			(fill no)
			(layer "F.CrtYd")
		)
		(fp_line
			(start 0.508 -0.3048)
			(end -0.508 -0.3048)
			(stroke
				(width 0.1)
				(type default)
			)
			(layer "F.Fab")
		)
		(fp_line
			(start -0.508 -0.3048)
			(end -0.508 0.3048)
			(stroke
				(width 0.1)
				(type default)
			)
			(layer "F.Fab")
		)
		(fp_line
			(start 0.508 0.3048)
			(end 0.508 -0.3048)
			(stroke
				(width 0.1)
				(type default)
			)
			(layer "F.Fab")
		)
		(fp_line
			(start -0.508 0.3048)
			(end 0.508 0.3048)
			(stroke
				(width 0.1)
				(type default)
			)
			(layer "F.Fab")
		)
		(pad "1" smd rect
			(at -0.5334 0 90)
			(size 0.7112 0.6096)
			(layers "F.Cu" "F.Mask" "F.Paste")
			(net "GPS_SMA_LED_RED_N")
		)
		(pad "2" smd rect
			(at 0.5334 0 90)
			(size 0.7112 0.6096)
			(layers "F.Cu" "F.Mask" "F.Paste")
			(net "UNNAMED_14_LED4PV14_I269_3")
		)
		(zone
			(layer "F.Cu")
			(hatch none 0.5)
			(connect_pads
				(clearance 0)
			)
			(min_thickness 0.25)
			(keepout
				(tracks not_allowed)
				(vias allowed)
				(pads allowed)
				(copperpour not_allowed)
				(footprints allowed)
			)
			(placement
				(enabled no)
				(sheetname "")
			)
			(fill
				(thermal_gap 0.5)
				(thermal_bridge_width 0.5)
				(island_removal_mode 0)
			)
			(polygon
				(pts
					(xy 8.0772 -81.4578) (xy 8.6868 -81.4578) (xy 8.6868 -81.6102) (xy 8.0772 -81.6102)
				)
			)
		)
		(zone
			(layer "F.Cu")
			(hatch none 0.5)
			(connect_pads
				(clearance 0)
			)
			(min_thickness 0.25)
			(keepout
				(tracks allowed)
				(vias not_allowed)
				(pads allowed)
				(copperpour not_allowed)
				(footprints allowed)
			)
			(placement
				(enabled no)
				(sheetname "")
			)
			(fill
				(thermal_gap 0.5)
				(thermal_bridge_width 0.5)
				(island_removal_mode 0)
			)
			(polygon
				(pts
					(xy 8.0772 -81.4578) (xy 8.6868 -81.4578) (xy 8.6868 -81.6102) (xy 8.0772 -81.6102)
				)
			)
		)
	)
	(footprint ""
		(layer "F.Cu")
		(at 20.052792 -67.5894 180)
		(property "Reference" "U28"
			(at 0.494792 2.09423 0)
			(unlocked yes)
			(layer "F.SilkS")
			(effects
				(font
					(size 0.7874 0.5842)
					(thickness 0.1524)
				)
			)
		)
		(property "Value" ""
			(at 0 0 180)
			(layer "F.Fab")
			(effects
				(font
					(size 1.27 1.27)
				)
			)
		)
		(property "Device Type" "ICP_10100_LGA10-A222-00002-FB,A"
			(at 0.0635 3.182112 180)
			(unlocked yes)
			(layer "F.Fab")
			(hide yes)
			(effects
				(font
					(size 0.7874 0.5842)
					(thickness 0.1524)
				)
			)
		)
		(property "User Part Number" "PARTNUM*"
			(at 0.0635 4.375912 180)
			(unlocked yes)
			(layer "Cmts.User")
			(hide yes)
			(effects
				(font
					(size 0.7874 0.5842)
					(thickness 0.1524)
				)
			)
		)
		(duplicate_pad_numbers_are_jumpers no)
		(fp_line
			(start 1.304036 1.304036)
			(end -1.304036 1.304036)
			(stroke
				(width 0.1)
				(type default)
			)
			(layer "F.SilkS")
		)
		(fp_line
			(start 1.304036 -1.304036)
			(end 1.304036 1.304036)
			(stroke
				(width 0.1)
				(type default)
			)
			(layer "F.SilkS")
		)
		(fp_line
			(start -1.304036 1.304036)
			(end -1.304036 -1.304036)
			(stroke
				(width 0.1)
				(type default)
			)
			(layer "F.SilkS")
		)
		(fp_line
			(start -1.304036 -1.304036)
			(end 1.304036 -1.304036)
			(stroke
				(width 0.1)
				(type default)
			)
			(layer "F.SilkS")
		)
		(fp_poly
			(pts
				(arc
					(start -2.172208 2.2606)
					(mid -1.156716 2.2606)
					(end -2.172208 2.2606)
				)
			)
			(stroke
				(width 0)
				(type default)
			)
			(fill yes)
			(layer "F.SilkS")
		)
		(fp_rect
			(start 1.558036 1.558036)
			(end -1.558036 -1.558036)
			(stroke
				(width 0)
				(type default)
			)
			(fill no)
			(layer "F.CrtYd")
		)
		(fp_line
			(start 1.050036 1.050036)
			(end -1.050036 1.050036)
			(stroke
				(width 0.1)
				(type default)
			)
			(layer "F.Fab")
		)
		(fp_line
			(start 1.050036 -1.050036)
			(end 1.050036 1.050036)
			(stroke
				(width 0.1)
				(type default)
			)
			(layer "F.Fab")
		)
		(fp_line
			(start -1.050036 1.050036)
			(end -1.050036 -1.050036)
			(stroke
				(width 0.1)
				(type default)
			)
			(layer "F.Fab")
		)
		(fp_line
			(start -1.050036 -1.050036)
			(end 1.050036 -1.050036)
			(stroke
				(width 0.1)
				(type default)
			)
			(layer "F.Fab")
		)
		(fp_poly
			(pts
				(arc
					(start -1.200658 2.133854)
					(mid -0.185166 2.133854)
					(end -1.200658 2.133854)
				)
			)
			(stroke
				(width 0)
				(type default)
			)
			(fill yes)
			(layer "F.Fab")
		)
		(fp_text user "2"
			(at 1.891792 2.10185 0)
			(unlocked yes)
			(layer "F.SilkS")
			(effects
				(font
					(size 0.635 0.4064)
					(thickness 0.1524)
				)
			)
		)
		(fp_text user "5"
			(at 1.759458 -0.96139 0)
			(unlocked yes)
			(layer "F.SilkS")
			(effects
				(font
					(size 0.635 0.4064)
					(thickness 0.1524)
				)
			)
		)
		(fp_text user "3"
			(at 1.693418 0.212598 0)
			(unlocked yes)
			(layer "F.SilkS")
			(effects
				(font
					(size 0.635 0.4064)
					(thickness 0.1524)
				)
			)
		)
		(fp_text user "6"
			(at 1.510792 -1.83515 0)
			(unlocked yes)
			(layer "F.SilkS")
			(effects
				(font
					(size 0.635 0.4064)
					(thickness 0.1524)
				)
			)
		)
		(fp_text user "8"
			(at -1.918208 -1.45415 0)
			(unlocked yes)
			(layer "F.SilkS")
			(effects
				(font
					(size 0.635 0.4064)
					(thickness 0.1524)
				)
			)
		)
		(fp_text user "3"
			(at 1.637792 1.09093 0)
			(unlocked yes)
			(layer "F.Fab")
			(effects
				(font
					(size 0.7874 0.5842)
					(thickness 0.1524)
				)
			)
		)
		(fp_text user "5"
			(at 1.383792 -0.56007 0)
			(unlocked yes)
			(layer "F.Fab")
			(effects
				(font
					(size 0.7874 0.5842)
					(thickness 0.1524)
				)
			)
		)
		(fp_text user "6"
			(at 1.383792 -1.70307 0)
			(unlocked yes)
			(layer "F.Fab")
			(effects
				(font
					(size 0.7874 0.5842)
					(thickness 0.1524)
				)
			)
		)
		(fp_text user "2"
			(at 0.621792 1.72593 0)
			(unlocked yes)
			(layer "F.Fab")
			(effects
				(font
					(size 0.7874 0.5842)
					(thickness 0.1524)
				)
			)
		)
		(fp_text user "7"
			(at -0.521208 -1.70307 0)
			(unlocked yes)
			(layer "F.Fab")
			(effects
				(font
					(size 0.7874 0.5842)
					(thickness 0.1524)
				)
			)
		)
		(fp_text user "8"
			(at -1.664208 -0.68707 0)
			(unlocked yes)
			(layer "F.Fab")
			(effects
				(font
					(size 0.7874 0.5842)
					(thickness 0.1524)
				)
			)
		)
		(fp_text user "10"
			(at -1.791208 1.47193 0)
			(unlocked yes)
			(layer "F.Fab")
			(effects
				(font
					(size 0.7874 0.5842)
					(thickness 0.1524)
				)
			)
		)
		(pad "1" smd rect
			(at -0.249936 0.774954 180)
			(size 0.2794 0.3556)
			(layers "F.Cu" "F.Mask" "F.Paste")
			(net "UNNAMED_8_ICP10100LGA10_I24_RES")
		)
		(pad "2" smd rect
			(at 0.249936 0.774954 180)
			(size 0.2794 0.3556)
			(layers "F.Cu" "F.Mask" "F.Paste")
			(net "R_ICP10100_I2C_SCL")
		)
		(pad "3" smd rect
			(at 0.774954 0.500126 180)
			(size 0.3556 0.2794)
			(layers "F.Cu" "F.Mask" "F.Paste")
			(net "UNNAMED_8_ICP10100LGA10_I24_R_1")
		)
		(pad "4" smd rect
			(at 0.774954 0 180)
			(size 0.3556 0.2794)
			(layers "F.Cu" "F.Mask" "F.Paste")
			(net "R_ICP10100_I2C_SDA")
		)
		(pad "5" smd rect
			(at 0.774954 -0.500126 180)
			(size 0.3556 0.2794)
			(layers "F.Cu" "F.Mask" "F.Paste")
			(net "UNNAMED_8_ICP10100LGA10_I24_R_2")
		)
		(pad "6" smd rect
			(at 0.249936 -0.774954 180)
			(size 0.2794 0.3556)
			(layers "F.Cu" "F.Mask" "F.Paste")
			(net "UNNAMED_8_ICP10100LGA10_I24_R_3")
		)
		(pad "7" smd rect
			(at -0.249936 -0.774954 180)
			(size 0.2794 0.3556)
			(layers "F.Cu" "F.Mask" "F.Paste")
			(net "UNNAMED_8_ICP10100LGA10_I24_R_4")
		)
		(pad "8" smd rect
			(at -0.774954 -0.500126 180)
			(size 0.3556 0.2794)
			(layers "F.Cu" "F.Mask" "F.Paste")
			(net "SG")
		)
		(pad "9" smd rect
			(at -0.774954 0 180)
			(size 0.3556 0.2794)
			(layers "F.Cu" "F.Mask" "F.Paste")
			(net "SG")
		)
		(pad "10" smd rect
			(at -0.774954 0.500126 180)
			(size 0.3556 0.2794)
			(layers "F.Cu" "F.Mask" "F.Paste")
			(net "XP1R8V_ICP10100")
		)
	)
	(footprint ""
		(layer "F.Cu")
		(at 126.492 -36.322)
		(property "Reference" "R222"
			(at 2.921 1.56337 0)
			(unlocked yes)
			(layer "F.SilkS")
			(effects
				(font
					(size 0.7874 0.5842)
					(thickness 0.1524)
				)
			)
		)
		(property "Value" "VAL*"
			(at 0.02032 2.13233 0)
			(unlocked yes)
			(layer "F.Fab")
			(hide yes)
			(effects
				(font
					(size 0.7874 0.5842)
					(thickness 0.1524)
				)
			)
		)
		(property "Device Type" "RESISTOR-G155-11000-01,100OHM,A"
			(at 0.008382 1.210564 0)
			(unlocked yes)
			(layer "F.Fab")
			(hide yes)
			(effects
				(font
					(size 0.7874 0.5842)
					(thickness 0.1524)
				)
			)
		)
		(property "User Part Number" "PARTNUM*"
			(at 0.02032 4.024884 0)
			(unlocked yes)
			(layer "Cmts.User")
			(hide yes)
			(effects
				(font
					(size 0.7874 0.5842)
					(thickness 0.1524)
				)
			)
		)
		(property "Tolerance" "TOL*"
			(at 0.044704 3.05435 0)
			(unlocked yes)
			(layer "Cmts.User")
			(hide yes)
			(effects
				(font
					(size 0.7874 0.5842)
					(thickness 0.1524)
				)
			)
		)
		(duplicate_pad_numbers_are_jumpers no)
		(fp_line
			(start -1.143 -0.5588)
			(end -1.143 0.5588)
			(stroke
				(width 0.1)
				(type default)
			)
			(layer "F.SilkS")
		)
		(fp_line
			(start -1.143 0.5588)
			(end 1.143 0.5588)
			(stroke
				(width 0.1)
				(type default)
			)
			(layer "F.SilkS")
		)
		(fp_line
			(start 1.143 -0.5588)
			(end -1.143 -0.5588)
			(stroke
				(width 0.1)
				(type default)
			)
			(layer "F.SilkS")
		)
		(fp_line
			(start 1.143 0.5588)
			(end 1.143 -0.5588)
			(stroke
				(width 0.1)
				(type default)
			)
			(layer "F.SilkS")
		)
		(fp_rect
			(start -1.143 0.5588)
			(end 1.143 -0.5588)
			(stroke
				(width 0)
				(type default)
			)
			(fill no)
			(layer "F.CrtYd")
		)
		(fp_line
			(start -0.508 -0.3048)
			(end -0.508 0.3048)
			(stroke
				(width 0.1)
				(type default)
			)
			(layer "F.Fab")
		)
		(fp_line
			(start -0.508 0.3048)
			(end 0.508 0.3048)
			(stroke
				(width 0.1)
				(type default)
			)
			(layer "F.Fab")
		)
		(fp_line
			(start 0.508 -0.3048)
			(end -0.508 -0.3048)
			(stroke
				(width 0.1)
				(type default)
			)
			(layer "F.Fab")
		)
		(fp_line
			(start 0.508 0.3048)
			(end 0.508 -0.3048)
			(stroke
				(width 0.1)
				(type default)
			)
			(layer "F.Fab")
		)
		(pad "1" smd rect
			(at -0.5334 0)
			(size 0.7112 0.6096)
			(layers "F.Cu" "F.Mask" "F.Paste")
			(net "FPGA_M2")
		)
		(pad "2" smd rect
			(at 0.5334 0)
			(size 0.7112 0.6096)
			(layers "F.Cu" "F.Mask" "F.Paste")
			(net "SG")
		)
		(zone
			(layer "F.Cu")
			(hatch none 0.5)
			(connect_pads
				(clearance 0)
			)
			(min_thickness 0.25)
			(keepout
				(tracks allowed)
				(vias not_allowed)
				(pads allowed)
				(copperpour not_allowed)
				(footprints allowed)
			)
			(placement
				(enabled no)
				(sheetname "")
			)
			(fill
				(thermal_gap 0.5)
				(thermal_bridge_width 0.5)
				(island_removal_mode 0)
			)
			(polygon
				(pts
					(xy 126.4158 -36.0172) (xy 126.5682 -36.0172) (xy 126.5682 -36.6268) (xy 126.4158 -36.6268)
				)
			)
		)
	)
	(footprint ""
		(layer "F.Cu")
		(at 127.889 -62.8396)
		(property "Reference" "C183"
			(at 1.143 4.83997 0)
			(unlocked yes)
			(layer "F.SilkS")
			(effects
				(font
					(size 0.7874 0.5842)
					(thickness 0.1524)
				)
			)
		)
		(property "Value" "VAL*"
			(at 0.0762 2.067306 0)
			(unlocked yes)
			(layer "F.Fab")
			(hide yes)
			(effects
				(font
					(size 0.7874 0.5842)
					(thickness 0.1524)
				)
			)
		)
		(property "Device Type" "CAPACITOR-G105-0B104-EK,0.1UF,A"
			(at 0.0508 1.127506 0)
			(unlocked yes)
			(layer "F.Fab")
			(hide yes)
			(effects
				(font
					(size 0.7874 0.5842)
					(thickness 0.1524)
				)
			)
		)
		(property "User Part Number" "PARTNUM*"
			(at 0.1016 4.023106 0)
			(unlocked yes)
			(layer "Cmts.User")
			(hide yes)
			(effects
				(font
					(size 0.7874 0.5842)
					(thickness 0.1524)
				)
			)
		)
		(property "Tolerance" "TOL*"
			(at 0.0762 3.032506 0)
			(unlocked yes)
			(layer "Cmts.User")
			(hide yes)
			(effects
				(font
					(size 0.7874 0.5842)
					(thickness 0.1524)
				)
			)
		)
		(duplicate_pad_numbers_are_jumpers no)
		(fp_line
			(start -1.143 -0.5588)
			(end -1.143 0.5588)
			(stroke
				(width 0.1)
				(type default)
			)
			(layer "F.SilkS")
		)
		(fp_line
			(start -1.143 0.5588)
			(end 1.143 0.5588)
			(stroke
				(width 0.1)
				(type default)
			)
			(layer "F.SilkS")
		)
		(fp_line
			(start 1.143 -0.5588)
			(end -1.143 -0.5588)
			(stroke
				(width 0.1)
				(type default)
			)
			(layer "F.SilkS")
		)
		(fp_line
			(start 1.143 0.5588)
			(end 1.143 -0.5588)
			(stroke
				(width 0.1)
				(type default)
			)
			(layer "F.SilkS")
		)
		(fp_rect
			(start 1.143 -0.5588)
			(end -1.143 0.5588)
			(stroke
				(width 0)
				(type default)
			)
			(fill no)
			(layer "F.CrtYd")
		)
		(fp_line
			(start -0.508 -0.3048)
			(end -0.508 0.3048)
			(stroke
				(width 0.1)
				(type default)
			)
			(layer "F.Fab")
		)
		(fp_line
			(start -0.508 0.3048)
			(end 0.508 0.3048)
			(stroke
				(width 0.1)
				(type default)
			)
			(layer "F.Fab")
		)
		(fp_line
			(start 0.508 -0.3048)
			(end -0.508 -0.3048)
			(stroke
				(width 0.1)
				(type default)
			)
			(layer "F.Fab")
		)
		(fp_line
			(start 0.508 0.3048)
			(end 0.508 -0.3048)
			(stroke
				(width 0.1)
				(type default)
			)
			(layer "F.Fab")
		)
		(pad "1" smd rect
			(at -0.5334 0)
			(size 0.7112 0.6096)
			(layers "F.Cu" "F.Mask" "F.Paste")
			(net "XP3R3V")
		)
		(pad "2" smd rect
			(at 0.5334 0)
			(size 0.7112 0.6096)
			(layers "F.Cu" "F.Mask" "F.Paste")
			(net "SG")
		)
		(zone
			(layer "F.Cu")
			(hatch none 0.5)
			(connect_pads
				(clearance 0)
			)
			(min_thickness 0.25)
			(keepout
				(tracks allowed)
				(vias not_allowed)
				(pads allowed)
				(copperpour not_allowed)
				(footprints allowed)
			)
			(placement
				(enabled no)
				(sheetname "")
			)
			(fill
				(thermal_gap 0.5)
				(thermal_bridge_width 0.5)
				(island_removal_mode 0)
			)
			(polygon
				(pts
					(xy 127.9652 -63.1444) (xy 127.8128 -63.1444) (xy 127.8128 -62.5348) (xy 127.9652 -62.5348)
				)
			)
		)
	)
	(footprint ""
		(layer "F.Cu")
		(at 16.256 -70.866 180)
		(property "Reference" "R346"
			(at -0.381 1.73863 0)
			(unlocked yes)
			(layer "F.SilkS")
			(effects
				(font
					(size 0.7874 0.5842)
					(thickness 0.1524)
				)
			)
		)
		(property "Value" "VAL*"
			(at 0.02032 2.13233 180)
			(unlocked yes)
			(layer "F.Fab")
			(hide yes)
			(effects
				(font
					(size 0.7874 0.5842)
					(thickness 0.1524)
				)
			)
		)
		(property "Tolerance" "TOL*"
			(at 0.044704 3.05435 180)
			(unlocked yes)
			(layer "Cmts.User")
			(hide yes)
			(effects
				(font
					(size 0.7874 0.5842)
					(thickness 0.1524)
				)
			)
		)
		(property "User Part Number" "PARTNUM*"
			(at 0.02032 4.024884 180)
			(unlocked yes)
			(layer "Cmts.User")
			(hide yes)
			(effects
				(font
					(size 0.7874 0.5842)
					(thickness 0.1524)
				)
			)
		)
		(property "Device Type" "RESISTOR-G155-100R0-J0,0OHM,-"
			(at 0.008382 1.210564 180)
			(unlocked yes)
			(layer "F.Fab")
			(hide yes)
			(effects
				(font
					(size 0.7874 0.5842)
					(thickness 0.1524)
				)
			)
		)
		(duplicate_pad_numbers_are_jumpers no)
		(fp_line
			(start 1.143 0.5588)
			(end 1.143 -0.5588)
			(stroke
				(width 0.1)
				(type default)
			)
			(layer "F.SilkS")
		)
		(fp_line
			(start 1.143 -0.5588)
			(end -1.143 -0.5588)
			(stroke
				(width 0.1)
				(type default)
			)
			(layer "F.SilkS")
		)
		(fp_line
			(start -1.143 0.5588)
			(end 1.143 0.5588)
			(stroke
				(width 0.1)
				(type default)
			)
			(layer "F.SilkS")
		)
		(fp_line
			(start -1.143 -0.5588)
			(end -1.143 0.5588)
			(stroke
				(width 0.1)
				(type default)
			)
			(layer "F.SilkS")
		)
		(fp_poly
			(pts
				(xy -1.143 0.5588) (xy 1.143 0.5588) (xy 1.143 -0.5588) (xy -1.143 -0.5588)
			)
			(stroke
				(width 0)
				(type default)
			)
			(fill no)
			(layer "F.CrtYd")
		)
		(fp_line
			(start 0.508 0.3048)
			(end 0.508 -0.3048)
			(stroke
				(width 0.1)
				(type default)
			)
			(layer "F.Fab")
		)
		(fp_line
			(start 0.508 -0.3048)
			(end -0.508 -0.3048)
			(stroke
				(width 0.1)
				(type default)
			)
			(layer "F.Fab")
		)
		(fp_line
			(start -0.508 0.3048)
			(end 0.508 0.3048)
			(stroke
				(width 0.1)
				(type default)
			)
			(layer "F.Fab")
		)
		(fp_line
			(start -0.508 -0.3048)
			(end -0.508 0.3048)
			(stroke
				(width 0.1)
				(type default)
			)
			(layer "F.Fab")
		)
		(pad "1" smd rect
			(at -0.5334 0 180)
			(size 0.7112 0.6096)
			(layers "F.Cu" "F.Mask" "F.Paste")
			(net "UNNAMED_8_ICP10100LGA10_I24_R_1")
		)
		(pad "2" smd rect
			(at 0.5334 0 180)
			(size 0.7112 0.6096)
			(layers "F.Cu" "F.Mask" "F.Paste")
			(net "SG")
		)
		(zone
			(layer "F.Cu")
			(hatch none 0.5)
			(connect_pads
				(clearance 0)
			)
			(min_thickness 0.25)
			(keepout
				(tracks allowed)
				(vias not_allowed)
				(pads allowed)
				(copperpour not_allowed)
				(footprints allowed)
			)
			(placement
				(enabled no)
				(sheetname "")
			)
			(fill
				(thermal_gap 0.5)
				(thermal_bridge_width 0.5)
				(island_removal_mode 0)
			)
			(polygon
				(pts
					(xy 16.3322 -71.1708) (xy 16.1798 -71.1708) (xy 16.1798 -70.5612) (xy 16.3322 -70.5612)
				)
			)
		)
		(zone
			(layer "F.Cu")
			(hatch none 0.5)
			(connect_pads
				(clearance 0)
			)
			(min_thickness 0.25)
			(keepout
				(tracks not_allowed)
				(vias allowed)
				(pads allowed)
				(copperpour not_allowed)
				(footprints allowed)
			)
			(placement
				(enabled no)
				(sheetname "")
			)
			(fill
				(thermal_gap 0.5)
				(thermal_bridge_width 0.5)
				(island_removal_mode 0)
			)
			(polygon
				(pts
					(xy 16.3322 -71.1708) (xy 16.1798 -71.1708) (xy 16.1798 -70.5612) (xy 16.3322 -70.5612)
				)
			)
		)
	)
	(footprint ""
		(layer "F.Cu")
		(at 16.1544 -74.041)
		(property "Reference" "TP24"
			(at -2.3876 -2.37363 0)
			(unlocked yes)
			(layer "F.SilkS")
			(effects
				(font
					(size 0.7874 0.5842)
					(thickness 0.1524)
				)
				(justify left)
			)
		)
		(property "Value" ""
			(at 0 0 0)
			(layer "F.Fab")
			(effects
				(font
					(size 1.27 1.27)
				)
			)
		)
		(property "Device Type" "TP_PIONT-TP010CT020B030_PTH-TPA"
			(at -1.341882 0.996696 0)
			(unlocked yes)
			(layer "F.Fab")
			(hide yes)
			(effects
				(font
					(size 0.7874 0.5842)
					(thickness 0.000001)
				)
				(justify left)
			)
		)
		(duplicate_pad_numbers_are_jumpers no)
		(fp_poly
			(pts
				(arc
					(start 0.889 0)
					(mid -0.889 0)
					(end 0.889 0)
				)
			)
			(stroke
				(width 0)
				(type default)
			)
			(fill no)
			(layer "B.CrtYd")
		)
		(fp_poly
			(pts
				(arc
					(start 0.889 0)
					(mid -0.889 0)
					(end 0.889 0)
				)
			)
			(stroke
				(width 0)
				(type default)
			)
			(fill no)
			(layer "F.CrtYd")
		)
		(pad "1" thru_hole circle
			(at 0 0)
			(size 0.508 0.508)
			(drill 0.254)
			(layers "*.Cu" "*.Mask")
			(remove_unused_layers no)
			(net "FPGA_IN_LM75B_INT1_N")
			(clearance 0.1016)
			(padstack
				(mode front_inner_back)
				(layer "Inner"
					(shape circle)
					(size 0.508 0.508)
					(clearance 0.1016)
				)
				(layer "B.Cu"
					(shape circle)
					(size 0.762 0.762)
					(clearance -0.0254)
				)
			)
		)
	)
	(footprint ""
		(layer "F.Cu")
		(at 14.351 -28.702)
		(property "Reference" "TP30"
			(at -0.22225 2.5654 90)
			(unlocked yes)
			(layer "F.SilkS")
			(effects
				(font
					(size 0.635 0.4064)
					(thickness 0.1524)
				)
				(justify left)
			)
		)
		(property "Value" ""
			(at 0 0 0)
			(layer "F.Fab")
			(effects
				(font
					(size 1.27 1.27)
				)
			)
		)
		(property "Device Type" "TP_PIONT-TP010CT020B030_PTH-TPA"
			(at -1.341882 0.996696 0)
			(unlocked yes)
			(layer "F.Fab")
			(hide yes)
			(effects
				(font
					(size 0.7874 0.5842)
					(thickness 0.000001)
				)
				(justify left)
			)
		)
		(duplicate_pad_numbers_are_jumpers no)
		(fp_poly
			(pts
				(arc
					(start 0.889 0)
					(mid -0.889 0)
					(end 0.889 0)
				)
			)
			(stroke
				(width 0)
				(type default)
			)
			(fill no)
			(layer "B.CrtYd")
		)
		(fp_poly
			(pts
				(arc
					(start 0.889 0)
					(mid -0.889 0)
					(end 0.889 0)
				)
			)
			(stroke
				(width 0)
				(type default)
			)
			(fill no)
			(layer "F.CrtYd")
		)
		(pad "1" thru_hole circle
			(at 0 0)
			(size 0.508 0.508)
			(drill 0.254)
			(layers "*.Cu" "*.Mask")
			(remove_unused_layers no)
			(net "SMA3_SIG_IN_BF_EN_N")
			(clearance 0.1016)
			(padstack
				(mode front_inner_back)
				(layer "Inner"
					(shape circle)
					(size 0.508 0.508)
					(clearance 0.1016)
				)
				(layer "B.Cu"
					(shape circle)
					(size 0.762 0.762)
					(clearance -0.0254)
				)
			)
		)
	)
	(footprint ""
		(layer "F.Cu")
		(at 145.2372 -100.711)
		(property "Reference" "TP37"
			(at 1.4224 0.15875 0)
			(unlocked yes)
			(layer "F.SilkS")
			(effects
				(font
					(size 0.635 0.4064)
					(thickness 0.1524)
				)
				(justify left)
			)
		)
		(property "Value" ""
			(at 0 0 0)
			(layer "F.Fab")
			(effects
				(font
					(size 1.27 1.27)
				)
			)
		)
		(property "Device Type" "TP_PIONT-TP010CT020B030_PTH-TPA"
			(at -1.341882 0.996696 0)
			(unlocked yes)
			(layer "F.Fab")
			(hide yes)
			(effects
				(font
					(size 0.7874 0.5842)
					(thickness 0.000001)
				)
				(justify left)
			)
		)
		(duplicate_pad_numbers_are_jumpers no)
		(fp_poly
			(pts
				(arc
					(start 0.889 0)
					(mid -0.889 0)
					(end 0.889 0)
				)
			)
			(stroke
				(width 0)
				(type default)
			)
			(fill no)
			(layer "B.CrtYd")
		)
		(fp_poly
			(pts
				(arc
					(start 0.889 0)
					(mid -0.889 0)
					(end 0.889 0)
				)
			)
			(stroke
				(width 0)
				(type default)
			)
			(fill no)
			(layer "F.CrtYd")
		)
		(pad "1" thru_hole circle
			(at 0 0)
			(size 0.508 0.508)
			(drill 0.254)
			(layers "*.Cu" "*.Mask")
			(remove_unused_layers no)
			(net "XP12R0V_A_FLTB")
			(clearance 0.1016)
			(padstack
				(mode front_inner_back)
				(layer "Inner"
					(shape circle)
					(size 0.508 0.508)
					(clearance 0.1016)
				)
				(layer "B.Cu"
					(shape circle)
					(size 0.762 0.762)
					(clearance -0.0254)
				)
			)
		)
	)
	(footprint ""
		(layer "F.Cu")
		(at 133.858 -70.866 -90)
		(property "Reference" "R179"
			(at -4.191 -1.05537 90)
			(unlocked yes)
			(layer "F.SilkS")
			(effects
				(font
					(size 0.7874 0.5842)
					(thickness 0.1524)
				)
			)
		)
		(property "Value" "VAL*"
			(at 0.02032 2.13233 270)
			(unlocked yes)
			(layer "F.Fab")
			(hide yes)
			(effects
				(font
					(size 0.7874 0.5842)
					(thickness 0.1524)
				)
			)
		)
		(property "Device Type" "RESISTOR-G155-14701-01,4.7KOHMA"
			(at 0.008382 1.210564 270)
			(unlocked yes)
			(layer "F.Fab")
			(hide yes)
			(effects
				(font
					(size 0.7874 0.5842)
					(thickness 0.1524)
				)
			)
		)
		(property "User Part Number" "PARTNUM*"
			(at 0.02032 4.024884 270)
			(unlocked yes)
			(layer "Cmts.User")
			(hide yes)
			(effects
				(font
					(size 0.7874 0.5842)
					(thickness 0.1524)
				)
			)
		)
		(property "Tolerance" "TOL*"
			(at 0.044704 3.05435 270)
			(unlocked yes)
			(layer "Cmts.User")
			(hide yes)
			(effects
				(font
					(size 0.7874 0.5842)
					(thickness 0.1524)
				)
			)
		)
		(duplicate_pad_numbers_are_jumpers no)
		(fp_line
			(start -1.143 0.5588)
			(end 1.143 0.5588)
			(stroke
				(width 0.1)
				(type default)
			)
			(layer "F.SilkS")
		)
		(fp_line
			(start 1.143 0.5588)
			(end 1.143 -0.5588)
			(stroke
				(width 0.1)
				(type default)
			)
			(layer "F.SilkS")
		)
		(fp_line
			(start -1.143 -0.5588)
			(end -1.143 0.5588)
			(stroke
				(width 0.1)
				(type default)
			)
			(layer "F.SilkS")
		)
		(fp_line
			(start 1.143 -0.5588)
			(end -1.143 -0.5588)
			(stroke
				(width 0.1)
				(type default)
			)
			(layer "F.SilkS")
		)
		(fp_rect
			(start -1.143 0.5588)
			(end 1.143 -0.5588)
			(stroke
				(width 0)
				(type default)
			)
			(fill no)
			(layer "F.CrtYd")
		)
		(fp_line
			(start -0.508 0.3048)
			(end 0.508 0.3048)
			(stroke
				(width 0.1)
				(type default)
			)
			(layer "F.Fab")
		)
		(fp_line
			(start 0.508 0.3048)
			(end 0.508 -0.3048)
			(stroke
				(width 0.1)
				(type default)
			)
			(layer "F.Fab")
		)
		(fp_line
			(start -0.508 -0.3048)
			(end -0.508 0.3048)
			(stroke
				(width 0.1)
				(type default)
			)
			(layer "F.Fab")
		)
		(fp_line
			(start 0.508 -0.3048)
			(end -0.508 -0.3048)
			(stroke
				(width 0.1)
				(type default)
			)
			(layer "F.Fab")
		)
		(pad "1" smd rect
			(at -0.5334 0 270)
			(size 0.7112 0.6096)
			(layers "F.Cu" "F.Mask" "F.Paste")
			(net "XP3R3V")
		)
		(pad "2" smd rect
			(at 0.5334 0 270)
			(size 0.7112 0.6096)
			(layers "F.Cu" "F.Mask" "F.Paste")
			(net "XP1R8V_PG_R")
		)
		(zone
			(layer "F.Cu")
			(hatch none 0.5)
			(connect_pads
				(clearance 0)
			)
			(min_thickness 0.25)
			(keepout
				(tracks allowed)
				(vias not_allowed)
				(pads allowed)
				(copperpour not_allowed)
				(footprints allowed)
			)
			(placement
				(enabled no)
				(sheetname "")
			)
			(fill
				(thermal_gap 0.5)
				(thermal_bridge_width 0.5)
				(island_removal_mode 0)
			)
			(polygon
				(pts
					(xy 133.5532 -70.9422) (xy 133.5532 -70.7898) (xy 134.1628 -70.7898) (xy 134.1628 -70.9422)
				)
			)
		)
	)
	(footprint ""
		(layer "F.Cu")
		(at 58.313828 -12.425172)
		(property "Reference" "TP48"
			(at -0.986028 -1.505458 0)
			(unlocked yes)
			(layer "F.SilkS")
			(effects
				(font
					(size 0.7874 0.5842)
					(thickness 0.1524)
				)
				(justify left)
			)
		)
		(property "Value" ""
			(at 0 0 0)
			(layer "F.Fab")
			(effects
				(font
					(size 1.27 1.27)
				)
			)
		)
		(property "Device Type" "TP_PIONT-TP010CT020B030_PTH-TPA"
			(at -1.341882 0.996696 0)
			(unlocked yes)
			(layer "F.Fab")
			(hide yes)
			(effects
				(font
					(size 0.7874 0.5842)
					(thickness 0.000001)
				)
				(justify left)
			)
		)
		(duplicate_pad_numbers_are_jumpers no)
		(fp_poly
			(pts
				(arc
					(start 0.889 0)
					(mid -0.889 0)
					(end 0.889 0)
				)
			)
			(stroke
				(width 0)
				(type default)
			)
			(fill no)
			(layer "B.CrtYd")
		)
		(fp_poly
			(pts
				(arc
					(start 0.889 0)
					(mid -0.889 0)
					(end 0.889 0)
				)
			)
			(stroke
				(width 0)
				(type default)
			)
			(fill no)
			(layer "F.CrtYd")
		)
		(pad "1" thru_hole circle
			(at 0 0)
			(size 0.508 0.508)
			(drill 0.254)
			(layers "*.Cu" "*.Mask")
			(remove_unused_layers no)
			(net "PCIE_CONN_PERST_N")
			(clearance 0.1016)
			(padstack
				(mode front_inner_back)
				(layer "Inner"
					(shape circle)
					(size 0.508 0.508)
					(clearance 0.1016)
				)
				(layer "B.Cu"
					(shape circle)
					(size 0.762 0.762)
					(clearance -0.0254)
				)
			)
		)
	)
	(footprint ""
		(layer "F.Cu")
		(at 22.225 -75.057)
		(property "Reference" "TP7"
			(at 0 0 0)
			(layer "F.SilkS")
			(hide yes)
			(effects
				(font
					(size 1.27 1.27)
				)
			)
		)
		(property "Value" ""
			(at 0 0 0)
			(layer "F.Fab")
			(effects
				(font
					(size 1.27 1.27)
				)
			)
		)
		(property "Device Type" "TP_PIONT-TP010CT020B030_PTH-TPA"
			(at -1.341882 0.996696 0)
			(unlocked yes)
			(layer "F.Fab")
			(hide yes)
			(effects
				(font
					(size 0.7874 0.5842)
					(thickness 0.1524)
				)
				(justify left)
			)
		)
		(duplicate_pad_numbers_are_jumpers no)
		(fp_poly
			(pts
				(arc
					(start 0.889 0)
					(mid -0.889 0)
					(end 0.889 0)
				)
			)
			(stroke
				(width 0)
				(type default)
			)
			(fill no)
			(layer "B.CrtYd")
		)
		(fp_poly
			(pts
				(arc
					(start 0.889 0)
					(mid -0.889 0)
					(end 0.889 0)
				)
			)
			(stroke
				(width 0)
				(type default)
			)
			(fill no)
			(layer "F.CrtYd")
		)
		(pad "1" thru_hole circle
			(at 0 0)
			(size 0.508 0.508)
			(drill 0.254)
			(layers "*.Cu" "*.Mask")
			(remove_unused_layers no)
			(net "UNNAMED_524_FT4232HLREELQFP64_2")
			(clearance 0.1016)
			(padstack
				(mode front_inner_back)
				(layer "Inner"
					(shape circle)
					(size 0.508 0.508)
					(clearance 0.1016)
				)
				(layer "B.Cu"
					(shape circle)
					(size 0.762 0.762)
					(clearance -0.0254)
				)
			)
		)
	)
	(footprint ""
		(layer "F.Cu")
		(at 36.83 -141.478)
		(property "Reference" "SP20"
			(at 0 0 0)
			(layer "F.SilkS")
			(hide yes)
			(effects
				(font
					(size 1.27 1.27)
				)
			)
		)
		(property "Value" ""
			(at 0 0 0)
			(layer "F.Fab")
			(effects
				(font
					(size 1.27 1.27)
				)
			)
		)
		(duplicate_pad_numbers_are_jumpers no)
	)
	(footprint ""
		(layer "F.Cu")
		(at 49.657 -126.238)
		(property "Reference" "SP68"
			(at 0 0 0)
			(layer "F.SilkS")
			(hide yes)
			(effects
				(font
					(size 1.27 1.27)
				)
			)
		)
		(property "Value" ""
			(at 0 0 0)
			(layer "F.Fab")
			(effects
				(font
					(size 1.27 1.27)
				)
			)
		)
		(duplicate_pad_numbers_are_jumpers no)
	)
	(footprint ""
		(layer "F.Cu")
		(at 1.500124 -53.600096 90)
		(property "Reference" "DS17"
			(at 2.875534 0.785876 0)
			(unlocked yes)
			(layer "F.SilkS")
			(effects
				(font
					(size 0.7874 0.5842)
					(thickness 0.1524)
				)
			)
		)
		(property "Value" ""
			(at 0 0 90)
			(layer "F.Fab")
			(effects
				(font
					(size 1.27 1.27)
				)
			)
		)
		(property "User Part Number" "PARTNUM*"
			(at 0.015494 4.486402 90)
			(unlocked yes)
			(layer "Cmts.User")
			(hide yes)
			(effects
				(font
					(size 0.7874 0.5842)
					(thickness 0.1524)
				)
			)
		)
		(property "Device Type" "LED_4P_V14-G170-10189-01"
			(at 0.015494 3.292602 90)
			(unlocked yes)
			(layer "F.Fab")
			(hide yes)
			(effects
				(font
					(size 0.7874 0.5842)
					(thickness 0.1524)
				)
			)
		)
		(duplicate_pad_numbers_are_jumpers no)
		(fp_line
			(start 1.378966 -0.829056)
			(end -1.378966 -0.829056)
			(stroke
				(width 0.1)
				(type default)
			)
			(layer "F.SilkS")
		)
		(fp_line
			(start -1.378966 -0.829056)
			(end -1.378966 -0.452628)
			(stroke
				(width 0.1)
				(type default)
			)
			(layer "F.SilkS")
		)
		(fp_line
			(start 1.998218 -0.452628)
			(end 1.378966 -0.452628)
			(stroke
				(width 0.1)
				(type default)
			)
			(layer "F.SilkS")
		)
		(fp_line
			(start 1.378966 -0.452628)
			(end 1.378966 -0.829056)
			(stroke
				(width 0.1)
				(type default)
			)
			(layer "F.SilkS")
		)
		(fp_line
			(start -1.378966 -0.452628)
			(end -1.998218 -0.452628)
			(stroke
				(width 0.1)
				(type default)
			)
			(layer "F.SilkS")
		)
		(fp_line
			(start -1.998218 -0.452628)
			(end -1.998218 1.103884)
			(stroke
				(width 0.1)
				(type default)
			)
			(layer "F.SilkS")
		)
		(fp_line
			(start 1.998218 1.103884)
			(end 1.998218 -0.452628)
			(stroke
				(width 0.1)
				(type default)
			)
			(layer "F.SilkS")
		)
		(fp_line
			(start -1.998218 1.103884)
			(end 1.998218 1.103884)
			(stroke
				(width 0.1)
				(type default)
			)
			(layer "F.SilkS")
		)
		(fp_poly
			(pts
				(xy 0.918464 -1.698498) (xy 1.223264 -1.46939) (xy 0.994664 -1.46939) (xy 0.994664 -1.24079) (xy 0.842264 -1.24079)
				(xy 0.842264 -1.46939) (xy 0.613664 -1.46939)
			)
			(stroke
				(width 0)
				(type default)
			)
			(fill yes)
			(layer "F.SilkS")
		)
		(fp_poly
			(pts
				(xy -0.73406 -1.677416) (xy -0.42926 -1.448308) (xy -0.65786 -1.448308) (xy -0.65786 -1.219708)
				(xy -0.81026 -1.219708) (xy -0.81026 -1.448308) (xy -1.03886 -1.448308)
			)
			(stroke
				(width 0)
				(type default)
			)
			(fill yes)
			(layer "F.SilkS")
		)
		(fp_poly
			(pts
				(xy -2.252218 1.357884) (xy -2.252218 -0.706628) (xy -1.632966 -0.706628) (xy -1.632966 -1.083056)
				(xy 1.632966 -1.083056) (xy 1.632966 -0.706628) (xy 2.252218 -0.706628) (xy 2.252218 1.357884)
			)
			(stroke
				(width 0)
				(type default)
			)
			(fill no)
			(layer "F.CrtYd")
		)
		(fp_line
			(start 1.124966 -0.575056)
			(end -1.124966 -0.575056)
			(stroke
				(width 0.1)
				(type default)
			)
			(layer "F.Fab")
		)
		(fp_line
			(start -1.124966 -0.575056)
			(end -1.124966 -0.075184)
			(stroke
				(width 0.1)
				(type default)
			)
			(layer "F.Fab")
		)
		(fp_line
			(start 1.325118 -0.075184)
			(end 1.124966 -0.075184)
			(stroke
				(width 0.1)
				(type default)
			)
			(layer "F.Fab")
		)
		(fp_line
			(start 1.124966 -0.075184)
			(end 1.124966 -0.575056)
			(stroke
				(width 0.1)
				(type default)
			)
			(layer "F.Fab")
		)
		(fp_line
			(start -1.124966 -0.075184)
			(end -1.325118 -0.075184)
			(stroke
				(width 0.1)
				(type default)
			)
			(layer "F.Fab")
		)
		(fp_line
			(start -1.325118 -0.075184)
			(end -1.325118 0.574802)
			(stroke
				(width 0.1)
				(type default)
			)
			(layer "F.Fab")
		)
		(fp_line
			(start 1.325118 0.574802)
			(end 1.325118 -0.075184)
			(stroke
				(width 0.1)
				(type default)
			)
			(layer "F.Fab")
		)
		(fp_line
			(start -1.325118 0.574802)
			(end 1.325118 0.574802)
			(stroke
				(width 0.1)
				(type default)
			)
			(layer "F.Fab")
		)
		(fp_poly
			(pts
				(xy 0.918464 -1.698498) (xy 1.223264 -1.46939) (xy 0.994664 -1.46939) (xy 0.994664 -1.24079) (xy 0.842264 -1.24079)
				(xy 0.842264 -1.46939) (xy 0.613664 -1.46939)
			)
			(stroke
				(width 0)
				(type default)
			)
			(fill yes)
			(layer "F.Fab")
		)
		(fp_poly
			(pts
				(xy -0.73406 -1.677416) (xy -0.42926 -1.448308) (xy -0.65786 -1.448308) (xy -0.65786 -1.219708)
				(xy -0.81026 -1.219708) (xy -0.81026 -1.448308) (xy -1.03886 -1.448308)
			)
			(stroke
				(width 0)
				(type default)
			)
			(fill yes)
			(layer "F.Fab")
		)
		(fp_text user "1"
			(at -2.37617 0.376936 90)
			(unlocked yes)
			(layer "F.SilkS")
			(effects
				(font
					(size 0.7874 0.5842)
					(thickness 0.1524)
				)
			)
		)
		(fp_text user "2"
			(at -1.053846 1.420876 0)
			(unlocked yes)
			(layer "F.SilkS")
			(effects
				(font
					(size 0.635 0.4064)
					(thickness 0.1524)
				)
			)
		)
		(fp_text user "3"
			(at 1.486154 1.547876 0)
			(unlocked yes)
			(layer "F.SilkS")
			(effects
				(font
					(size 0.635 0.4064)
					(thickness 0.1524)
				)
			)
		)
		(fp_text user "4"
			(at 2.03835 1.166876 0)
			(unlocked yes)
			(layer "F.Fab")
			(effects
				(font
					(size 0.7874 0.5842)
					(thickness 0.1524)
				)
			)
		)
		(fp_text user "3"
			(at 1.02235 1.166876 0)
			(unlocked yes)
			(layer "F.Fab")
			(effects
				(font
					(size 0.7874 0.5842)
					(thickness 0.1524)
				)
			)
		)
		(fp_text user "2"
			(at 0.00635 1.166876 0)
			(unlocked yes)
			(layer "F.Fab")
			(effects
				(font
					(size 0.7874 0.5842)
					(thickness 0.1524)
				)
			)
		)
		(fp_text user "1"
			(at -1.061466 1.166876 0)
			(unlocked yes)
			(layer "F.Fab")
			(effects
				(font
					(size 0.7874 0.5842)
					(thickness 0.1524)
				)
			)
		)
		(pad "1" smd rect
			(at -1.325118 0.245872 90)
			(size 0.8382 0.889)
			(layers "F.Cu" "F.Mask" "F.Paste")
			(net "UNNAMED_14_LED4PV14_I268_1")
		)
		(pad "2" smd rect
			(at -0.424942 0.595884 90)
			(size 0.4572 0.508)
			(layers "F.Cu" "F.Mask" "F.Paste")
			(net "XP3R3V_FPGA")
		)
		(pad "3" smd rect
			(at 0.424942 0.595884 90)
			(size 0.4572 0.508)
			(layers "F.Cu" "F.Mask" "F.Paste")
			(net "UNNAMED_14_LED4PV14_I268_3")
		)
		(pad "4" smd rect
			(at 1.325118 0.245872 90)
			(size 0.8382 0.889)
			(layers "F.Cu" "F.Mask" "F.Paste")
			(net "UNNAMED_14_LED4PV14_I268_4")
		)
	)
	(footprint ""
		(layer "F.Cu")
		(at 107.188 -31.369 90)
		(property "Reference" "TP200"
			(at -3.0988 0.15875 90)
			(unlocked yes)
			(layer "F.SilkS")
			(effects
				(font
					(size 0.635 0.4064)
					(thickness 0.1524)
				)
				(justify left)
			)
		)
		(property "Value" ""
			(at 0 0 90)
			(layer "F.Fab")
			(effects
				(font
					(size 1.27 1.27)
				)
			)
		)
		(property "Device Type" "TP_PIONT-TP010CT020B030_PTH-TPA"
			(at -1.341882 0.996696 90)
			(unlocked yes)
			(layer "F.Fab")
			(hide yes)
			(effects
				(font
					(size 0.7874 0.5842)
					(thickness 0.1524)
				)
				(justify left)
			)
		)
		(duplicate_pad_numbers_are_jumpers no)
		(fp_poly
			(pts
				(arc
					(start 0 0.889)
					(mid 0 -0.889)
					(end 0 0.889)
				)
			)
			(stroke
				(width 0)
				(type default)
			)
			(fill no)
			(layer "B.CrtYd")
		)
		(fp_poly
			(pts
				(arc
					(start 0 0.889)
					(mid 0 -0.889)
					(end 0 0.889)
				)
			)
			(stroke
				(width 0)
				(type default)
			)
			(fill no)
			(layer "F.CrtYd")
		)
		(pad "1" thru_hole circle
			(at 0 0 90)
			(size 0.508 0.508)
			(drill 0.254)
			(layers "*.Cu" "*.Mask")
			(remove_unused_layers no)
			(net "IO_L20N_35")
			(clearance 0.1016)
			(padstack
				(mode front_inner_back)
				(layer "Inner"
					(shape circle)
					(size 0.508 0.508)
					(clearance 0.1016)
				)
				(layer "B.Cu"
					(shape circle)
					(size 0.762 0.762)
					(clearance -0.0254)
				)
			)
		)
	)
	(footprint ""
		(layer "F.Cu")
		(at 43.4594 -95.9104)
		(property "Reference" "C32"
			(at 0.127 4.05257 0)
			(unlocked yes)
			(layer "F.SilkS")
			(effects
				(font
					(size 0.7874 0.5842)
					(thickness 0.1524)
				)
			)
		)
		(property "Value" "VAL*"
			(at 0.0762 3.134106 0)
			(unlocked yes)
			(layer "F.Fab")
			(hide yes)
			(effects
				(font
					(size 0.7874 0.5842)
					(thickness 0.1524)
				)
			)
		)
		(property "Device Type" "CAPACITOR-G107-0F106-EM,10UF,2A"
			(at 0.0508 2.194306 0)
			(unlocked yes)
			(layer "F.Fab")
			(hide yes)
			(effects
				(font
					(size 0.7874 0.5842)
					(thickness 0.1524)
				)
			)
		)
		(property "User Part Number" "PARTNUM*"
			(at 0.1016 5.013706 0)
			(unlocked yes)
			(layer "Cmts.User")
			(hide yes)
			(effects
				(font
					(size 0.7874 0.5842)
					(thickness 0.1524)
				)
			)
		)
		(property "Tolerance" "TOL*"
			(at 0.0762 4.048506 0)
			(unlocked yes)
			(layer "Cmts.User")
			(hide yes)
			(effects
				(font
					(size 0.7874 0.5842)
					(thickness 0.1524)
				)
			)
		)
		(duplicate_pad_numbers_are_jumpers no)
		(fp_line
			(start -1.5748 -0.9398)
			(end -1.5748 0.9398)
			(stroke
				(width 0.1)
				(type default)
			)
			(layer "F.SilkS")
		)
		(fp_line
			(start -1.5748 0.9398)
			(end 1.5748 0.9398)
			(stroke
				(width 0.1)
				(type default)
			)
			(layer "F.SilkS")
		)
		(fp_line
			(start 1.5748 -0.9398)
			(end -1.5748 -0.9398)
			(stroke
				(width 0.1)
				(type default)
			)
			(layer "F.SilkS")
		)
		(fp_line
			(start 1.5748 0.9398)
			(end 1.5748 -0.9398)
			(stroke
				(width 0.1)
				(type default)
			)
			(layer "F.SilkS")
		)
		(fp_rect
			(start 1.5748 -0.9398)
			(end -1.5748 0.9398)
			(stroke
				(width 0)
				(type default)
			)
			(fill no)
			(layer "F.CrtYd")
		)
		(fp_line
			(start -1.016 -0.635)
			(end -1.016 0.635)
			(stroke
				(width 0.1)
				(type default)
			)
			(layer "F.Fab")
		)
		(fp_line
			(start -1.016 0.635)
			(end 1.016 0.635)
			(stroke
				(width 0.1)
				(type default)
			)
			(layer "F.Fab")
		)
		(fp_line
			(start 1.016 -0.635)
			(end -1.016 -0.635)
			(stroke
				(width 0.1)
				(type default)
			)
			(layer "F.Fab")
		)
		(fp_line
			(start 1.016 0.635)
			(end 1.016 -0.635)
			(stroke
				(width 0.1)
				(type default)
			)
			(layer "F.Fab")
		)
		(pad "1" smd rect
			(at -0.8382 0)
			(size 0.9652 1.3716)
			(layers "F.Cu" "F.Mask" "F.Paste")
			(net "VIN_XP5R0V")
		)
		(pad "2" smd rect
			(at 0.8382 0)
			(size 0.9652 1.3716)
			(layers "F.Cu" "F.Mask" "F.Paste")
			(net "SG")
		)
		(zone
			(layer "F.Cu")
			(hatch none 0.5)
			(connect_pads
				(clearance 0)
			)
			(min_thickness 0.25)
			(keepout
				(tracks allowed)
				(vias not_allowed)
				(pads allowed)
				(copperpour not_allowed)
				(footprints allowed)
			)
			(placement
				(enabled no)
				(sheetname "")
			)
			(fill
				(thermal_gap 0.5)
				(thermal_bridge_width 0.5)
				(island_removal_mode 0)
			)
			(polygon
				(pts
					(xy 43.688 -96.5454) (xy 43.2308 -96.5454) (xy 43.2308 -95.2754) (xy 43.688 -95.2754)
				)
			)
		)
	)
	(footprint ""
		(layer "F.Cu")
		(at 51.054 -126.111)
		(property "Reference" "SP69"
			(at 0 0 0)
			(layer "F.SilkS")
			(hide yes)
			(effects
				(font
					(size 1.27 1.27)
				)
			)
		)
		(property "Value" ""
			(at 0 0 0)
			(layer "F.Fab")
			(effects
				(font
					(size 1.27 1.27)
				)
			)
		)
		(duplicate_pad_numbers_are_jumpers no)
	)
	(footprint ""
		(layer "F.Cu")
		(at 81.0006 -52.324 180)
		(property "Reference" "R84"
			(at 0.9906 -14.39037 0)
			(unlocked yes)
			(layer "F.SilkS")
			(effects
				(font
					(size 0.7874 0.5842)
					(thickness 0.1524)
				)
			)
		)
		(property "Value" "VAL*"
			(at 0.02032 2.13233 180)
			(unlocked yes)
			(layer "F.Fab")
			(hide yes)
			(effects
				(font
					(size 0.7874 0.5842)
					(thickness 0.1524)
				)
			)
		)
		(property "Tolerance" "TOL*"
			(at 0.044704 3.05435 180)
			(unlocked yes)
			(layer "Cmts.User")
			(hide yes)
			(effects
				(font
					(size 0.7874 0.5842)
					(thickness 0.1524)
				)
			)
		)
		(property "User Part Number" "PARTNUM*"
			(at 0.02032 4.024884 180)
			(unlocked yes)
			(layer "Cmts.User")
			(hide yes)
			(effects
				(font
					(size 0.7874 0.5842)
					(thickness 0.1524)
				)
			)
		)
		(property "Device Type" "RESISTOR-G155-100R0-J0,0OHM,-"
			(at 0.008382 1.210564 180)
			(unlocked yes)
			(layer "F.Fab")
			(hide yes)
			(effects
				(font
					(size 0.7874 0.5842)
					(thickness 0.1524)
				)
			)
		)
		(duplicate_pad_numbers_are_jumpers no)
		(fp_line
			(start 1.143 0.5588)
			(end 1.143 -0.5588)
			(stroke
				(width 0.1)
				(type default)
			)
			(layer "F.SilkS")
		)
		(fp_line
			(start 1.143 -0.5588)
			(end -1.143 -0.5588)
			(stroke
				(width 0.1)
				(type default)
			)
			(layer "F.SilkS")
		)
		(fp_line
			(start -1.143 0.5588)
			(end 1.143 0.5588)
			(stroke
				(width 0.1)
				(type default)
			)
			(layer "F.SilkS")
		)
		(fp_line
			(start -1.143 -0.5588)
			(end -1.143 0.5588)
			(stroke
				(width 0.1)
				(type default)
			)
			(layer "F.SilkS")
		)
		(fp_rect
			(start 1.143 -0.5588)
			(end -1.143 0.5588)
			(stroke
				(width 0)
				(type default)
			)
			(fill no)
			(layer "F.CrtYd")
		)
		(fp_line
			(start 0.508 0.3048)
			(end 0.508 -0.3048)
			(stroke
				(width 0.1)
				(type default)
			)
			(layer "F.Fab")
		)
		(fp_line
			(start 0.508 -0.3048)
			(end -0.508 -0.3048)
			(stroke
				(width 0.1)
				(type default)
			)
			(layer "F.Fab")
		)
		(fp_line
			(start -0.508 0.3048)
			(end 0.508 0.3048)
			(stroke
				(width 0.1)
				(type default)
			)
			(layer "F.Fab")
		)
		(fp_line
			(start -0.508 -0.3048)
			(end -0.508 0.3048)
			(stroke
				(width 0.1)
				(type default)
			)
			(layer "F.Fab")
		)
		(pad "1" smd rect
			(at -0.5334 0 180)
			(size 0.7112 0.6096)
			(layers "F.Cu" "F.Mask" "F.Paste")
			(net "FPGA_OUT_MAC_PPS_IN1N")
		)
		(pad "2" smd rect
			(at 0.5334 0 180)
			(size 0.7112 0.6096)
			(layers "F.Cu" "F.Mask" "F.Paste")
			(net "R_MAC_PPS_IN1N")
		)
		(zone
			(layer "F.Cu")
			(hatch none 0.5)
			(connect_pads
				(clearance 0)
			)
			(min_thickness 0.25)
			(keepout
				(tracks allowed)
				(vias not_allowed)
				(pads allowed)
				(copperpour not_allowed)
				(footprints allowed)
			)
			(placement
				(enabled no)
				(sheetname "")
			)
			(fill
				(thermal_gap 0.5)
				(thermal_bridge_width 0.5)
				(island_removal_mode 0)
			)
			(polygon
				(pts
					(xy 80.9244 -52.0192) (xy 81.0768 -52.0192) (xy 81.0768 -52.6288) (xy 80.9244 -52.6288)
				)
			)
		)
	)
	(footprint ""
		(layer "F.Cu")
		(at 13.899896 -18.10004 -90)
		(property "Reference" "U14"
			(at 3.91541 0.945896 0)
			(unlocked yes)
			(layer "F.SilkS")
			(effects
				(font
					(size 0.7874 0.5842)
					(thickness 0.1524)
				)
			)
		)
		(property "Value" ""
			(at 0 0 270)
			(layer "F.Fab")
			(effects
				(font
					(size 1.27 1.27)
				)
			)
		)
		(property "Device Type" "74HCT2G125DP_TSSOP8-G220-00055A"
			(at 0 2.413 270)
			(unlocked yes)
			(layer "F.Fab")
			(hide yes)
			(effects
				(font
					(size 0.7874 0.5842)
					(thickness 0.1524)
				)
			)
		)
		(property "User Part Number" "PARTNUM*"
			(at 0 3.6068 270)
			(unlocked yes)
			(layer "Cmts.User")
			(hide yes)
			(effects
				(font
					(size 0.7874 0.5842)
					(thickness 0.1524)
				)
			)
		)
		(duplicate_pad_numbers_are_jumpers no)
		(fp_line
			(start -2.426716 1.304036)
			(end -2.426716 -1.304036)
			(stroke
				(width 0.1)
				(type default)
			)
			(layer "F.SilkS")
		)
		(fp_line
			(start 2.426716 1.304036)
			(end -2.426716 1.304036)
			(stroke
				(width 0.1)
				(type default)
			)
			(layer "F.SilkS")
		)
		(fp_line
			(start -2.426716 -1.304036)
			(end 2.426716 -1.304036)
			(stroke
				(width 0.1)
				(type default)
			)
			(layer "F.SilkS")
		)
		(fp_line
			(start 2.426716 -1.304036)
			(end 2.426716 1.304036)
			(stroke
				(width 0.1)
				(type default)
			)
			(layer "F.SilkS")
		)
		(fp_poly
			(pts
				(arc
					(start -2.98196 -1.594104)
					(mid -2.98196 -0.832104)
					(end -2.98196 -1.594104)
				)
			)
			(stroke
				(width 0)
				(type default)
			)
			(fill yes)
			(layer "F.SilkS")
		)
		(fp_poly
			(pts
				(xy -2.680716 1.558036) (xy 2.680716 1.558036) (xy 2.680716 -1.558036) (xy -2.680716 -1.558036)
			)
			(stroke
				(width 0)
				(type default)
			)
			(fill no)
			(layer "F.CrtYd")
		)
		(fp_line
			(start -1.199896 1.050036)
			(end 1.199896 1.050036)
			(stroke
				(width 0.1)
				(type default)
			)
			(layer "F.Fab")
		)
		(fp_line
			(start 1.199896 1.050036)
			(end 1.199896 -1.050036)
			(stroke
				(width 0.1)
				(type default)
			)
			(layer "F.Fab")
		)
		(fp_line
			(start -1.199896 -1.050036)
			(end -1.199896 1.050036)
			(stroke
				(width 0.1)
				(type default)
			)
			(layer "F.Fab")
		)
		(fp_line
			(start 1.199896 -1.050036)
			(end -1.199896 -1.050036)
			(stroke
				(width 0.1)
				(type default)
			)
			(layer "F.Fab")
		)
		(fp_poly
			(pts
				(arc
					(start -1.94437 -1.338326)
					(mid -1.94437 -0.576326)
					(end -1.94437 -1.338326)
				)
			)
			(stroke
				(width 0)
				(type default)
			)
			(fill yes)
			(layer "F.Fab")
		)
		(fp_text user "4"
			(at -2.208022 1.834896 0)
			(unlocked yes)
			(layer "F.SilkS")
			(effects
				(font
					(size 0.635 0.4064)
					(thickness 0.1524)
				)
			)
		)
		(fp_text user "5"
			(at 2.71399 1.834896 0)
			(unlocked yes)
			(layer "F.SilkS")
			(effects
				(font
					(size 0.635 0.4064)
					(thickness 0.1524)
				)
			)
		)
		(fp_text user "8"
			(at 3.125978 -1.975104 0)
			(unlocked yes)
			(layer "F.SilkS")
			(effects
				(font
					(size 0.635 0.4064)
					(thickness 0.1524)
				)
			)
		)
		(fp_text user "4"
			(at -1.781302 1.199896 0)
			(unlocked yes)
			(layer "F.Fab")
			(effects
				(font
					(size 0.7874 0.5842)
					(thickness 0.1524)
				)
			)
		)
		(fp_text user "5"
			(at 1.947926 0.710184 0)
			(unlocked yes)
			(layer "F.Fab")
			(effects
				(font
					(size 0.7874 0.5842)
					(thickness 0.1524)
				)
			)
		)
		(fp_text user "8"
			(at 1.96088 -0.910844 0)
			(unlocked yes)
			(layer "F.Fab")
			(effects
				(font
					(size 0.7874 0.5842)
					(thickness 0.1524)
				)
			)
		)
		(pad "1" smd rect
			(at -1.690116 -0.749808 270)
			(size 0.9652 0.3048)
			(layers "F.Cu" "F.Mask" "F.Paste")
			(net "SMA4_SIG_OUT_BF_EN_N")
		)
		(pad "2" smd rect
			(at -1.690116 -0.249936 270)
			(size 0.9652 0.3048)
			(layers "F.Cu" "F.Mask" "F.Paste")
			(net "UNNAMED_12_74HCT2G125DPTSSOP8_3")
		)
		(pad "3" smd rect
			(at -1.690116 0.249936 270)
			(size 0.9652 0.3048)
			(layers "F.Cu" "F.Mask" "F.Paste")
			(net "BF_ANT4_IN")
		)
		(pad "4" smd rect
			(at -1.690116 0.749808 270)
			(size 0.9652 0.3048)
			(layers "F.Cu" "F.Mask" "F.Paste")
			(net "SG")
		)
		(pad "5" smd rect
			(at 1.690116 0.749808 270)
			(size 0.9652 0.3048)
			(layers "F.Cu" "F.Mask" "F.Paste")
			(net "BF_SMA4_SIG_IO_CONN")
		)
		(pad "6" smd rect
			(at 1.690116 0.249936 270)
			(size 0.9652 0.3048)
			(layers "F.Cu" "F.Mask" "F.Paste")
			(net "BF_SMA4_SIG_IO_CONN")
		)
		(pad "7" smd rect
			(at 1.690116 -0.249936 270)
			(size 0.9652 0.3048)
			(layers "F.Cu" "F.Mask" "F.Paste")
			(net "SMA4_SIG_IN_BF_EN_N")
		)
		(pad "8" smd rect
			(at 1.690116 -0.749808 270)
			(size 0.9652 0.3048)
			(layers "F.Cu" "F.Mask" "F.Paste")
			(net "XP3R3V_FPGA")
		)
	)
	(footprint ""
		(layer "F.Cu")
		(at 49.7586 -83.0072 -90)
		(property "Reference" "R422"
			(at -3.3528 -0.19177 90)
			(unlocked yes)
			(layer "F.SilkS")
			(effects
				(font
					(size 0.7874 0.5842)
					(thickness 0.1524)
				)
			)
		)
		(property "Value" "VAL*"
			(at 0.02032 2.13233 270)
			(unlocked yes)
			(layer "F.Fab")
			(hide yes)
			(effects
				(font
					(size 0.7874 0.5842)
					(thickness 0.1524)
				)
			)
		)
		(property "Tolerance" "TOL*"
			(at 0.044704 3.05435 270)
			(unlocked yes)
			(layer "Cmts.User")
			(hide yes)
			(effects
				(font
					(size 0.7874 0.5842)
					(thickness 0.1524)
				)
			)
		)
		(property "User Part Number" "PARTNUM*"
			(at 0.02032 4.024884 270)
			(unlocked yes)
			(layer "Cmts.User")
			(hide yes)
			(effects
				(font
					(size 0.7874 0.5842)
					(thickness 0.1524)
				)
			)
		)
		(property "Device Type" "RESISTOR-G155-14701-01,4.7KOHMA"
			(at 0.008382 1.210564 270)
			(unlocked yes)
			(layer "F.Fab")
			(hide yes)
			(effects
				(font
					(size 0.7874 0.5842)
					(thickness 0.1524)
				)
			)
		)
		(duplicate_pad_numbers_are_jumpers no)
		(fp_line
			(start -1.143 0.5588)
			(end 1.143 0.5588)
			(stroke
				(width 0.1)
				(type default)
			)
			(layer "F.SilkS")
		)
		(fp_line
			(start 1.143 0.5588)
			(end 1.143 -0.5588)
			(stroke
				(width 0.1)
				(type default)
			)
			(layer "F.SilkS")
		)
		(fp_line
			(start -1.143 -0.5588)
			(end -1.143 0.5588)
			(stroke
				(width 0.1)
				(type default)
			)
			(layer "F.SilkS")
		)
		(fp_line
			(start 1.143 -0.5588)
			(end -1.143 -0.5588)
			(stroke
				(width 0.1)
				(type default)
			)
			(layer "F.SilkS")
		)
		(fp_rect
			(start -1.143 0.5588)
			(end 1.143 -0.5588)
			(stroke
				(width 0)
				(type default)
			)
			(fill no)
			(layer "F.CrtYd")
		)
		(fp_line
			(start -0.508 0.3048)
			(end 0.508 0.3048)
			(stroke
				(width 0.1)
				(type default)
			)
			(layer "F.Fab")
		)
		(fp_line
			(start 0.508 0.3048)
			(end 0.508 -0.3048)
			(stroke
				(width 0.1)
				(type default)
			)
			(layer "F.Fab")
		)
		(fp_line
			(start -0.508 -0.3048)
			(end -0.508 0.3048)
			(stroke
				(width 0.1)
				(type default)
			)
			(layer "F.Fab")
		)
		(fp_line
			(start 0.508 -0.3048)
			(end -0.508 -0.3048)
			(stroke
				(width 0.1)
				(type default)
			)
			(layer "F.Fab")
		)
		(pad "1" smd rect
			(at -0.5334 0 270)
			(size 0.7112 0.6096)
			(layers "F.Cu" "F.Mask" "F.Paste")
			(net "XP3R3V_FPGA")
		)
		(pad "2" smd rect
			(at 0.5334 0 270)
			(size 0.7112 0.6096)
			(layers "F.Cu" "F.Mask" "F.Paste")
			(net "FPGA_IN_LM75B_INT2_N")
		)
		(zone
			(layer "F.Cu")
			(hatch none 0.5)
			(connect_pads
				(clearance 0)
			)
			(min_thickness 0.25)
			(keepout
				(tracks not_allowed)
				(vias allowed)
				(pads allowed)
				(copperpour not_allowed)
				(footprints allowed)
			)
			(placement
				(enabled no)
				(sheetname "")
			)
			(fill
				(thermal_gap 0.5)
				(thermal_bridge_width 0.5)
				(island_removal_mode 0)
			)
			(polygon
				(pts
					(xy 49.4538 -83.0834) (xy 49.4538 -82.931) (xy 50.0634 -82.931) (xy 50.0634 -83.0834)
				)
			)
		)
		(zone
			(layer "F.Cu")
			(hatch none 0.5)
			(connect_pads
				(clearance 0)
			)
			(min_thickness 0.25)
			(keepout
				(tracks allowed)
				(vias not_allowed)
				(pads allowed)
				(copperpour not_allowed)
				(footprints allowed)
			)
			(placement
				(enabled no)
				(sheetname "")
			)
			(fill
				(thermal_gap 0.5)
				(thermal_bridge_width 0.5)
				(island_removal_mode 0)
			)
			(polygon
				(pts
					(xy 49.4538 -83.0834) (xy 49.4538 -82.931) (xy 50.0634 -82.931) (xy 50.0634 -83.0834)
				)
			)
		)
	)
	(footprint ""
		(layer "F.Cu")
		(at 68.216018 -65.009522)
		(property "Reference" "ME6"
			(at -4.444238 2.072132 0)
			(unlocked yes)
			(layer "F.SilkS")
			(effects
				(font
					(size 0.7874 0.5842)
					(thickness 0.1524)
				)
			)
		)
		(property "Value" ""
			(at 0 0 0)
			(layer "F.Fab")
			(effects
				(font
					(size 1.27 1.27)
				)
			)
		)
		(duplicate_pad_numbers_are_jumpers no)
		(fp_poly
			(pts
				(arc
					(start 3.556 0)
					(mid -3.556 0)
					(end 3.556 0)
				)
			)
			(stroke
				(width 0)
				(type default)
			)
			(fill no)
			(layer "B.CrtYd")
		)
		(fp_poly
			(pts
				(arc
					(start 3.556 0)
					(mid -3.556 0)
					(end 3.556 0)
				)
			)
			(stroke
				(width 0)
				(type default)
			)
			(fill no)
			(layer "F.CrtYd")
		)
		(fp_circle
			(center 0 0)
			(end 3.048 0)
			(stroke
				(width 0.1)
				(type default)
			)
			(fill no)
			(layer "B.Fab")
		)
		(fp_circle
			(center 0 0)
			(end 3.048 0)
			(stroke
				(width 0.1)
				(type default)
			)
			(fill no)
			(layer "F.Fab")
		)
		(pad "" np_thru_hole circle
			(at 0 0)
			(size 2.286 2.286)
			(drill 2.54)
			(layers "*.Cu" "*.Mask")
			(padstack
				(mode front_inner_back)
				(layer "Inner"
					(shape circle)
					(size 2.286 2.286)
					(clearance 0.4445)
				)
				(layer "B.Cu"
					(shape circle)
					(size 2.286 2.286)
				)
			)
		)
		(zone
			(layers "F.Cu" "B.Cu" "In1.Cu" "In2.Cu" "In3.Cu" "In4.Cu" "In5.Cu" "In6.Cu"
				"In7.Cu" "In8.Cu"
			)
			(hatch none 0.5)
			(connect_pads
				(clearance 0)
			)
			(min_thickness 0.25)
			(keepout
				(tracks not_allowed)
				(vias allowed)
				(pads allowed)
				(copperpour not_allowed)
				(footprints allowed)
			)
			(placement
				(enabled no)
				(sheetname "")
			)
			(fill
				(thermal_gap 0.5)
				(thermal_bridge_width 0.5)
				(island_removal_mode 0)
			)
			(polygon
				(pts
					(arc
						(start 69.790818 -65.009522)
						(mid 66.641218 -65.009522)
						(end 69.790818 -65.009522)
					)
				)
			)
		)
	)
	(footprint ""
		(layer "F.Cu")
		(at 19.468338 -44.45 180)
		(property "Reference" "R394"
			(at -3.518662 -0.16637 0)
			(unlocked yes)
			(layer "F.SilkS")
			(effects
				(font
					(size 0.7874 0.5842)
					(thickness 0.1524)
				)
			)
		)
		(property "Value" "VAL*"
			(at 0.02032 2.13233 180)
			(unlocked yes)
			(layer "F.Fab")
			(hide yes)
			(effects
				(font
					(size 0.7874 0.5842)
					(thickness 0.1524)
				)
			)
		)
		(property "Tolerance" "TOL*"
			(at 0.044704 3.05435 180)
			(unlocked yes)
			(layer "Cmts.User")
			(hide yes)
			(effects
				(font
					(size 0.7874 0.5842)
					(thickness 0.1524)
				)
			)
		)
		(property "User Part Number" "PARTNUM*"
			(at 0.02032 4.024884 180)
			(unlocked yes)
			(layer "Cmts.User")
			(hide yes)
			(effects
				(font
					(size 0.7874 0.5842)
					(thickness 0.1524)
				)
			)
		)
		(property "Device Type" "RESISTOR-G155-133R0-01,33OHM,1%"
			(at 0.008382 1.210564 180)
			(unlocked yes)
			(layer "F.Fab")
			(hide yes)
			(effects
				(font
					(size 0.7874 0.5842)
					(thickness 0.1524)
				)
			)
		)
		(duplicate_pad_numbers_are_jumpers no)
		(fp_line
			(start 1.143 0.5588)
			(end 1.143 -0.5588)
			(stroke
				(width 0.1)
				(type default)
			)
			(layer "F.SilkS")
		)
		(fp_line
			(start 1.143 -0.5588)
			(end -1.143 -0.5588)
			(stroke
				(width 0.1)
				(type default)
			)
			(layer "F.SilkS")
		)
		(fp_line
			(start -1.143 0.5588)
			(end 1.143 0.5588)
			(stroke
				(width 0.1)
				(type default)
			)
			(layer "F.SilkS")
		)
		(fp_line
			(start -1.143 -0.5588)
			(end -1.143 0.5588)
			(stroke
				(width 0.1)
				(type default)
			)
			(layer "F.SilkS")
		)
		(fp_rect
			(start -1.143 -0.5588)
			(end 1.143 0.5588)
			(stroke
				(width 0)
				(type default)
			)
			(fill no)
			(layer "F.CrtYd")
		)
		(fp_line
			(start 0.508 0.3048)
			(end 0.508 -0.3048)
			(stroke
				(width 0.1)
				(type default)
			)
			(layer "F.Fab")
		)
		(fp_line
			(start 0.508 -0.3048)
			(end -0.508 -0.3048)
			(stroke
				(width 0.1)
				(type default)
			)
			(layer "F.Fab")
		)
		(fp_line
			(start -0.508 0.3048)
			(end 0.508 0.3048)
			(stroke
				(width 0.1)
				(type default)
			)
			(layer "F.Fab")
		)
		(fp_line
			(start -0.508 -0.3048)
			(end -0.508 0.3048)
			(stroke
				(width 0.1)
				(type default)
			)
			(layer "F.Fab")
		)
		(pad "1" smd rect
			(at -0.5334 0 180)
			(size 0.7112 0.6096)
			(layers "F.Cu" "F.Mask" "F.Paste")
			(net "SMA4_LED_BLUE_N")
		)
		(pad "2" smd rect
			(at 0.5334 0 180)
			(size 0.7112 0.6096)
			(layers "F.Cu" "F.Mask" "F.Paste")
			(net "UNNAMED_14_LED4PV14_I268_1")
		)
		(zone
			(layer "F.Cu")
			(hatch none 0.5)
			(connect_pads
				(clearance 0)
			)
			(min_thickness 0.25)
			(keepout
				(tracks allowed)
				(vias not_allowed)
				(pads allowed)
				(copperpour not_allowed)
				(footprints allowed)
			)
			(placement
				(enabled no)
				(sheetname "")
			)
			(fill
				(thermal_gap 0.5)
				(thermal_bridge_width 0.5)
				(island_removal_mode 0)
			)
			(polygon
				(pts
					(xy 19.544538 -44.1452) (xy 19.544538 -44.7548) (xy 19.392138 -44.7548) (xy 19.392138 -44.1452)
				)
			)
		)
		(zone
			(layer "F.Cu")
			(hatch none 0.5)
			(connect_pads
				(clearance 0)
			)
			(min_thickness 0.25)
			(keepout
				(tracks not_allowed)
				(vias allowed)
				(pads allowed)
				(copperpour not_allowed)
				(footprints allowed)
			)
			(placement
				(enabled no)
				(sheetname "")
			)
			(fill
				(thermal_gap 0.5)
				(thermal_bridge_width 0.5)
				(island_removal_mode 0)
			)
			(polygon
				(pts
					(xy 19.544538 -44.1452) (xy 19.544538 -44.7548) (xy 19.392138 -44.7548) (xy 19.392138 -44.1452)
				)
			)
		)
	)
	(footprint ""
		(layer "F.Cu")
		(at 117.348 -61.976 90)
		(property "Reference" "R348"
			(at 3.302 0.80137 90)
			(unlocked yes)
			(layer "F.SilkS")
			(effects
				(font
					(size 0.7874 0.5842)
					(thickness 0.1524)
				)
			)
		)
		(property "Value" "VAL*"
			(at 0.02032 2.13233 90)
			(unlocked yes)
			(layer "F.Fab")
			(hide yes)
			(effects
				(font
					(size 0.7874 0.5842)
					(thickness 0.1524)
				)
			)
		)
		(property "Tolerance" "TOL*"
			(at 0.044704 3.05435 90)
			(unlocked yes)
			(layer "Cmts.User")
			(hide yes)
			(effects
				(font
					(size 0.7874 0.5842)
					(thickness 0.1524)
				)
			)
		)
		(property "User Part Number" "PARTNUM*"
			(at 0.02032 4.024884 90)
			(unlocked yes)
			(layer "Cmts.User")
			(hide yes)
			(effects
				(font
					(size 0.7874 0.5842)
					(thickness 0.1524)
				)
			)
		)
		(property "Device Type" "RESISTOR-G155-133R0-01,33OHM,1%"
			(at 0.008382 1.210564 90)
			(unlocked yes)
			(layer "F.Fab")
			(hide yes)
			(effects
				(font
					(size 0.7874 0.5842)
					(thickness 0.1524)
				)
			)
		)
		(duplicate_pad_numbers_are_jumpers no)
		(fp_line
			(start 1.143 -0.5588)
			(end -1.143 -0.5588)
			(stroke
				(width 0.1)
				(type default)
			)
			(layer "F.SilkS")
		)
		(fp_line
			(start -1.143 -0.5588)
			(end -1.143 0.5588)
			(stroke
				(width 0.1)
				(type default)
			)
			(layer "F.SilkS")
		)
		(fp_line
			(start 1.143 0.5588)
			(end 1.143 -0.5588)
			(stroke
				(width 0.1)
				(type default)
			)
			(layer "F.SilkS")
		)
		(fp_line
			(start -1.143 0.5588)
			(end 1.143 0.5588)
			(stroke
				(width 0.1)
				(type default)
			)
			(layer "F.SilkS")
		)
		(fp_poly
			(pts
				(xy -1.143 0.5588) (xy 1.143 0.5588) (xy 1.143 -0.5588) (xy -1.143 -0.5588)
			)
			(stroke
				(width 0)
				(type default)
			)
			(fill no)
			(layer "F.CrtYd")
		)
		(fp_line
			(start 0.508 -0.3048)
			(end -0.508 -0.3048)
			(stroke
				(width 0.1)
				(type default)
			)
			(layer "F.Fab")
		)
		(fp_line
			(start -0.508 -0.3048)
			(end -0.508 0.3048)
			(stroke
				(width 0.1)
				(type default)
			)
			(layer "F.Fab")
		)
		(fp_line
			(start 0.508 0.3048)
			(end 0.508 -0.3048)
			(stroke
				(width 0.1)
				(type default)
			)
			(layer "F.Fab")
		)
		(fp_line
			(start -0.508 0.3048)
			(end 0.508 0.3048)
			(stroke
				(width 0.1)
				(type default)
			)
			(layer "F.Fab")
		)
		(pad "1" smd rect
			(at -0.5334 0 90)
			(size 0.7112 0.6096)
			(layers "F.Cu" "F.Mask" "F.Paste")
			(net "FPGA_D03")
		)
		(pad "2" smd rect
			(at 0.5334 0 90)
			(size 0.7112 0.6096)
			(layers "F.Cu" "F.Mask" "F.Paste")
			(net "FPGA_FLASH_DQ3")
		)
		(zone
			(layer "F.Cu")
			(hatch none 0.5)
			(connect_pads
				(clearance 0)
			)
			(min_thickness 0.25)
			(keepout
				(tracks not_allowed)
				(vias allowed)
				(pads allowed)
				(copperpour not_allowed)
				(footprints allowed)
			)
			(placement
				(enabled no)
				(sheetname "")
			)
			(fill
				(thermal_gap 0.5)
				(thermal_bridge_width 0.5)
				(island_removal_mode 0)
			)
			(polygon
				(pts
					(xy 117.6528 -61.8998) (xy 117.6528 -62.0522) (xy 117.0432 -62.0522) (xy 117.0432 -61.8998)
				)
			)
		)
		(zone
			(layer "F.Cu")
			(hatch none 0.5)
			(connect_pads
				(clearance 0)
			)
			(min_thickness 0.25)
			(keepout
				(tracks allowed)
				(vias not_allowed)
				(pads allowed)
				(copperpour not_allowed)
				(footprints allowed)
			)
			(placement
				(enabled no)
				(sheetname "")
			)
			(fill
				(thermal_gap 0.5)
				(thermal_bridge_width 0.5)
				(island_removal_mode 0)
			)
			(polygon
				(pts
					(xy 117.6528 -61.8998) (xy 117.6528 -62.0522) (xy 117.0432 -62.0522) (xy 117.0432 -61.8998)
				)
			)
		)
	)
	(footprint ""
		(layer "F.Cu")
		(at 83.185 -54.991)
		(property "Reference" "R290"
			(at -9.398 -18.62963 0)
			(unlocked yes)
			(layer "F.SilkS")
			(effects
				(font
					(size 0.7874 0.5842)
					(thickness 0.1524)
				)
			)
		)
		(property "Value" "VAL*"
			(at 0.02032 2.13233 0)
			(unlocked yes)
			(layer "F.Fab")
			(hide yes)
			(effects
				(font
					(size 0.7874 0.5842)
					(thickness 0.1524)
				)
			)
		)
		(property "Tolerance" "TOL*"
			(at 0.044704 3.05435 0)
			(unlocked yes)
			(layer "Cmts.User")
			(hide yes)
			(effects
				(font
					(size 0.7874 0.5842)
					(thickness 0.1524)
				)
			)
		)
		(property "User Part Number" "PARTNUM*"
			(at 0.02032 4.024884 0)
			(unlocked yes)
			(layer "Cmts.User")
			(hide yes)
			(effects
				(font
					(size 0.7874 0.5842)
					(thickness 0.1524)
				)
			)
		)
		(property "Device Type" "RESISTOR-G155-14701-01,4.7KOHMA"
			(at 0.008382 1.210564 0)
			(unlocked yes)
			(layer "F.Fab")
			(hide yes)
			(effects
				(font
					(size 0.7874 0.5842)
					(thickness 0.1524)
				)
			)
		)
		(duplicate_pad_numbers_are_jumpers no)
		(fp_line
			(start -1.143 -0.5588)
			(end -1.143 0.5588)
			(stroke
				(width 0.1)
				(type default)
			)
			(layer "F.SilkS")
		)
		(fp_line
			(start -1.143 0.5588)
			(end 1.143 0.5588)
			(stroke
				(width 0.1)
				(type default)
			)
			(layer "F.SilkS")
		)
		(fp_line
			(start 1.143 -0.5588)
			(end -1.143 -0.5588)
			(stroke
				(width 0.1)
				(type default)
			)
			(layer "F.SilkS")
		)
		(fp_line
			(start 1.143 0.5588)
			(end 1.143 -0.5588)
			(stroke
				(width 0.1)
				(type default)
			)
			(layer "F.SilkS")
		)
		(fp_rect
			(start -1.143 -0.5588)
			(end 1.143 0.5588)
			(stroke
				(width 0)
				(type default)
			)
			(fill no)
			(layer "F.CrtYd")
		)
		(fp_line
			(start -0.508 -0.3048)
			(end -0.508 0.3048)
			(stroke
				(width 0.1)
				(type default)
			)
			(layer "F.Fab")
		)
		(fp_line
			(start -0.508 0.3048)
			(end 0.508 0.3048)
			(stroke
				(width 0.1)
				(type default)
			)
			(layer "F.Fab")
		)
		(fp_line
			(start 0.508 -0.3048)
			(end -0.508 -0.3048)
			(stroke
				(width 0.1)
				(type default)
			)
			(layer "F.Fab")
		)
		(fp_line
			(start 0.508 0.3048)
			(end 0.508 -0.3048)
			(stroke
				(width 0.1)
				(type default)
			)
			(layer "F.Fab")
		)
		(pad "1" smd rect
			(at -0.5334 0)
			(size 0.7112 0.6096)
			(layers "F.Cu" "F.Mask" "F.Paste")
			(net "XP3R3V_FPGA")
		)
		(pad "2" smd rect
			(at 0.5334 0)
			(size 0.7112 0.6096)
			(layers "F.Cu" "F.Mask" "F.Paste")
			(net "BNO080_SA0")
		)
		(zone
			(layer "F.Cu")
			(hatch none 0.5)
			(connect_pads
				(clearance 0)
			)
			(min_thickness 0.25)
			(keepout
				(tracks allowed)
				(vias not_allowed)
				(pads allowed)
				(copperpour not_allowed)
				(footprints allowed)
			)
			(placement
				(enabled no)
				(sheetname "")
			)
			(fill
				(thermal_gap 0.5)
				(thermal_bridge_width 0.5)
				(island_removal_mode 0)
			)
			(polygon
				(pts
					(xy 83.1088 -55.2958) (xy 83.1088 -54.6862) (xy 83.2612 -54.6862) (xy 83.2612 -55.2958)
				)
			)
		)
	)
	(footprint ""
		(layer "F.Cu")
		(at 46.736 -81.026)
		(property "Reference" "C298"
			(at 3.81 0.16637 0)
			(unlocked yes)
			(layer "F.SilkS")
			(effects
				(font
					(size 0.7874 0.5842)
					(thickness 0.1524)
				)
			)
		)
		(property "Value" "VAL*"
			(at 0.0762 2.067306 0)
			(unlocked yes)
			(layer "F.Fab")
			(hide yes)
			(effects
				(font
					(size 0.7874 0.5842)
					(thickness 0.1524)
				)
			)
		)
		(property "Tolerance" "TOL*"
			(at 0.0762 3.032506 0)
			(unlocked yes)
			(layer "Cmts.User")
			(hide yes)
			(effects
				(font
					(size 0.7874 0.5842)
					(thickness 0.1524)
				)
			)
		)
		(property "User Part Number" "PARTNUM*"
			(at 0.1016 4.023106 0)
			(unlocked yes)
			(layer "Cmts.User")
			(hide yes)
			(effects
				(font
					(size 0.7874 0.5842)
					(thickness 0.1524)
				)
			)
		)
		(property "Device Type" "CAPACITOR-G105-0B104-EK,0.1UF,A"
			(at 0.0508 1.127506 0)
			(unlocked yes)
			(layer "F.Fab")
			(hide yes)
			(effects
				(font
					(size 0.7874 0.5842)
					(thickness 0.1524)
				)
			)
		)
		(duplicate_pad_numbers_are_jumpers no)
		(fp_line
			(start -1.143 -0.5588)
			(end -1.143 0.5588)
			(stroke
				(width 0.1)
				(type default)
			)
			(layer "F.SilkS")
		)
		(fp_line
			(start -1.143 0.5588)
			(end 1.143 0.5588)
			(stroke
				(width 0.1)
				(type default)
			)
			(layer "F.SilkS")
		)
		(fp_line
			(start 1.143 -0.5588)
			(end -1.143 -0.5588)
			(stroke
				(width 0.1)
				(type default)
			)
			(layer "F.SilkS")
		)
		(fp_line
			(start 1.143 0.5588)
			(end 1.143 -0.5588)
			(stroke
				(width 0.1)
				(type default)
			)
			(layer "F.SilkS")
		)
		(fp_poly
			(pts
				(xy -1.143 0.5588) (xy 1.143 0.5588) (xy 1.143 -0.5588) (xy -1.143 -0.5588)
			)
			(stroke
				(width 0)
				(type default)
			)
			(fill no)
			(layer "F.CrtYd")
		)
		(fp_line
			(start -0.508 -0.3048)
			(end -0.508 0.3048)
			(stroke
				(width 0.1)
				(type default)
			)
			(layer "F.Fab")
		)
		(fp_line
			(start -0.508 0.3048)
			(end 0.508 0.3048)
			(stroke
				(width 0.1)
				(type default)
			)
			(layer "F.Fab")
		)
		(fp_line
			(start 0.508 -0.3048)
			(end -0.508 -0.3048)
			(stroke
				(width 0.1)
				(type default)
			)
			(layer "F.Fab")
		)
		(fp_line
			(start 0.508 0.3048)
			(end 0.508 -0.3048)
			(stroke
				(width 0.1)
				(type default)
			)
			(layer "F.Fab")
		)
		(pad "1" smd rect
			(at -0.5334 0)
			(size 0.7112 0.6096)
			(layers "F.Cu" "F.Mask" "F.Paste")
			(net "UNNAMED_525_CAPACITOR_I7_1")
		)
		(pad "2" smd rect
			(at 0.5334 0)
			(size 0.7112 0.6096)
			(layers "F.Cu" "F.Mask" "F.Paste")
			(net "SG")
		)
		(zone
			(layer "F.Cu")
			(hatch none 0.5)
			(connect_pads
				(clearance 0)
			)
			(min_thickness 0.25)
			(keepout
				(tracks allowed)
				(vias not_allowed)
				(pads allowed)
				(copperpour not_allowed)
				(footprints allowed)
			)
			(placement
				(enabled no)
				(sheetname "")
			)
			(fill
				(thermal_gap 0.5)
				(thermal_bridge_width 0.5)
				(island_removal_mode 0)
			)
			(polygon
				(pts
					(xy 46.6598 -80.7212) (xy 46.8122 -80.7212) (xy 46.8122 -81.3308) (xy 46.6598 -81.3308)
				)
			)
		)
		(zone
			(layer "F.Cu")
			(hatch none 0.5)
			(connect_pads
				(clearance 0)
			)
			(min_thickness 0.25)
			(keepout
				(tracks not_allowed)
				(vias allowed)
				(pads allowed)
				(copperpour not_allowed)
				(footprints allowed)
			)
			(placement
				(enabled no)
				(sheetname "")
			)
			(fill
				(thermal_gap 0.5)
				(thermal_bridge_width 0.5)
				(island_removal_mode 0)
			)
			(polygon
				(pts
					(xy 46.6598 -80.7212) (xy 46.8122 -80.7212) (xy 46.8122 -81.3308) (xy 46.6598 -81.3308)
				)
			)
		)
	)
	(footprint ""
		(layer "F.Cu")
		(at 111.125 -101.981)
		(property "Reference" "R323"
			(at 3.175 -3.13563 0)
			(unlocked yes)
			(layer "F.SilkS")
			(effects
				(font
					(size 0.7874 0.5842)
					(thickness 0.1524)
				)
			)
		)
		(property "Value" "VAL*"
			(at 0.02032 2.13233 0)
			(unlocked yes)
			(layer "F.Fab")
			(hide yes)
			(effects
				(font
					(size 0.7874 0.5842)
					(thickness 0.1524)
				)
			)
		)
		(property "Tolerance" "TOL*"
			(at 0.044704 3.05435 0)
			(unlocked yes)
			(layer "Cmts.User")
			(hide yes)
			(effects
				(font
					(size 0.7874 0.5842)
					(thickness 0.1524)
				)
			)
		)
		(property "User Part Number" "PARTNUM*"
			(at 0.02032 4.024884 0)
			(unlocked yes)
			(layer "Cmts.User")
			(hide yes)
			(effects
				(font
					(size 0.7874 0.5842)
					(thickness 0.1524)
				)
			)
		)
		(property "Device Type" "RESISTOR-G155-14701-01,4.7KOHMA"
			(at 0.008382 1.210564 0)
			(unlocked yes)
			(layer "F.Fab")
			(hide yes)
			(effects
				(font
					(size 0.7874 0.5842)
					(thickness 0.1524)
				)
			)
		)
		(duplicate_pad_numbers_are_jumpers no)
		(fp_line
			(start -1.143 -0.5588)
			(end -1.143 0.5588)
			(stroke
				(width 0.1)
				(type default)
			)
			(layer "F.SilkS")
		)
		(fp_line
			(start -1.143 0.5588)
			(end 1.143 0.5588)
			(stroke
				(width 0.1)
				(type default)
			)
			(layer "F.SilkS")
		)
		(fp_line
			(start 1.143 -0.5588)
			(end -1.143 -0.5588)
			(stroke
				(width 0.1)
				(type default)
			)
			(layer "F.SilkS")
		)
		(fp_line
			(start 1.143 0.5588)
			(end 1.143 -0.5588)
			(stroke
				(width 0.1)
				(type default)
			)
			(layer "F.SilkS")
		)
		(fp_poly
			(pts
				(xy -1.143 0.5588) (xy 1.143 0.5588) (xy 1.143 -0.5588) (xy -1.143 -0.5588)
			)
			(stroke
				(width 0)
				(type default)
			)
			(fill no)
			(layer "F.CrtYd")
		)
		(fp_line
			(start -0.508 -0.3048)
			(end -0.508 0.3048)
			(stroke
				(width 0.1)
				(type default)
			)
			(layer "F.Fab")
		)
		(fp_line
			(start -0.508 0.3048)
			(end 0.508 0.3048)
			(stroke
				(width 0.1)
				(type default)
			)
			(layer "F.Fab")
		)
		(fp_line
			(start 0.508 -0.3048)
			(end -0.508 -0.3048)
			(stroke
				(width 0.1)
				(type default)
			)
			(layer "F.Fab")
		)
		(fp_line
			(start 0.508 0.3048)
			(end 0.508 -0.3048)
			(stroke
				(width 0.1)
				(type default)
			)
			(layer "F.Fab")
		)
		(pad "1" smd rect
			(at -0.5334 0)
			(size 0.7112 0.6096)
			(layers "F.Cu" "F.Mask" "F.Paste")
			(net "UNNAMED_14_IS32FL3207QWLA3TRQ_1")
		)
		(pad "2" smd rect
			(at 0.5334 0)
			(size 0.7112 0.6096)
			(layers "F.Cu" "F.Mask" "F.Paste")
			(net "SG")
		)
		(zone
			(layer "F.Cu")
			(hatch none 0.5)
			(connect_pads
				(clearance 0)
			)
			(min_thickness 0.25)
			(keepout
				(tracks allowed)
				(vias not_allowed)
				(pads allowed)
				(copperpour not_allowed)
				(footprints allowed)
			)
			(placement
				(enabled no)
				(sheetname "")
			)
			(fill
				(thermal_gap 0.5)
				(thermal_bridge_width 0.5)
				(island_removal_mode 0)
			)
			(polygon
				(pts
					(xy 111.0488 -101.6762) (xy 111.2012 -101.6762) (xy 111.2012 -102.2858) (xy 111.0488 -102.2858)
				)
			)
		)
		(zone
			(layer "F.Cu")
			(hatch none 0.5)
			(connect_pads
				(clearance 0)
			)
			(min_thickness 0.25)
			(keepout
				(tracks not_allowed)
				(vias allowed)
				(pads allowed)
				(copperpour not_allowed)
				(footprints allowed)
			)
			(placement
				(enabled no)
				(sheetname "")
			)
			(fill
				(thermal_gap 0.5)
				(thermal_bridge_width 0.5)
				(island_removal_mode 0)
			)
			(polygon
				(pts
					(xy 111.0488 -101.6762) (xy 111.2012 -101.6762) (xy 111.2012 -102.2858) (xy 111.0488 -102.2858)
				)
			)
		)
	)
	(footprint ""
		(layer "F.Cu")
		(at 142.6464 -90.6526)
		(property "Reference" "C2"
			(at -0.6604 1.15697 0)
			(unlocked yes)
			(layer "F.SilkS")
			(effects
				(font
					(size 0.7874 0.5842)
					(thickness 0.1524)
				)
			)
		)
		(property "Value" "VAL*"
			(at 0.0762 2.067306 0)
			(unlocked yes)
			(layer "F.Fab")
			(hide yes)
			(effects
				(font
					(size 0.7874 0.5842)
					(thickness 0.1524)
				)
			)
		)
		(property "Device Type" "CAPACITOR-G105-0B104-EK,0.1UF,A"
			(at 0.0508 1.127506 0)
			(unlocked yes)
			(layer "F.Fab")
			(hide yes)
			(effects
				(font
					(size 0.7874 0.5842)
					(thickness 0.1524)
				)
			)
		)
		(property "User Part Number" "PARTNUM*"
			(at 0.1016 4.023106 0)
			(unlocked yes)
			(layer "Cmts.User")
			(hide yes)
			(effects
				(font
					(size 0.7874 0.5842)
					(thickness 0.1524)
				)
			)
		)
		(property "Tolerance" "TOL*"
			(at 0.0762 3.032506 0)
			(unlocked yes)
			(layer "Cmts.User")
			(hide yes)
			(effects
				(font
					(size 0.7874 0.5842)
					(thickness 0.1524)
				)
			)
		)
		(duplicate_pad_numbers_are_jumpers no)
		(fp_line
			(start -1.143 -0.5588)
			(end -1.143 0.5588)
			(stroke
				(width 0.1)
				(type default)
			)
			(layer "F.SilkS")
		)
		(fp_line
			(start -1.143 0.5588)
			(end 1.143 0.5588)
			(stroke
				(width 0.1)
				(type default)
			)
			(layer "F.SilkS")
		)
		(fp_line
			(start 1.143 -0.5588)
			(end -1.143 -0.5588)
			(stroke
				(width 0.1)
				(type default)
			)
			(layer "F.SilkS")
		)
		(fp_line
			(start 1.143 0.5588)
			(end 1.143 -0.5588)
			(stroke
				(width 0.1)
				(type default)
			)
			(layer "F.SilkS")
		)
		(fp_rect
			(start -1.143 0.5588)
			(end 1.143 -0.5588)
			(stroke
				(width 0)
				(type default)
			)
			(fill no)
			(layer "F.CrtYd")
		)
		(fp_line
			(start -0.508 -0.3048)
			(end -0.508 0.3048)
			(stroke
				(width 0.1)
				(type default)
			)
			(layer "F.Fab")
		)
		(fp_line
			(start -0.508 0.3048)
			(end 0.508 0.3048)
			(stroke
				(width 0.1)
				(type default)
			)
			(layer "F.Fab")
		)
		(fp_line
			(start 0.508 -0.3048)
			(end -0.508 -0.3048)
			(stroke
				(width 0.1)
				(type default)
			)
			(layer "F.Fab")
		)
		(fp_line
			(start 0.508 0.3048)
			(end 0.508 -0.3048)
			(stroke
				(width 0.1)
				(type default)
			)
			(layer "F.Fab")
		)
		(pad "1" smd rect
			(at -0.5334 0)
			(size 0.7112 0.6096)
			(layers "F.Cu" "F.Mask" "F.Paste")
			(net "XP12R0V_IN")
		)
		(pad "2" smd rect
			(at 0.5334 0)
			(size 0.7112 0.6096)
			(layers "F.Cu" "F.Mask" "F.Paste")
			(net "SG")
		)
		(zone
			(layer "F.Cu")
			(hatch none 0.5)
			(connect_pads
				(clearance 0)
			)
			(min_thickness 0.25)
			(keepout
				(tracks allowed)
				(vias not_allowed)
				(pads allowed)
				(copperpour not_allowed)
				(footprints allowed)
			)
			(placement
				(enabled no)
				(sheetname "")
			)
			(fill
				(thermal_gap 0.5)
				(thermal_bridge_width 0.5)
				(island_removal_mode 0)
			)
			(polygon
				(pts
					(xy 142.5702 -90.3478) (xy 142.7226 -90.3478) (xy 142.7226 -90.9574) (xy 142.5702 -90.9574)
				)
			)
		)
	)
	(footprint ""
		(layer "F.Cu")
		(at 102.997 -26.67 90)
		(property "Reference" "C253"
			(at 0.508 -2.24663 90)
			(unlocked yes)
			(layer "F.SilkS")
			(effects
				(font
					(size 0.7874 0.5842)
					(thickness 0.1524)
				)
			)
		)
		(property "Value" "VAL*"
			(at 0.0762 2.067306 90)
			(unlocked yes)
			(layer "F.Fab")
			(hide yes)
			(effects
				(font
					(size 0.7874 0.5842)
					(thickness 0.1524)
				)
			)
		)
		(property "Tolerance" "TOL*"
			(at 0.0762 3.032506 90)
			(unlocked yes)
			(layer "Cmts.User")
			(hide yes)
			(effects
				(font
					(size 0.7874 0.5842)
					(thickness 0.1524)
				)
			)
		)
		(property "User Part Number" "PARTNUM*"
			(at 0.1016 4.023106 90)
			(unlocked yes)
			(layer "Cmts.User")
			(hide yes)
			(effects
				(font
					(size 0.7874 0.5842)
					(thickness 0.1524)
				)
			)
		)
		(property "Device Type" "CAPACITOR-G105-0B104-CK,0.1UF,A"
			(at 0.0508 1.127506 90)
			(unlocked yes)
			(layer "F.Fab")
			(hide yes)
			(effects
				(font
					(size 0.7874 0.5842)
					(thickness 0.1524)
				)
			)
		)
		(duplicate_pad_numbers_are_jumpers no)
		(fp_line
			(start 1.143 -0.5588)
			(end -1.143 -0.5588)
			(stroke
				(width 0.1)
				(type default)
			)
			(layer "F.SilkS")
		)
		(fp_line
			(start -1.143 -0.5588)
			(end -1.143 0.5588)
			(stroke
				(width 0.1)
				(type default)
			)
			(layer "F.SilkS")
		)
		(fp_line
			(start 1.143 0.5588)
			(end 1.143 -0.5588)
			(stroke
				(width 0.1)
				(type default)
			)
			(layer "F.SilkS")
		)
		(fp_line
			(start -1.143 0.5588)
			(end 1.143 0.5588)
			(stroke
				(width 0.1)
				(type default)
			)
			(layer "F.SilkS")
		)
		(fp_rect
			(start -1.143 -0.5588)
			(end 1.143 0.5588)
			(stroke
				(width 0)
				(type default)
			)
			(fill no)
			(layer "F.CrtYd")
		)
		(fp_line
			(start 0.508 -0.3048)
			(end -0.508 -0.3048)
			(stroke
				(width 0.1)
				(type default)
			)
			(layer "F.Fab")
		)
		(fp_line
			(start -0.508 -0.3048)
			(end -0.508 0.3048)
			(stroke
				(width 0.1)
				(type default)
			)
			(layer "F.Fab")
		)
		(fp_line
			(start 0.508 0.3048)
			(end 0.508 -0.3048)
			(stroke
				(width 0.1)
				(type default)
			)
			(layer "F.Fab")
		)
		(fp_line
			(start -0.508 0.3048)
			(end 0.508 0.3048)
			(stroke
				(width 0.1)
				(type default)
			)
			(layer "F.Fab")
		)
		(pad "1" smd rect
			(at -0.5334 0 90)
			(size 0.7112 0.6096)
			(layers "F.Cu" "F.Mask" "F.Paste")
			(net "OSC_125M_CLKP")
		)
		(pad "2" smd rect
			(at 0.5334 0 90)
			(size 0.7112 0.6096)
			(layers "F.Cu" "F.Mask" "F.Paste")
			(net "MHZ125CLKP_CLKIN")
		)
		(zone
			(layer "F.Cu")
			(hatch none 0.5)
			(connect_pads
				(clearance 0)
			)
			(min_thickness 0.25)
			(keepout
				(tracks allowed)
				(vias not_allowed)
				(pads allowed)
				(copperpour not_allowed)
				(footprints allowed)
			)
			(placement
				(enabled no)
				(sheetname "")
			)
			(fill
				(thermal_gap 0.5)
				(thermal_bridge_width 0.5)
				(island_removal_mode 0)
			)
			(polygon
				(pts
					(xy 102.6922 -26.5938) (xy 103.3018 -26.5938) (xy 103.3018 -26.7462) (xy 102.6922 -26.7462)
				)
			)
		)
	)
	(footprint ""
		(layer "F.Cu")
		(at 12.827 -28.06446 90)
		(property "Reference" "R377"
			(at -0.50546 -2.37363 90)
			(unlocked yes)
			(layer "F.SilkS")
			(effects
				(font
					(size 0.7874 0.5842)
					(thickness 0.1524)
				)
			)
		)
		(property "Value" "VAL*"
			(at 0.02032 2.13233 90)
			(unlocked yes)
			(layer "F.Fab")
			(hide yes)
			(effects
				(font
					(size 0.7874 0.5842)
					(thickness 0.1524)
				)
			)
		)
		(property "Tolerance" "TOL*"
			(at 0.044704 3.05435 90)
			(unlocked yes)
			(layer "Cmts.User")
			(hide yes)
			(effects
				(font
					(size 0.7874 0.5842)
					(thickness 0.1524)
				)
			)
		)
		(property "User Part Number" "PARTNUM*"
			(at 0.02032 4.024884 90)
			(unlocked yes)
			(layer "Cmts.User")
			(hide yes)
			(effects
				(font
					(size 0.7874 0.5842)
					(thickness 0.1524)
				)
			)
		)
		(property "Device Type" "RESISTOR-G155-14701-01,4.7KOHMA"
			(at 0.008382 1.210564 90)
			(unlocked yes)
			(layer "F.Fab")
			(hide yes)
			(effects
				(font
					(size 0.7874 0.5842)
					(thickness 0.1524)
				)
			)
		)
		(duplicate_pad_numbers_are_jumpers no)
		(fp_line
			(start 1.143 -0.5588)
			(end -1.143 -0.5588)
			(stroke
				(width 0.1)
				(type default)
			)
			(layer "F.SilkS")
		)
		(fp_line
			(start -1.143 -0.5588)
			(end -1.143 0.5588)
			(stroke
				(width 0.1)
				(type default)
			)
			(layer "F.SilkS")
		)
		(fp_line
			(start 1.143 0.5588)
			(end 1.143 -0.5588)
			(stroke
				(width 0.1)
				(type default)
			)
			(layer "F.SilkS")
		)
		(fp_line
			(start -1.143 0.5588)
			(end 1.143 0.5588)
			(stroke
				(width 0.1)
				(type default)
			)
			(layer "F.SilkS")
		)
		(fp_rect
			(start 1.143 0.5588)
			(end -1.143 -0.5588)
			(stroke
				(width 0)
				(type default)
			)
			(fill no)
			(layer "F.CrtYd")
		)
		(fp_line
			(start 0.508 -0.3048)
			(end -0.508 -0.3048)
			(stroke
				(width 0.1)
				(type default)
			)
			(layer "F.Fab")
		)
		(fp_line
			(start -0.508 -0.3048)
			(end -0.508 0.3048)
			(stroke
				(width 0.1)
				(type default)
			)
			(layer "F.Fab")
		)
		(fp_line
			(start 0.508 0.3048)
			(end 0.508 -0.3048)
			(stroke
				(width 0.1)
				(type default)
			)
			(layer "F.Fab")
		)
		(fp_line
			(start -0.508 0.3048)
			(end 0.508 0.3048)
			(stroke
				(width 0.1)
				(type default)
			)
			(layer "F.Fab")
		)
		(pad "1" smd rect
			(at -0.5334 0 90)
			(size 0.7112 0.6096)
			(layers "F.Cu" "F.Mask" "F.Paste")
			(net "XP3R3V_FPGA")
		)
		(pad "2" smd rect
			(at 0.5334 0 90)
			(size 0.7112 0.6096)
			(layers "F.Cu" "F.Mask" "F.Paste")
			(net "SMA3_SIG_IN_BF_EN_N")
		)
		(zone
			(layer "F.Cu")
			(hatch none 0.5)
			(connect_pads
				(clearance 0)
			)
			(min_thickness 0.25)
			(keepout
				(tracks not_allowed)
				(vias allowed)
				(pads allowed)
				(copperpour not_allowed)
				(footprints allowed)
			)
			(placement
				(enabled no)
				(sheetname "")
			)
			(fill
				(thermal_gap 0.5)
				(thermal_bridge_width 0.5)
				(island_removal_mode 0)
			)
			(polygon
				(pts
					(xy 13.1318 -28.14066) (xy 12.5222 -28.14066) (xy 12.5222 -27.98826) (xy 13.1318 -27.98826)
				)
			)
		)
		(zone
			(layer "F.Cu")
			(hatch none 0.5)
			(connect_pads
				(clearance 0)
			)
			(min_thickness 0.25)
			(keepout
				(tracks allowed)
				(vias not_allowed)
				(pads allowed)
				(copperpour not_allowed)
				(footprints allowed)
			)
			(placement
				(enabled no)
				(sheetname "")
			)
			(fill
				(thermal_gap 0.5)
				(thermal_bridge_width 0.5)
				(island_removal_mode 0)
			)
			(polygon
				(pts
					(xy 13.1318 -28.14066) (xy 12.5222 -28.14066) (xy 12.5222 -27.98826) (xy 13.1318 -27.98826)
				)
			)
		)
	)
	(footprint ""
		(layer "F.Cu")
		(at 36.957 -80.391 -90)
		(property "Reference" "L24"
			(at -1.5875 -0.03937 90)
			(unlocked yes)
			(layer "F.SilkS")
			(effects
				(font
					(size 0.7874 0.5842)
					(thickness 0.1524)
				)
				(justify left)
			)
		)
		(property "Value" "VAL*"
			(at -0.9398 3.70967 270)
			(unlocked yes)
			(layer "F.Fab")
			(hide yes)
			(effects
				(font
					(size 0.7874 0.5842)
					(thickness 0.1524)
				)
				(justify left)
			)
		)
		(property "Tolerance" "TOL*"
			(at -0.9906 5.00507 270)
			(unlocked yes)
			(layer "Cmts.User")
			(hide yes)
			(effects
				(font
					(size 0.7874 0.5842)
					(thickness 0.1524)
				)
				(justify left)
			)
		)
		(property "User Part Number" "PARTNUM*"
			(at -2.54 2.46507 270)
			(unlocked yes)
			(layer "Cmts.User")
			(hide yes)
			(effects
				(font
					(size 0.7874 0.5842)
					(thickness 0.1524)
				)
				(justify left)
			)
		)
		(property "Device Type" "FERRITEBEAD-G191-10100-01,120OA"
			(at -0.9906 1.22047 270)
			(unlocked yes)
			(layer "F.Fab")
			(hide yes)
			(effects
				(font
					(size 0.7874 0.5842)
					(thickness 0.1524)
				)
				(justify left)
			)
		)
		(duplicate_pad_numbers_are_jumpers no)
		(fp_line
			(start -1.3208 0.7112)
			(end -1.3208 -0.7112)
			(stroke
				(width 0.1)
				(type default)
			)
			(layer "F.SilkS")
		)
		(fp_line
			(start 1.3208 0.7112)
			(end -1.3208 0.7112)
			(stroke
				(width 0.1)
				(type default)
			)
			(layer "F.SilkS")
		)
		(fp_line
			(start -1.3208 -0.7112)
			(end 1.3208 -0.7112)
			(stroke
				(width 0.1)
				(type default)
			)
			(layer "F.SilkS")
		)
		(fp_line
			(start 1.3208 -0.7112)
			(end 1.3208 0.7112)
			(stroke
				(width 0.1)
				(type default)
			)
			(layer "F.SilkS")
		)
		(fp_rect
			(start -1.3208 0.7112)
			(end 1.3208 -0.7112)
			(stroke
				(width 0)
				(type default)
			)
			(fill no)
			(layer "F.CrtYd")
		)
		(fp_line
			(start -0.8128 0.4572)
			(end -0.8128 -0.4572)
			(stroke
				(width 0.1)
				(type default)
			)
			(layer "F.Fab")
		)
		(fp_line
			(start 0.8128 0.4572)
			(end -0.8128 0.4572)
			(stroke
				(width 0.1)
				(type default)
			)
			(layer "F.Fab")
		)
		(fp_line
			(start -0.8128 -0.4572)
			(end 0.8128 -0.4572)
			(stroke
				(width 0.1)
				(type default)
			)
			(layer "F.Fab")
		)
		(fp_line
			(start 0.8128 -0.4572)
			(end 0.8128 0.4572)
			(stroke
				(width 0.1)
				(type default)
			)
			(layer "F.Fab")
		)
		(pad "1" smd rect
			(at -0.6858 0 270)
			(size 0.762 0.8636)
			(layers "F.Cu" "F.Mask" "F.Paste")
			(net "XP3R3V_FPGA")
		)
		(pad "2" smd rect
			(at 0.6858 0 270)
			(size 0.762 0.8636)
			(layers "F.Cu" "F.Mask" "F.Paste")
			(net "XP3R3V_FT4232")
		)
		(zone
			(layer "F.Cu")
			(hatch none 0.5)
			(connect_pads
				(clearance 0)
			)
			(min_thickness 0.25)
			(keepout
				(tracks not_allowed)
				(vias allowed)
				(pads allowed)
				(copperpour not_allowed)
				(footprints allowed)
			)
			(placement
				(enabled no)
				(sheetname "")
			)
			(fill
				(thermal_gap 0.5)
				(thermal_bridge_width 0.5)
				(island_removal_mode 0)
			)
			(polygon
				(pts
					(xy 36.4998 -80.5434) (xy 36.4998 -80.2386) (xy 37.4142 -80.2386) (xy 37.4142 -80.5434)
				)
			)
		)
		(zone
			(layer "F.Cu")
			(hatch none 0.5)
			(connect_pads
				(clearance 0)
			)
			(min_thickness 0.25)
			(keepout
				(tracks allowed)
				(vias not_allowed)
				(pads allowed)
				(copperpour not_allowed)
				(footprints allowed)
			)
			(placement
				(enabled no)
				(sheetname "")
			)
			(fill
				(thermal_gap 0.5)
				(thermal_bridge_width 0.5)
				(island_removal_mode 0)
			)
			(polygon
				(pts
					(xy 36.4998 -80.5434) (xy 36.4998 -80.2386) (xy 37.4142 -80.2386) (xy 37.4142 -80.5434)
				)
			)
		)
	)
	(footprint ""
		(layer "F.Cu")
		(at 37.1094 -102.3874 180)
		(property "Reference" "C43"
			(at 4.2164 1.71323 0)
			(unlocked yes)
			(layer "F.SilkS")
			(effects
				(font
					(size 0.7874 0.5842)
					(thickness 0.1524)
				)
			)
		)
		(property "Value" "VAL*"
			(at 0.193548 2.13614 180)
			(unlocked yes)
			(layer "F.Fab")
			(hide yes)
			(effects
				(font
					(size 0.7874 0.5842)
					(thickness 0.1524)
				)
			)
		)
		(property "Tolerance" "TOL*"
			(at 0.216154 3.1496 180)
			(unlocked yes)
			(layer "Cmts.User")
			(hide yes)
			(effects
				(font
					(size 0.7874 0.5842)
					(thickness 0.1524)
				)
			)
		)
		(property "Device Type" "CAPACITOR-G104-0A180-FJ,18PF,5%"
			(at 0.184404 1.180592 180)
			(unlocked yes)
			(layer "F.Fab")
			(hide yes)
			(effects
				(font
					(size 0.7874 0.5842)
					(thickness 0.1524)
				)
			)
		)
		(property "User Part Number" "PARTNUM*"
			(at 0.216154 4.185666 180)
			(unlocked yes)
			(layer "Cmts.User")
			(hide yes)
			(effects
				(font
					(size 0.7874 0.5842)
					(thickness 0.1524)
				)
			)
		)
		(duplicate_pad_numbers_are_jumpers no)
		(fp_line
			(start 0.671322 0.4445)
			(end -0.671322 0.4445)
			(stroke
				(width 0.1)
				(type default)
			)
			(layer "F.SilkS")
		)
		(fp_line
			(start 0.671322 -0.4445)
			(end 0.671322 0.4445)
			(stroke
				(width 0.1)
				(type default)
			)
			(layer "F.SilkS")
		)
		(fp_line
			(start -0.671322 0.4445)
			(end -0.671322 -0.4445)
			(stroke
				(width 0.1)
				(type default)
			)
			(layer "F.SilkS")
		)
		(fp_line
			(start -0.671322 -0.4445)
			(end 0.671322 -0.4445)
			(stroke
				(width 0.1)
				(type default)
			)
			(layer "F.SilkS")
		)
		(fp_rect
			(start -0.671322 0.4445)
			(end 0.671322 -0.4445)
			(stroke
				(width 0)
				(type default)
			)
			(fill no)
			(layer "F.CrtYd")
		)
		(fp_line
			(start 0.31496 0.1651)
			(end 0.31496 -0.1651)
			(stroke
				(width 0.1)
				(type default)
			)
			(layer "F.Fab")
		)
		(fp_line
			(start 0.31496 -0.1651)
			(end -0.31496 -0.1651)
			(stroke
				(width 0.1)
				(type default)
			)
			(layer "F.Fab")
		)
		(fp_line
			(start -0.31496 0.1651)
			(end 0.31496 0.1651)
			(stroke
				(width 0.1)
				(type default)
			)
			(layer "F.Fab")
		)
		(fp_line
			(start -0.31496 -0.1651)
			(end -0.31496 0.1651)
			(stroke
				(width 0.1)
				(type default)
			)
			(layer "F.Fab")
		)
		(pad "1" smd rect
			(at -0.264922 0 180)
			(size 0.3048 0.381)
			(layers "F.Cu" "F.Mask" "F.Paste")
			(net "XP5R0V_COMP")
		)
		(pad "2" smd rect
			(at 0.264922 0 180)
			(size 0.3048 0.381)
			(layers "F.Cu" "F.Mask" "F.Paste")
			(net "XP5R0V_AGND")
		)
		(zone
			(layer "F.Cu")
			(hatch none 0.5)
			(connect_pads
				(clearance 0)
			)
			(min_thickness 0.25)
			(keepout
				(tracks allowed)
				(vias not_allowed)
				(pads allowed)
				(copperpour not_allowed)
				(footprints allowed)
			)
			(placement
				(enabled no)
				(sheetname "")
			)
			(fill
				(thermal_gap 0.5)
				(thermal_bridge_width 0.5)
				(island_removal_mode 0)
			)
			(polygon
				(pts
					(xy 37.221922 -102.5779) (xy 36.996878 -102.5779) (xy 36.996878 -102.1969) (xy 37.221922 -102.1969)
				)
			)
		)
	)
	(footprint ""
		(layer "F.Cu")
		(at 72.35444 -46.746668 -90)
		(property "Reference" "P1"
			(at 0.558038 -4.60756 0)
			(unlocked yes)
			(layer "F.SilkS")
			(effects
				(font
					(size 0.7874 0.5842)
					(thickness 0.1524)
				)
			)
		)
		(property "Value" ""
			(at 0 0 270)
			(layer "F.Fab")
			(effects
				(font
					(size 1.27 1.27)
				)
			)
		)
		(property "User Part Number" "PARTNUM*"
			(at 0.051054 6.007608 270)
			(unlocked yes)
			(layer "Cmts.User")
			(hide yes)
			(effects
				(font
					(size 0.7874 0.5842)
					(thickness 0.1524)
				)
			)
		)
		(property "Device Type" "CONN_HDR_2X10_M_S_SMT-G200-130A"
			(at 0.051054 4.813808 270)
			(unlocked yes)
			(layer "F.Fab")
			(hide yes)
			(effects
				(font
					(size 0.7874 0.5842)
					(thickness 0.1524)
				)
			)
		)
		(duplicate_pad_numbers_are_jumpers no)
		(fp_line
			(start -4.01828 3.155696)
			(end 4.754118 3.155696)
			(stroke
				(width 0.1)
				(type default)
			)
			(layer "F.SilkS")
		)
		(fp_line
			(start 4.754118 3.155696)
			(end 4.754118 -3.155696)
			(stroke
				(width 0.1)
				(type default)
			)
			(layer "F.SilkS")
		)
		(fp_line
			(start -4.754118 2.419858)
			(end -4.01828 3.155696)
			(stroke
				(width 0.1)
				(type default)
			)
			(layer "F.SilkS")
		)
		(fp_line
			(start -4.754118 -3.155696)
			(end -4.754118 2.419858)
			(stroke
				(width 0.1)
				(type default)
			)
			(layer "F.SilkS")
		)
		(fp_line
			(start 4.754118 -3.155696)
			(end -4.754118 -3.155696)
			(stroke
				(width 0.1)
				(type default)
			)
			(layer "F.SilkS")
		)
		(fp_poly
			(pts
				(xy -5.008118 2.525014) (xy -5.008118 -3.409696) (xy 5.008118 -3.409696) (xy 5.008118 3.409696)
				(xy -4.123436 3.409696)
			)
			(stroke
				(width 0)
				(type default)
			)
			(fill no)
			(layer "F.CrtYd")
		)
		(fp_line
			(start -4.01447 2.800096)
			(end -4.500118 2.314702)
			(stroke
				(width 0.1)
				(type default)
			)
			(layer "F.Fab")
		)
		(fp_line
			(start 4.500118 2.800096)
			(end -4.01447 2.800096)
			(stroke
				(width 0.1)
				(type default)
			)
			(layer "F.Fab")
		)
		(fp_line
			(start -4.500118 2.314702)
			(end -4.500118 -2.800096)
			(stroke
				(width 0.1)
				(type default)
			)
			(layer "F.Fab")
		)
		(fp_line
			(start -4.500118 -2.800096)
			(end 4.500118 -2.800096)
			(stroke
				(width 0.1)
				(type default)
			)
			(layer "F.Fab")
		)
		(fp_line
			(start 4.500118 -2.800096)
			(end 4.500118 2.800096)
			(stroke
				(width 0.1)
				(type default)
			)
			(layer "F.Fab")
		)
		(fp_text user "1"
			(at -2.624582 3.77444 0)
			(unlocked yes)
			(layer "F.SilkS")
			(effects
				(font
					(size 0.635 0.4064)
					(thickness 0.1524)
				)
			)
		)
		(fp_text user "19"
			(at 2.455418 3.77444 0)
			(unlocked yes)
			(layer "F.SilkS")
			(effects
				(font
					(size 0.635 0.4064)
					(thickness 0.1524)
				)
			)
		)
		(fp_text user "2"
			(at -2.624582 -3.71856 0)
			(unlocked yes)
			(layer "F.SilkS")
			(effects
				(font
					(size 0.635 0.4064)
					(thickness 0.1524)
				)
			)
		)
		(fp_text user "20"
			(at 1.693418 -4.09956 0)
			(unlocked yes)
			(layer "F.SilkS")
			(effects
				(font
					(size 0.635 0.4064)
					(thickness 0.1524)
				)
			)
		)
		(fp_text user "19"
			(at 3.085338 3.77444 0)
			(unlocked yes)
			(layer "F.Fab")
			(effects
				(font
					(size 0.7874 0.5842)
					(thickness 0.1524)
				)
			)
		)
		(fp_text user "1"
			(at -2.687066 3.14071 0)
			(unlocked yes)
			(layer "F.Fab")
			(effects
				(font
					(size 0.7874 0.5842)
					(thickness 0.1524)
				)
			)
		)
		(fp_text user "2"
			(at -1.875536 -3.850386 0)
			(unlocked yes)
			(layer "F.Fab")
			(effects
				(font
					(size 0.7874 0.5842)
					(thickness 0.1524)
				)
			)
		)
		(fp_text user "20"
			(at 2.980436 -3.89128 0)
			(unlocked yes)
			(layer "F.Fab")
			(effects
				(font
					(size 0.7874 0.5842)
					(thickness 0.1524)
				)
			)
		)
		(pad "1" smd rect
			(at -2.249932 1.999996 270)
			(size 0.254 1.8034)
			(layers "F.Cu" "F.Mask" "F.Paste")
			(net "R_MAC_PPS_IN1P")
		)
		(pad "2" smd rect
			(at -2.249932 -1.999996 270)
			(size 0.254 1.8034)
			(layers "F.Cu" "F.Mask" "F.Paste")
			(net "R_MAC_USB_DP")
		)
		(pad "3" smd rect
			(at -1.75006 1.999996 270)
			(size 0.254 1.8034)
			(layers "F.Cu" "F.Mask" "F.Paste")
			(net "R_MAC_PPS_IN1N")
		)
		(pad "4" smd rect
			(at -1.75006 -1.999996 270)
			(size 0.254 1.8034)
			(layers "F.Cu" "F.Mask" "F.Paste")
			(net "R_MAC_USB_DM")
		)
		(pad "5" smd rect
			(at -1.249934 1.999996 270)
			(size 0.254 1.8034)
			(layers "F.Cu" "F.Mask" "F.Paste")
			(net "R_MAC_PPS_IN0P")
		)
		(pad "6" smd rect
			(at -1.249934 -1.999996 270)
			(size 0.254 1.8034)
			(layers "F.Cu" "F.Mask" "F.Paste")
			(net "XP5R0V_MAC_USB")
		)
		(pad "7" smd rect
			(at -0.750062 1.999996 270)
			(size 0.254 1.8034)
			(layers "F.Cu" "F.Mask" "F.Paste")
			(net "R_MAC_PPS_IN0N")
		)
		(pad "8" smd rect
			(at -0.750062 -1.999996 270)
			(size 0.254 1.8034)
			(layers "F.Cu" "F.Mask" "F.Paste")
			(net "SG")
		)
		(pad "9" smd rect
			(at -0.249936 1.999996 270)
			(size 0.254 1.8034)
			(layers "F.Cu" "F.Mask" "F.Paste")
			(net "SG")
		)
		(pad "10" smd rect
			(at -0.249936 -1.999996 270)
			(size 0.254 1.8034)
			(layers "F.Cu" "F.Mask" "F.Paste")
			(net "Net_773")
		)
		(pad "11" smd rect
			(at 0.249936 1.999996 270)
			(size 0.254 1.8034)
			(layers "F.Cu" "F.Mask" "F.Paste")
			(net "Net_772")
		)
		(pad "12" smd rect
			(at 0.249936 -1.999996 270)
			(size 0.254 1.8034)
			(layers "F.Cu" "F.Mask" "F.Paste")
			(net "Net_771")
		)
		(pad "13" smd rect
			(at 0.750062 1.999996 270)
			(size 0.254 1.8034)
			(layers "F.Cu" "F.Mask" "F.Paste")
			(net "Net_770")
		)
		(pad "14" smd rect
			(at 0.750062 -1.999996 270)
			(size 0.254 1.8034)
			(layers "F.Cu" "F.Mask" "F.Paste")
			(net "Net_769")
		)
		(pad "15" smd rect
			(at 1.249934 1.999996 270)
			(size 0.254 1.8034)
			(layers "F.Cu" "F.Mask" "F.Paste")
			(net "SG")
		)
		(pad "16" smd rect
			(at 1.249934 -1.999996 270)
			(size 0.254 1.8034)
			(layers "F.Cu" "F.Mask" "F.Paste")
			(net "Net_768")
		)
		(pad "17" smd rect
			(at 1.75006 1.999996 270)
			(size 0.254 1.8034)
			(layers "F.Cu" "F.Mask" "F.Paste")
			(net "R_MAC_PPS_OUTP")
		)
		(pad "18" smd rect
			(at 1.75006 -1.999996 270)
			(size 0.254 1.8034)
			(layers "F.Cu" "F.Mask" "F.Paste")
			(net "Net_767")
		)
		(pad "19" smd rect
			(at 2.249932 1.999996 270)
			(size 0.254 1.8034)
			(layers "F.Cu" "F.Mask" "F.Paste")
			(net "R_MAC_PPS_OUTN")
		)
		(pad "20" smd rect
			(at 2.249932 -1.999996 270)
			(size 0.254 1.8034)
			(layers "F.Cu" "F.Mask" "F.Paste")
			(net "MAC_ALARM")
		)
	)
	(footprint ""
		(layer "F.Cu")
		(at 102.5398 -64.2874 -90)
		(property "Reference" "R292"
			(at 2.8194 -0.75057 90)
			(unlocked yes)
			(layer "F.SilkS")
			(effects
				(font
					(size 0.7874 0.5842)
					(thickness 0.1524)
				)
			)
		)
		(property "Value" "VAL*"
			(at 0.02032 2.13233 270)
			(unlocked yes)
			(layer "F.Fab")
			(hide yes)
			(effects
				(font
					(size 0.7874 0.5842)
					(thickness 0.1524)
				)
			)
		)
		(property "Tolerance" "TOL*"
			(at 0.044704 3.05435 270)
			(unlocked yes)
			(layer "Cmts.User")
			(hide yes)
			(effects
				(font
					(size 0.7874 0.5842)
					(thickness 0.1524)
				)
			)
		)
		(property "User Part Number" "PARTNUM*"
			(at 0.02032 4.024884 270)
			(unlocked yes)
			(layer "Cmts.User")
			(hide yes)
			(effects
				(font
					(size 0.7874 0.5842)
					(thickness 0.1524)
				)
			)
		)
		(property "Device Type" "RESISTOR-G155-11002-01,10KOHM,A"
			(at 0.008382 1.210564 270)
			(unlocked yes)
			(layer "F.Fab")
			(hide yes)
			(effects
				(font
					(size 0.7874 0.5842)
					(thickness 0.1524)
				)
			)
		)
		(duplicate_pad_numbers_are_jumpers no)
		(fp_line
			(start -1.143 0.5588)
			(end 1.143 0.5588)
			(stroke
				(width 0.1)
				(type default)
			)
			(layer "F.SilkS")
		)
		(fp_line
			(start 1.143 0.5588)
			(end 1.143 -0.5588)
			(stroke
				(width 0.1)
				(type default)
			)
			(layer "F.SilkS")
		)
		(fp_line
			(start -1.143 -0.5588)
			(end -1.143 0.5588)
			(stroke
				(width 0.1)
				(type default)
			)
			(layer "F.SilkS")
		)
		(fp_line
			(start 1.143 -0.5588)
			(end -1.143 -0.5588)
			(stroke
				(width 0.1)
				(type default)
			)
			(layer "F.SilkS")
		)
		(fp_rect
			(start 1.143 0.5588)
			(end -1.143 -0.5588)
			(stroke
				(width 0)
				(type default)
			)
			(fill no)
			(layer "F.CrtYd")
		)
		(fp_line
			(start -0.508 0.3048)
			(end 0.508 0.3048)
			(stroke
				(width 0.1)
				(type default)
			)
			(layer "F.Fab")
		)
		(fp_line
			(start 0.508 0.3048)
			(end 0.508 -0.3048)
			(stroke
				(width 0.1)
				(type default)
			)
			(layer "F.Fab")
		)
		(fp_line
			(start -0.508 -0.3048)
			(end -0.508 0.3048)
			(stroke
				(width 0.1)
				(type default)
			)
			(layer "F.Fab")
		)
		(fp_line
			(start 0.508 -0.3048)
			(end -0.508 -0.3048)
			(stroke
				(width 0.1)
				(type default)
			)
			(layer "F.Fab")
		)
		(pad "1" smd rect
			(at -0.5334 0 270)
			(size 0.7112 0.6096)
			(layers "F.Cu" "F.Mask" "F.Paste")
			(net "XP3R3V_FPGA")
		)
		(pad "2" smd rect
			(at 0.5334 0 270)
			(size 0.7112 0.6096)
			(layers "F.Cu" "F.Mask" "F.Paste")
			(net "FPGA_IO_4")
		)
		(zone
			(layer "F.Cu")
			(hatch none 0.5)
			(connect_pads
				(clearance 0)
			)
			(min_thickness 0.25)
			(keepout
				(tracks allowed)
				(vias not_allowed)
				(pads allowed)
				(copperpour not_allowed)
				(footprints allowed)
			)
			(placement
				(enabled no)
				(sheetname "")
			)
			(fill
				(thermal_gap 0.5)
				(thermal_bridge_width 0.5)
				(island_removal_mode 0)
			)
			(polygon
				(pts
					(xy 102.235 -64.2112) (xy 102.8446 -64.2112) (xy 102.8446 -64.3636) (xy 102.235 -64.3636)
				)
			)
		)
	)
	(footprint ""
		(layer "F.Cu")
		(at 55.1942 -74.9808 90)
		(property "Reference" "R418"
			(at -0.5588 4.28117 90)
			(unlocked yes)
			(layer "F.SilkS")
			(effects
				(font
					(size 0.7874 0.5842)
					(thickness 0.1524)
				)
			)
		)
		(property "Value" "VAL*"
			(at 0.02032 2.13233 90)
			(unlocked yes)
			(layer "F.Fab")
			(hide yes)
			(effects
				(font
					(size 0.7874 0.5842)
					(thickness 0.1524)
				)
			)
		)
		(property "Device Type" "RESISTOR-G155-14701-01,4.7KOHMA"
			(at 0.008382 1.210564 90)
			(unlocked yes)
			(layer "F.Fab")
			(hide yes)
			(effects
				(font
					(size 0.7874 0.5842)
					(thickness 0.1524)
				)
			)
		)
		(property "User Part Number" "PARTNUM*"
			(at 0.02032 4.024884 90)
			(unlocked yes)
			(layer "Cmts.User")
			(hide yes)
			(effects
				(font
					(size 0.7874 0.5842)
					(thickness 0.1524)
				)
			)
		)
		(property "Tolerance" "TOL*"
			(at 0.044704 3.05435 90)
			(unlocked yes)
			(layer "Cmts.User")
			(hide yes)
			(effects
				(font
					(size 0.7874 0.5842)
					(thickness 0.1524)
				)
			)
		)
		(duplicate_pad_numbers_are_jumpers no)
		(fp_line
			(start 1.143 -0.5588)
			(end -1.143 -0.5588)
			(stroke
				(width 0.1)
				(type default)
			)
			(layer "F.SilkS")
		)
		(fp_line
			(start -1.143 -0.5588)
			(end -1.143 0.5588)
			(stroke
				(width 0.1)
				(type default)
			)
			(layer "F.SilkS")
		)
		(fp_line
			(start 1.143 0.5588)
			(end 1.143 -0.5588)
			(stroke
				(width 0.1)
				(type default)
			)
			(layer "F.SilkS")
		)
		(fp_line
			(start -1.143 0.5588)
			(end 1.143 0.5588)
			(stroke
				(width 0.1)
				(type default)
			)
			(layer "F.SilkS")
		)
		(fp_rect
			(start -1.143 0.5588)
			(end 1.143 -0.5588)
			(stroke
				(width 0)
				(type default)
			)
			(fill no)
			(layer "F.CrtYd")
		)
		(fp_line
			(start 0.508 -0.3048)
			(end -0.508 -0.3048)
			(stroke
				(width 0.1)
				(type default)
			)
			(layer "F.Fab")
		)
		(fp_line
			(start -0.508 -0.3048)
			(end -0.508 0.3048)
			(stroke
				(width 0.1)
				(type default)
			)
			(layer "F.Fab")
		)
		(fp_line
			(start 0.508 0.3048)
			(end 0.508 -0.3048)
			(stroke
				(width 0.1)
				(type default)
			)
			(layer "F.Fab")
		)
		(fp_line
			(start -0.508 0.3048)
			(end 0.508 0.3048)
			(stroke
				(width 0.1)
				(type default)
			)
			(layer "F.Fab")
		)
		(pad "1" smd rect
			(at -0.5334 0 90)
			(size 0.7112 0.6096)
			(layers "F.Cu" "F.Mask" "F.Paste")
			(net "XP3R3V_FPGA")
		)
		(pad "2" smd rect
			(at 0.5334 0 90)
			(size 0.7112 0.6096)
			(layers "F.Cu" "F.Mask" "F.Paste")
			(net "UNNAMED_6_LM75BDPTSSOP8_I59_A0")
		)
		(zone
			(layer "F.Cu")
			(hatch none 0.5)
			(connect_pads
				(clearance 0)
			)
			(min_thickness 0.25)
			(keepout
				(tracks not_allowed)
				(vias allowed)
				(pads allowed)
				(copperpour not_allowed)
				(footprints allowed)
			)
			(placement
				(enabled no)
				(sheetname "")
			)
			(fill
				(thermal_gap 0.5)
				(thermal_bridge_width 0.5)
				(island_removal_mode 0)
			)
			(polygon
				(pts
					(xy 55.499 -74.9046) (xy 55.499 -75.057) (xy 54.8894 -75.057) (xy 54.8894 -74.9046)
				)
			)
		)
		(zone
			(layer "F.Cu")
			(hatch none 0.5)
			(connect_pads
				(clearance 0)
			)
			(min_thickness 0.25)
			(keepout
				(tracks allowed)
				(vias not_allowed)
				(pads allowed)
				(copperpour not_allowed)
				(footprints allowed)
			)
			(placement
				(enabled no)
				(sheetname "")
			)
			(fill
				(thermal_gap 0.5)
				(thermal_bridge_width 0.5)
				(island_removal_mode 0)
			)
			(polygon
				(pts
					(xy 55.499 -74.9046) (xy 55.499 -75.057) (xy 54.8894 -75.057) (xy 54.8894 -74.9046)
				)
			)
		)
	)
	(footprint ""
		(layer "F.Cu")
		(at 142.24 -59.563 90)
		(property "Reference" "C259"
			(at 3.048 -1.86563 90)
			(unlocked yes)
			(layer "F.SilkS")
			(effects
				(font
					(size 0.7874 0.5842)
					(thickness 0.1524)
				)
			)
		)
		(property "Value" "VAL*"
			(at 0.0762 2.067306 90)
			(unlocked yes)
			(layer "F.Fab")
			(hide yes)
			(effects
				(font
					(size 0.7874 0.5842)
					(thickness 0.1524)
				)
			)
		)
		(property "Device Type" "CAPACITOR-G105-0B223-EK,0.022UA"
			(at 0.0508 1.127506 90)
			(unlocked yes)
			(layer "F.Fab")
			(hide yes)
			(effects
				(font
					(size 0.7874 0.5842)
					(thickness 0.1524)
				)
			)
		)
		(property "User Part Number" "PARTNUM*"
			(at 0.1016 4.023106 90)
			(unlocked yes)
			(layer "Cmts.User")
			(hide yes)
			(effects
				(font
					(size 0.7874 0.5842)
					(thickness 0.1524)
				)
			)
		)
		(property "Tolerance" "TOL*"
			(at 0.0762 3.032506 90)
			(unlocked yes)
			(layer "Cmts.User")
			(hide yes)
			(effects
				(font
					(size 0.7874 0.5842)
					(thickness 0.1524)
				)
			)
		)
		(duplicate_pad_numbers_are_jumpers no)
		(fp_line
			(start 1.143 -0.5588)
			(end -1.143 -0.5588)
			(stroke
				(width 0.1)
				(type default)
			)
			(layer "F.SilkS")
		)
		(fp_line
			(start -1.143 -0.5588)
			(end -1.143 0.5588)
			(stroke
				(width 0.1)
				(type default)
			)
			(layer "F.SilkS")
		)
		(fp_line
			(start 1.143 0.5588)
			(end 1.143 -0.5588)
			(stroke
				(width 0.1)
				(type default)
			)
			(layer "F.SilkS")
		)
		(fp_line
			(start -1.143 0.5588)
			(end 1.143 0.5588)
			(stroke
				(width 0.1)
				(type default)
			)
			(layer "F.SilkS")
		)
		(fp_rect
			(start -1.143 -0.5588)
			(end 1.143 0.5588)
			(stroke
				(width 0)
				(type default)
			)
			(fill no)
			(layer "F.CrtYd")
		)
		(fp_line
			(start 0.508 -0.3048)
			(end -0.508 -0.3048)
			(stroke
				(width 0.1)
				(type default)
			)
			(layer "F.Fab")
		)
		(fp_line
			(start -0.508 -0.3048)
			(end -0.508 0.3048)
			(stroke
				(width 0.1)
				(type default)
			)
			(layer "F.Fab")
		)
		(fp_line
			(start 0.508 0.3048)
			(end 0.508 -0.3048)
			(stroke
				(width 0.1)
				(type default)
			)
			(layer "F.Fab")
		)
		(fp_line
			(start -0.508 0.3048)
			(end 0.508 0.3048)
			(stroke
				(width 0.1)
				(type default)
			)
			(layer "F.Fab")
		)
		(pad "1" smd rect
			(at -0.5334 0 90)
			(size 0.7112 0.6096)
			(layers "F.Cu" "F.Mask" "F.Paste")
			(net "XP1R0V_SS")
		)
		(pad "2" smd rect
			(at 0.5334 0 90)
			(size 0.7112 0.6096)
			(layers "F.Cu" "F.Mask" "F.Paste")
			(net "XP1R0V_AGND")
		)
		(zone
			(layer "F.Cu")
			(hatch none 0.5)
			(connect_pads
				(clearance 0)
			)
			(min_thickness 0.25)
			(keepout
				(tracks allowed)
				(vias not_allowed)
				(pads allowed)
				(copperpour not_allowed)
				(footprints allowed)
			)
			(placement
				(enabled no)
				(sheetname "")
			)
			(fill
				(thermal_gap 0.5)
				(thermal_bridge_width 0.5)
				(island_removal_mode 0)
			)
			(polygon
				(pts
					(xy 141.9352 -59.4868) (xy 142.5448 -59.4868) (xy 142.5448 -59.6392) (xy 141.9352 -59.6392)
				)
			)
		)
	)
	(footprint ""
		(layer "F.Cu")
		(at 79.756 -48.133)
		(property "Reference" "R97"
			(at 0.127 14.26337 0)
			(unlocked yes)
			(layer "F.SilkS")
			(effects
				(font
					(size 0.7874 0.5842)
					(thickness 0.1524)
				)
			)
		)
		(property "Value" "VAL*"
			(at 0.02032 2.13233 0)
			(unlocked yes)
			(layer "F.Fab")
			(hide yes)
			(effects
				(font
					(size 0.7874 0.5842)
					(thickness 0.1524)
				)
			)
		)
		(property "Device Type" "RESISTOR-G155-100R0-J0,0OHM,-"
			(at 0.008382 1.210564 0)
			(unlocked yes)
			(layer "F.Fab")
			(hide yes)
			(effects
				(font
					(size 0.7874 0.5842)
					(thickness 0.1524)
				)
			)
		)
		(property "User Part Number" "PARTNUM*"
			(at 0.02032 4.024884 0)
			(unlocked yes)
			(layer "Cmts.User")
			(hide yes)
			(effects
				(font
					(size 0.7874 0.5842)
					(thickness 0.1524)
				)
			)
		)
		(property "Tolerance" "TOL*"
			(at 0.044704 3.05435 0)
			(unlocked yes)
			(layer "Cmts.User")
			(hide yes)
			(effects
				(font
					(size 0.7874 0.5842)
					(thickness 0.1524)
				)
			)
		)
		(duplicate_pad_numbers_are_jumpers no)
		(fp_line
			(start -1.143 -0.5588)
			(end -1.143 0.5588)
			(stroke
				(width 0.1)
				(type default)
			)
			(layer "F.SilkS")
		)
		(fp_line
			(start -1.143 0.5588)
			(end 1.143 0.5588)
			(stroke
				(width 0.1)
				(type default)
			)
			(layer "F.SilkS")
		)
		(fp_line
			(start 1.143 -0.5588)
			(end -1.143 -0.5588)
			(stroke
				(width 0.1)
				(type default)
			)
			(layer "F.SilkS")
		)
		(fp_line
			(start 1.143 0.5588)
			(end 1.143 -0.5588)
			(stroke
				(width 0.1)
				(type default)
			)
			(layer "F.SilkS")
		)
		(fp_rect
			(start -1.143 0.5588)
			(end 1.143 -0.5588)
			(stroke
				(width 0)
				(type default)
			)
			(fill no)
			(layer "F.CrtYd")
		)
		(fp_line
			(start -0.508 -0.3048)
			(end -0.508 0.3048)
			(stroke
				(width 0.1)
				(type default)
			)
			(layer "F.Fab")
		)
		(fp_line
			(start -0.508 0.3048)
			(end 0.508 0.3048)
			(stroke
				(width 0.1)
				(type default)
			)
			(layer "F.Fab")
		)
		(fp_line
			(start 0.508 -0.3048)
			(end -0.508 -0.3048)
			(stroke
				(width 0.1)
				(type default)
			)
			(layer "F.Fab")
		)
		(fp_line
			(start 0.508 0.3048)
			(end 0.508 -0.3048)
			(stroke
				(width 0.1)
				(type default)
			)
			(layer "F.Fab")
		)
		(pad "1" smd rect
			(at -0.5334 0)
			(size 0.7112 0.6096)
			(layers "F.Cu" "F.Mask" "F.Paste")
			(net "R_MAC_USB_DP")
		)
		(pad "2" smd rect
			(at 0.5334 0)
			(size 0.7112 0.6096)
			(layers "F.Cu" "F.Mask" "F.Paste")
			(net "MUX_USB_DP")
		)
		(zone
			(layer "F.Cu")
			(hatch none 0.5)
			(connect_pads
				(clearance 0)
			)
			(min_thickness 0.25)
			(keepout
				(tracks allowed)
				(vias not_allowed)
				(pads allowed)
				(copperpour not_allowed)
				(footprints allowed)
			)
			(placement
				(enabled no)
				(sheetname "")
			)
			(fill
				(thermal_gap 0.5)
				(thermal_bridge_width 0.5)
				(island_removal_mode 0)
			)
			(polygon
				(pts
					(xy 79.6798 -47.8282) (xy 79.8322 -47.8282) (xy 79.8322 -48.4378) (xy 79.6798 -48.4378)
				)
			)
		)
	)
	(footprint ""
		(layer "F.Cu")
		(at 19.468338 -50.165 180)
		(property "Reference" "R401"
			(at -2.883662 0.21463 0)
			(unlocked yes)
			(layer "F.SilkS")
			(effects
				(font
					(size 0.7874 0.5842)
					(thickness 0.1524)
				)
			)
		)
		(property "Value" "VAL*"
			(at 0.02032 2.13233 180)
			(unlocked yes)
			(layer "F.Fab")
			(hide yes)
			(effects
				(font
					(size 0.7874 0.5842)
					(thickness 0.1524)
				)
			)
		)
		(property "Device Type" "RESISTOR-G155-11000-01,100OHM,A"
			(at 0.008382 1.210564 180)
			(unlocked yes)
			(layer "F.Fab")
			(hide yes)
			(effects
				(font
					(size 0.7874 0.5842)
					(thickness 0.1524)
				)
			)
		)
		(property "User Part Number" "PARTNUM*"
			(at 0.02032 4.024884 180)
			(unlocked yes)
			(layer "Cmts.User")
			(hide yes)
			(effects
				(font
					(size 0.7874 0.5842)
					(thickness 0.1524)
				)
			)
		)
		(property "Tolerance" "TOL*"
			(at 0.044704 3.05435 180)
			(unlocked yes)
			(layer "Cmts.User")
			(hide yes)
			(effects
				(font
					(size 0.7874 0.5842)
					(thickness 0.1524)
				)
			)
		)
		(duplicate_pad_numbers_are_jumpers no)
		(fp_line
			(start 1.143 0.5588)
			(end 1.143 -0.5588)
			(stroke
				(width 0.1)
				(type default)
			)
			(layer "F.SilkS")
		)
		(fp_line
			(start 1.143 -0.5588)
			(end -1.143 -0.5588)
			(stroke
				(width 0.1)
				(type default)
			)
			(layer "F.SilkS")
		)
		(fp_line
			(start -1.143 0.5588)
			(end 1.143 0.5588)
			(stroke
				(width 0.1)
				(type default)
			)
			(layer "F.SilkS")
		)
		(fp_line
			(start -1.143 -0.5588)
			(end -1.143 0.5588)
			(stroke
				(width 0.1)
				(type default)
			)
			(layer "F.SilkS")
		)
		(fp_poly
			(pts
				(xy -1.143 0.5588) (xy 1.143 0.5588) (xy 1.143 -0.5588) (xy -1.143 -0.5588)
			)
			(stroke
				(width 0)
				(type default)
			)
			(fill no)
			(layer "F.CrtYd")
		)
		(fp_line
			(start 0.508 0.3048)
			(end 0.508 -0.3048)
			(stroke
				(width 0.1)
				(type default)
			)
			(layer "F.Fab")
		)
		(fp_line
			(start 0.508 -0.3048)
			(end -0.508 -0.3048)
			(stroke
				(width 0.1)
				(type default)
			)
			(layer "F.Fab")
		)
		(fp_line
			(start -0.508 0.3048)
			(end 0.508 0.3048)
			(stroke
				(width 0.1)
				(type default)
			)
			(layer "F.Fab")
		)
		(fp_line
			(start -0.508 -0.3048)
			(end -0.508 0.3048)
			(stroke
				(width 0.1)
				(type default)
			)
			(layer "F.Fab")
		)
		(pad "1" smd rect
			(at -0.5334 0 180)
			(size 0.7112 0.6096)
			(layers "F.Cu" "F.Mask" "F.Paste")
			(net "FPGA_OUT_SMA4_LED_GREEN_N")
		)
		(pad "2" smd rect
			(at 0.5334 0 180)
			(size 0.7112 0.6096)
			(layers "F.Cu" "F.Mask" "F.Paste")
			(net "UNNAMED_14_LED4PV14_I268_4")
		)
		(zone
			(layer "F.Cu")
			(hatch none 0.5)
			(connect_pads
				(clearance 0)
			)
			(min_thickness 0.25)
			(keepout
				(tracks allowed)
				(vias not_allowed)
				(pads allowed)
				(copperpour not_allowed)
				(footprints allowed)
			)
			(placement
				(enabled no)
				(sheetname "")
			)
			(fill
				(thermal_gap 0.5)
				(thermal_bridge_width 0.5)
				(island_removal_mode 0)
			)
			(polygon
				(pts
					(xy 19.544538 -50.4698) (xy 19.392138 -50.4698) (xy 19.392138 -49.8602) (xy 19.544538 -49.8602)
				)
			)
		)
		(zone
			(layer "F.Cu")
			(hatch none 0.5)
			(connect_pads
				(clearance 0)
			)
			(min_thickness 0.25)
			(keepout
				(tracks not_allowed)
				(vias allowed)
				(pads allowed)
				(copperpour not_allowed)
				(footprints allowed)
			)
			(placement
				(enabled no)
				(sheetname "")
			)
			(fill
				(thermal_gap 0.5)
				(thermal_bridge_width 0.5)
				(island_removal_mode 0)
			)
			(polygon
				(pts
					(xy 19.544538 -50.4698) (xy 19.392138 -50.4698) (xy 19.392138 -49.8602) (xy 19.544538 -49.8602)
				)
			)
		)
	)
	(footprint ""
		(layer "F.Cu")
		(at 23.507192 -66.8528 180)
		(property "Reference" "L18"
			(at -3.035808 0.03683 0)
			(unlocked yes)
			(layer "F.SilkS")
			(effects
				(font
					(size 0.7874 0.5842)
					(thickness 0.1524)
				)
			)
		)
		(property "Value" "VAL*"
			(at 0.014732 2.526538 180)
			(unlocked yes)
			(layer "F.Fab")
			(hide yes)
			(effects
				(font
					(size 0.7874 0.5842)
					(thickness 0.000001)
				)
			)
		)
		(property "Tolerance" "TOL*"
			(at 0.014732 3.503676 180)
			(unlocked yes)
			(layer "Cmts.User")
			(hide yes)
			(effects
				(font
					(size 0.7874 0.5842)
					(thickness 0.000001)
				)
			)
		)
		(property "User Part Number" "PARTNUM*"
			(at 0.02794 4.480814 180)
			(unlocked yes)
			(layer "Cmts.User")
			(hide yes)
			(effects
				(font
					(size 0.7874 0.5842)
					(thickness 0.000001)
				)
			)
		)
		(property "Device Type" "FERRITEBEAD-G191-10097-01,600OA"
			(at 0.014732 1.600708 180)
			(unlocked yes)
			(layer "F.Fab")
			(hide yes)
			(effects
				(font
					(size 0.7874 0.5842)
					(thickness 0.000001)
				)
			)
		)
		(duplicate_pad_numbers_are_jumpers no)
		(fp_line
			(start 1.3208 0.7112)
			(end -1.3208 0.7112)
			(stroke
				(width 0.1)
				(type default)
			)
			(layer "F.SilkS")
		)
		(fp_line
			(start 1.3208 -0.7112)
			(end 1.3208 0.7112)
			(stroke
				(width 0.1)
				(type default)
			)
			(layer "F.SilkS")
		)
		(fp_line
			(start -1.3208 0.7112)
			(end -1.3208 -0.7112)
			(stroke
				(width 0.1)
				(type default)
			)
			(layer "F.SilkS")
		)
		(fp_line
			(start -1.3208 -0.7112)
			(end 1.3208 -0.7112)
			(stroke
				(width 0.1)
				(type default)
			)
			(layer "F.SilkS")
		)
		(fp_rect
			(start -1.3208 0.7112)
			(end 1.3208 -0.7112)
			(stroke
				(width 0)
				(type default)
			)
			(fill no)
			(layer "F.CrtYd")
		)
		(fp_line
			(start 0.8128 0.4572)
			(end -0.8128 0.4572)
			(stroke
				(width 0.1)
				(type default)
			)
			(layer "F.Fab")
		)
		(fp_line
			(start 0.8128 -0.4572)
			(end 0.8128 0.4572)
			(stroke
				(width 0.1)
				(type default)
			)
			(layer "F.Fab")
		)
		(fp_line
			(start -0.8128 0.4572)
			(end -0.8128 -0.4572)
			(stroke
				(width 0.1)
				(type default)
			)
			(layer "F.Fab")
		)
		(fp_line
			(start -0.8128 -0.4572)
			(end 0.8128 -0.4572)
			(stroke
				(width 0.1)
				(type default)
			)
			(layer "F.Fab")
		)
		(pad "1" smd rect
			(at -0.6858 0 180)
			(size 0.762 0.8636)
			(layers "F.Cu" "F.Mask" "F.Paste")
			(net "XP1R8V_FPGA")
		)
		(pad "2" smd rect
			(at 0.6858 0 180)
			(size 0.762 0.8636)
			(layers "F.Cu" "F.Mask" "F.Paste")
			(net "XP1R8V_ICP10100")
		)
		(zone
			(layer "F.Cu")
			(hatch none 0.5)
			(connect_pads
				(clearance 0)
			)
			(min_thickness 0.25)
			(keepout
				(tracks not_allowed)
				(vias allowed)
				(pads allowed)
				(copperpour not_allowed)
				(footprints allowed)
			)
			(placement
				(enabled no)
				(sheetname "")
			)
			(fill
				(thermal_gap 0.5)
				(thermal_bridge_width 0.5)
				(island_removal_mode 0)
			)
			(polygon
				(pts
					(xy 23.659592 -67.31) (xy 23.354792 -67.31) (xy 23.354792 -66.3956) (xy 23.659592 -66.3956)
				)
			)
		)
		(zone
			(layer "F.Cu")
			(hatch none 0.5)
			(connect_pads
				(clearance 0)
			)
			(min_thickness 0.25)
			(keepout
				(tracks allowed)
				(vias not_allowed)
				(pads allowed)
				(copperpour not_allowed)
				(footprints allowed)
			)
			(placement
				(enabled no)
				(sheetname "")
			)
			(fill
				(thermal_gap 0.5)
				(thermal_bridge_width 0.5)
				(island_removal_mode 0)
			)
			(polygon
				(pts
					(xy 23.659592 -67.31) (xy 23.354792 -67.31) (xy 23.354792 -66.3956) (xy 23.659592 -66.3956)
				)
			)
		)
	)
	(footprint ""
		(layer "F.Cu")
		(at 56.134 -132.715)
		(property "Reference" "SP41"
			(at 0 0 0)
			(layer "F.SilkS")
			(hide yes)
			(effects
				(font
					(size 1.27 1.27)
				)
			)
		)
		(property "Value" ""
			(at 0 0 0)
			(layer "F.Fab")
			(effects
				(font
					(size 1.27 1.27)
				)
			)
		)
		(duplicate_pad_numbers_are_jumpers no)
	)
	(footprint ""
		(layer "F.Cu")
		(at 101.092 -87.4522 -90)
		(property "Reference" "U39"
			(at -2.7178 1.99263 90)
			(unlocked yes)
			(layer "F.SilkS")
			(effects
				(font
					(size 0.7874 0.5842)
					(thickness 0.1524)
				)
			)
		)
		(property "Value" ""
			(at 0 0 270)
			(layer "F.Fab")
			(effects
				(font
					(size 1.27 1.27)
				)
			)
		)
		(property "Device Type" "NLASB3157DFT2G_SC88-G223-10187A"
			(at 0.1524 2.168906 270)
			(unlocked yes)
			(layer "F.Fab")
			(hide yes)
			(effects
				(font
					(size 0.7874 0.5842)
					(thickness 0.000001)
				)
			)
		)
		(property "User Part Number" "PARTNUM*"
			(at 0.127 3.184906 270)
			(unlocked yes)
			(layer "Cmts.User")
			(hide yes)
			(effects
				(font
					(size 0.7874 0.5842)
					(thickness 0.000001)
				)
			)
		)
		(duplicate_pad_numbers_are_jumpers no)
		(fp_line
			(start -1.50876 1.354074)
			(end -1.50876 -1.354074)
			(stroke
				(width 0.1)
				(type default)
			)
			(layer "F.SilkS")
		)
		(fp_line
			(start 1.50876 1.354074)
			(end -1.50876 1.354074)
			(stroke
				(width 0.1)
				(type default)
			)
			(layer "F.SilkS")
		)
		(fp_line
			(start -1.50876 -1.354074)
			(end 1.50876 -1.354074)
			(stroke
				(width 0.1)
				(type default)
			)
			(layer "F.SilkS")
		)
		(fp_line
			(start 1.50876 -1.354074)
			(end 1.50876 1.354074)
			(stroke
				(width 0.1)
				(type default)
			)
			(layer "F.SilkS")
		)
		(fp_poly
			(pts
				(arc
					(start -2.159 -1.3716)
					(mid -2.159 -0.6096)
					(end -2.159 -1.3716)
				)
			)
			(stroke
				(width 0)
				(type default)
			)
			(fill yes)
			(layer "F.SilkS")
		)
		(fp_poly
			(pts
				(xy -1.76276 1.608074) (xy 1.76276 1.608074) (xy 1.76276 -1.608074) (xy -1.76276 -1.608074)
			)
			(stroke
				(width 0)
				(type default)
			)
			(fill no)
			(layer "F.CrtYd")
		)
		(fp_line
			(start -0.674878 1.100074)
			(end -0.674878 -1.100074)
			(stroke
				(width 0.1)
				(type default)
			)
			(layer "F.Fab")
		)
		(fp_line
			(start 0.674878 1.100074)
			(end -0.674878 1.100074)
			(stroke
				(width 0.1)
				(type default)
			)
			(layer "F.Fab")
		)
		(fp_line
			(start -0.674878 -1.100074)
			(end 0.674878 -1.100074)
			(stroke
				(width 0.1)
				(type default)
			)
			(layer "F.Fab")
		)
		(fp_line
			(start 0.674878 -1.100074)
			(end 0.674878 1.100074)
			(stroke
				(width 0.1)
				(type default)
			)
			(layer "F.Fab")
		)
		(fp_poly
			(pts
				(arc
					(start -2.159 -1.3716)
					(mid -2.159 -0.6096)
					(end -2.159 -1.3716)
				)
			)
			(stroke
				(width 0)
				(type default)
			)
			(fill yes)
			(layer "F.Fab")
		)
		(fp_text user "3"
			(at -0.83185 1.778 0)
			(unlocked yes)
			(layer "F.SilkS")
			(effects
				(font
					(size 0.635 0.4064)
					(thickness 0.1524)
				)
			)
		)
		(fp_text user "4"
			(at 2.08915 1.651 0)
			(unlocked yes)
			(layer "F.SilkS")
			(effects
				(font
					(size 0.635 0.4064)
					(thickness 0.1524)
				)
			)
		)
		(fp_text user "6"
			(at 2.08915 -1.651 0)
			(unlocked yes)
			(layer "F.SilkS")
			(effects
				(font
					(size 0.635 0.4064)
					(thickness 0.1524)
				)
			)
		)
		(fp_text user "4"
			(at 2.035048 0.924306 90)
			(unlocked yes)
			(layer "F.Fab")
			(effects
				(font
					(size 0.7874 0.5842)
					(thickness 0.1524)
				)
			)
		)
		(fp_text user "3"
			(at -1.995678 0.91313 90)
			(unlocked yes)
			(layer "F.Fab")
			(effects
				(font
					(size 0.7874 0.5842)
					(thickness 0.1524)
				)
			)
		)
		(fp_text user "6"
			(at 1.97104 -0.731774 90)
			(unlocked yes)
			(layer "F.Fab")
			(effects
				(font
					(size 0.7874 0.5842)
					(thickness 0.1524)
				)
			)
		)
		(pad "1" smd rect
			(at -0.94996 -0.649986 270)
			(size 0.6096 0.4318)
			(layers "F.Cu" "F.Mask" "F.Paste")
			(net "Net_787")
		)
		(pad "2" smd rect
			(at -0.94996 0 270)
			(size 0.6096 0.4318)
			(layers "F.Cu" "F.Mask" "F.Paste")
			(net "SG")
		)
		(pad "3" smd rect
			(at -0.94996 0.649986 270)
			(size 0.6096 0.4318)
			(layers "F.Cu" "F.Mask" "F.Paste")
			(net "FLASH_DQ2")
		)
		(pad "4" smd rect
			(at 0.94996 0.649986 270)
			(size 0.6096 0.4318)
			(layers "F.Cu" "F.Mask" "F.Paste")
			(net "FPGA_FLASH_DQ2")
		)
		(pad "5" smd rect
			(at 0.94996 0 270)
			(size 0.6096 0.4318)
			(layers "F.Cu" "F.Mask" "F.Paste")
			(net "XP3R3V_FPGA")
		)
		(pad "6" smd rect
			(at 0.94996 -0.649986 270)
			(size 0.6096 0.4318)
			(layers "F.Cu" "F.Mask" "F.Paste")
			(net "MUX2_SEL")
		)
	)
	(footprint ""
		(layer "F.Cu")
		(at 107.442 -59.7916)
		(property "Reference" "TP185"
			(at 2.82575 0.7874 90)
			(unlocked yes)
			(layer "F.SilkS")
			(effects
				(font
					(size 0.635 0.4064)
					(thickness 0.1524)
				)
				(justify left)
			)
		)
		(property "Value" ""
			(at 0 0 0)
			(layer "F.Fab")
			(effects
				(font
					(size 1.27 1.27)
				)
			)
		)
		(property "Device Type" "TP_PIONT-TP010CT020B030_PTH-TPA"
			(at -1.341882 0.996696 0)
			(unlocked yes)
			(layer "F.Fab")
			(hide yes)
			(effects
				(font
					(size 0.7874 0.5842)
					(thickness 0.1524)
				)
				(justify left)
			)
		)
		(duplicate_pad_numbers_are_jumpers no)
		(fp_poly
			(pts
				(arc
					(start 0.889 0)
					(mid -0.889 0)
					(end 0.889 0)
				)
			)
			(stroke
				(width 0)
				(type default)
			)
			(fill no)
			(layer "B.CrtYd")
		)
		(fp_poly
			(pts
				(arc
					(start 0.889 0)
					(mid -0.889 0)
					(end 0.889 0)
				)
			)
			(stroke
				(width 0)
				(type default)
			)
			(fill no)
			(layer "F.CrtYd")
		)
		(pad "1" thru_hole circle
			(at 0 0)
			(size 0.508 0.508)
			(drill 0.254)
			(layers "*.Cu" "*.Mask")
			(remove_unused_layers no)
			(net "IO_L23P_16")
			(clearance 0.1016)
			(padstack
				(mode front_inner_back)
				(layer "Inner"
					(shape circle)
					(size 0.508 0.508)
					(clearance 0.1016)
				)
				(layer "B.Cu"
					(shape circle)
					(size 0.762 0.762)
					(clearance -0.0254)
				)
			)
		)
	)
	(footprint ""
		(layer "F.Cu")
		(at 75.5904 -15.7734)
		(property "Reference" "R63"
			(at 0.3556 -2.98323 0)
			(unlocked yes)
			(layer "F.SilkS")
			(effects
				(font
					(size 0.7874 0.5842)
					(thickness 0.1524)
				)
			)
		)
		(property "Value" "VAL*"
			(at 0.02032 2.13233 0)
			(unlocked yes)
			(layer "F.Fab")
			(hide yes)
			(effects
				(font
					(size 0.7874 0.5842)
					(thickness 0.1524)
				)
			)
		)
		(property "Tolerance" "TOL*"
			(at 0.044704 3.05435 0)
			(unlocked yes)
			(layer "Cmts.User")
			(hide yes)
			(effects
				(font
					(size 0.7874 0.5842)
					(thickness 0.1524)
				)
			)
		)
		(property "User Part Number" "PARTNUM*"
			(at 0.02032 4.024884 0)
			(unlocked yes)
			(layer "Cmts.User")
			(hide yes)
			(effects
				(font
					(size 0.7874 0.5842)
					(thickness 0.1524)
				)
			)
		)
		(property "Device Type" "RESISTOR-G155-14701-01,4.7KOHMA"
			(at 0.008382 1.210564 0)
			(unlocked yes)
			(layer "F.Fab")
			(hide yes)
			(effects
				(font
					(size 0.7874 0.5842)
					(thickness 0.1524)
				)
			)
		)
		(duplicate_pad_numbers_are_jumpers no)
		(fp_line
			(start -1.143 -0.5588)
			(end -1.143 0.5588)
			(stroke
				(width 0.1)
				(type default)
			)
			(layer "F.SilkS")
		)
		(fp_line
			(start -1.143 0.5588)
			(end 1.143 0.5588)
			(stroke
				(width 0.1)
				(type default)
			)
			(layer "F.SilkS")
		)
		(fp_line
			(start 1.143 -0.5588)
			(end -1.143 -0.5588)
			(stroke
				(width 0.1)
				(type default)
			)
			(layer "F.SilkS")
		)
		(fp_line
			(start 1.143 0.5588)
			(end 1.143 -0.5588)
			(stroke
				(width 0.1)
				(type default)
			)
			(layer "F.SilkS")
		)
		(fp_poly
			(pts
				(xy -1.143 0.5588) (xy 1.143 0.5588) (xy 1.143 -0.5588) (xy -1.143 -0.5588)
			)
			(stroke
				(width 0)
				(type default)
			)
			(fill no)
			(layer "F.CrtYd")
		)
		(fp_line
			(start -0.508 -0.3048)
			(end -0.508 0.3048)
			(stroke
				(width 0.1)
				(type default)
			)
			(layer "F.Fab")
		)
		(fp_line
			(start -0.508 0.3048)
			(end 0.508 0.3048)
			(stroke
				(width 0.1)
				(type default)
			)
			(layer "F.Fab")
		)
		(fp_line
			(start 0.508 -0.3048)
			(end -0.508 -0.3048)
			(stroke
				(width 0.1)
				(type default)
			)
			(layer "F.Fab")
		)
		(fp_line
			(start 0.508 0.3048)
			(end 0.508 -0.3048)
			(stroke
				(width 0.1)
				(type default)
			)
			(layer "F.Fab")
		)
		(pad "1" smd rect
			(at -0.5334 0)
			(size 0.7112 0.6096)
			(layers "F.Cu" "F.Mask" "F.Paste")
			(net "XP3R3V_FPGA")
		)
		(pad "2" smd rect
			(at 0.5334 0)
			(size 0.7112 0.6096)
			(layers "F.Cu" "F.Mask" "F.Paste")
			(net "PCIE_PERST_N")
		)
		(zone
			(layer "F.Cu")
			(hatch none 0.5)
			(connect_pads
				(clearance 0)
			)
			(min_thickness 0.25)
			(keepout
				(tracks not_allowed)
				(vias allowed)
				(pads allowed)
				(copperpour not_allowed)
				(footprints allowed)
			)
			(placement
				(enabled no)
				(sheetname "")
			)
			(fill
				(thermal_gap 0.5)
				(thermal_bridge_width 0.5)
				(island_removal_mode 0)
			)
			(polygon
				(pts
					(xy 75.5142 -15.4686) (xy 75.6666 -15.4686) (xy 75.6666 -16.0782) (xy 75.5142 -16.0782)
				)
			)
		)
		(zone
			(layer "F.Cu")
			(hatch none 0.5)
			(connect_pads
				(clearance 0)
			)
			(min_thickness 0.25)
			(keepout
				(tracks allowed)
				(vias not_allowed)
				(pads allowed)
				(copperpour not_allowed)
				(footprints allowed)
			)
			(placement
				(enabled no)
				(sheetname "")
			)
			(fill
				(thermal_gap 0.5)
				(thermal_bridge_width 0.5)
				(island_removal_mode 0)
			)
			(polygon
				(pts
					(xy 75.5142 -15.4686) (xy 75.6666 -15.4686) (xy 75.6666 -16.0782) (xy 75.5142 -16.0782)
				)
			)
		)
	)
	(footprint ""
		(layer "F.Cu")
		(at 4.073906 -32.599884)
		(property "Reference" "J1"
			(at 5.324094 -1.142746 0)
			(unlocked yes)
			(layer "F.SilkS")
			(effects
				(font
					(size 0.7874 0.5842)
					(thickness 0.1524)
				)
			)
		)
		(property "Value" ""
			(at 0 0 0)
			(layer "F.Fab")
			(effects
				(font
					(size 1.27 1.27)
				)
			)
		)
		(property "Device Type" "CONN_JACK_1P_GH4_S_TH-G200-130A"
			(at -5.098288 5.899912 0)
			(unlocked yes)
			(layer "F.Fab")
			(hide yes)
			(effects
				(font
					(size 0.7874 0.5842)
					(thickness 0.1524)
				)
			)
		)
		(property "User Part Number" "PARTNUM*"
			(at -5.098288 7.093712 0)
			(unlocked yes)
			(layer "Cmts.User")
			(hide yes)
			(effects
				(font
					(size 0.7874 0.5842)
					(thickness 0.1524)
				)
			)
		)
		(duplicate_pad_numbers_are_jumpers no)
		(fp_line
			(start -13.953998 -3.937)
			(end 3.937 -3.937)
			(stroke
				(width 0.1)
				(type default)
			)
			(layer "F.SilkS")
		)
		(fp_line
			(start -13.953998 3.937)
			(end -13.953998 -3.937)
			(stroke
				(width 0.1)
				(type default)
			)
			(layer "F.SilkS")
		)
		(fp_line
			(start 3.937 -3.937)
			(end 3.937 3.937)
			(stroke
				(width 0.1)
				(type default)
			)
			(layer "F.SilkS")
		)
		(fp_line
			(start 3.937 3.937)
			(end -13.953998 3.937)
			(stroke
				(width 0.1)
				(type default)
			)
			(layer "F.SilkS")
		)
		(fp_rect
			(start -8.763 8.763)
			(end 8.763 -8.763)
			(stroke
				(width 0)
				(type default)
			)
			(fill no)
			(layer "B.CrtYd")
		)
		(fp_rect
			(start -14.207998 4.191)
			(end 4.191 -4.191)
			(stroke
				(width 0)
				(type default)
			)
			(fill no)
			(layer "F.CrtYd")
		)
		(fp_line
			(start -13.699998 -3.599942)
			(end 3.599942 -3.599942)
			(stroke
				(width 0.1)
				(type default)
			)
			(layer "F.Fab")
		)
		(fp_line
			(start -13.699998 3.599942)
			(end -13.699998 -3.599942)
			(stroke
				(width 0.1)
				(type default)
			)
			(layer "F.Fab")
		)
		(fp_line
			(start 3.599942 -3.599942)
			(end 3.599942 3.599942)
			(stroke
				(width 0.1)
				(type default)
			)
			(layer "F.Fab")
		)
		(fp_line
			(start 3.599942 3.599942)
			(end -13.699998 3.599942)
			(stroke
				(width 0.1)
				(type default)
			)
			(layer "F.Fab")
		)
		(fp_text user "GH3"
			(at -1.533906 4.310634 0)
			(unlocked yes)
			(layer "F.SilkS")
			(effects
				(font
					(size 0.635 0.4064)
					(thickness 0.1524)
				)
			)
		)
		(fp_text user "GH1"
			(at -0.009906 -4.325366 0)
			(unlocked yes)
			(layer "F.SilkS")
			(effects
				(font
					(size 0.635 0.4064)
					(thickness 0.1524)
				)
			)
		)
		(fp_text user "GH4"
			(at 2.276094 4.437634 0)
			(unlocked yes)
			(layer "F.SilkS")
			(effects
				(font
					(size 0.635 0.4064)
					(thickness 0.1524)
				)
			)
		)
		(fp_text user "GH2"
			(at 2.54 -4.50215 0)
			(unlocked yes)
			(layer "F.SilkS")
			(effects
				(font
					(size 0.635 0.4064)
					(thickness 0.1524)
				)
			)
		)
		(fp_text user "1"
			(at 4.015994 0.000254 0)
			(unlocked yes)
			(layer "F.SilkS")
			(effects
				(font
					(size 0.7874 0.5842)
					(thickness 0.1524)
				)
				(justify left)
			)
		)
		(fp_text user "GH3"
			(at -2.803906 4.201668 0)
			(unlocked yes)
			(layer "F.Fab")
			(effects
				(font
					(size 0.7874 0.5842)
					(thickness 0.1524)
				)
			)
		)
		(fp_text user "GH1"
			(at -2.676906 -4.063746 0)
			(unlocked yes)
			(layer "F.Fab")
			(effects
				(font
					(size 0.7874 0.5842)
					(thickness 0.1524)
				)
			)
		)
		(fp_text user "GH2"
			(at 2.54 -4.57073 0)
			(unlocked yes)
			(layer "F.Fab")
			(effects
				(font
					(size 0.7874 0.5842)
					(thickness 0.1524)
				)
			)
		)
		(fp_text user "GH4"
			(at 2.657094 4.191254 0)
			(unlocked yes)
			(layer "F.Fab")
			(effects
				(font
					(size 0.7874 0.5842)
					(thickness 0.1524)
				)
			)
		)
		(fp_text user "1"
			(at 4.191 -0.35433 0)
			(unlocked yes)
			(layer "F.Fab")
			(effects
				(font
					(size 0.7874 0.5842)
					(thickness 0.1524)
				)
				(justify left)
			)
		)
		(pad "1" thru_hole circle
			(at 0 0)
			(size 2.1844 2.1844)
			(drill 1.4986)
			(layers "*.Cu" "*.Mask")
			(remove_unused_layers no)
			(net "SMA3_SIG_IO_CONN")
			(padstack
				(mode front_inner_back)
				(layer "Inner"
					(shape circle)
					(size 2.1844 2.1844)
					(clearance -0.0508)
				)
				(layer "B.Cu"
					(shape circle)
					(size 2.1844 2.1844)
				)
			)
		)
		(pad "GH1" thru_hole circle
			(at -2.54 -2.54)
			(size 2.286 2.286)
			(drill 1.6002)
			(layers "*.Cu" "*.Mask")
			(remove_unused_layers no)
			(net "SG")
			(padstack
				(mode front_inner_back)
				(layer "Inner"
					(shape circle)
					(size 2.286 2.286)
					(clearance -0.0508)
				)
				(layer "B.Cu"
					(shape circle)
					(size 2.286 2.286)
				)
			)
		)
		(pad "GH2" thru_hole circle
			(at 2.54 -2.54)
			(size 2.286 2.286)
			(drill 1.6002)
			(layers "*.Cu" "*.Mask")
			(remove_unused_layers no)
			(net "SG")
			(padstack
				(mode front_inner_back)
				(layer "Inner"
					(shape circle)
					(size 2.286 2.286)
					(clearance -0.0508)
				)
				(layer "B.Cu"
					(shape circle)
					(size 2.286 2.286)
				)
			)
		)
		(pad "GH3" thru_hole circle
			(at -2.54 2.54)
			(size 2.286 2.286)
			(drill 1.6002)
			(layers "*.Cu" "*.Mask")
			(remove_unused_layers no)
			(net "SG")
			(padstack
				(mode front_inner_back)
				(layer "Inner"
					(shape circle)
					(size 2.286 2.286)
					(clearance -0.0508)
				)
				(layer "B.Cu"
					(shape circle)
					(size 2.286 2.286)
				)
			)
		)
		(pad "GH4" thru_hole circle
			(at 2.54 2.54)
			(size 2.286 2.286)
			(drill 1.6002)
			(layers "*.Cu" "*.Mask")
			(remove_unused_layers no)
			(net "SG")
			(padstack
				(mode front_inner_back)
				(layer "Inner"
					(shape circle)
					(size 2.286 2.286)
					(clearance -0.0508)
				)
				(layer "B.Cu"
					(shape circle)
					(size 2.286 2.286)
				)
			)
		)
	)
	(footprint ""
		(layer "F.Cu")
		(at 49.784 -131.699)
		(property "Reference" "SP73"
			(at 0 0 0)
			(layer "F.SilkS")
			(hide yes)
			(effects
				(font
					(size 1.27 1.27)
				)
			)
		)
		(property "Value" ""
			(at 0 0 0)
			(layer "F.Fab")
			(effects
				(font
					(size 1.27 1.27)
				)
			)
		)
		(duplicate_pad_numbers_are_jumpers no)
	)
	(footprint ""
		(layer "F.Cu")
		(at 155.9814 -58.3946 -90)
		(property "Reference" "C40"
			(at -3.3274 -0.26797 90)
			(unlocked yes)
			(layer "F.SilkS")
			(effects
				(font
					(size 0.7874 0.5842)
					(thickness 0.1524)
				)
			)
		)
		(property "Value" "VAL*"
			(at 0.0762 2.067306 270)
			(unlocked yes)
			(layer "F.Fab")
			(hide yes)
			(effects
				(font
					(size 0.7874 0.5842)
					(thickness 0.1524)
				)
			)
		)
		(property "Device Type" "CAPACITOR-G105-0B104-EK,0.1UF,A"
			(at 0.0508 1.127506 270)
			(unlocked yes)
			(layer "F.Fab")
			(hide yes)
			(effects
				(font
					(size 0.7874 0.5842)
					(thickness 0.1524)
				)
			)
		)
		(property "User Part Number" "PARTNUM*"
			(at 0.1016 4.023106 270)
			(unlocked yes)
			(layer "Cmts.User")
			(hide yes)
			(effects
				(font
					(size 0.7874 0.5842)
					(thickness 0.1524)
				)
			)
		)
		(property "Tolerance" "TOL*"
			(at 0.0762 3.032506 270)
			(unlocked yes)
			(layer "Cmts.User")
			(hide yes)
			(effects
				(font
					(size 0.7874 0.5842)
					(thickness 0.1524)
				)
			)
		)
		(duplicate_pad_numbers_are_jumpers no)
		(fp_line
			(start -1.143 0.5588)
			(end 1.143 0.5588)
			(stroke
				(width 0.1)
				(type default)
			)
			(layer "F.SilkS")
		)
		(fp_line
			(start 1.143 0.5588)
			(end 1.143 -0.5588)
			(stroke
				(width 0.1)
				(type default)
			)
			(layer "F.SilkS")
		)
		(fp_line
			(start -1.143 -0.5588)
			(end -1.143 0.5588)
			(stroke
				(width 0.1)
				(type default)
			)
			(layer "F.SilkS")
		)
		(fp_line
			(start 1.143 -0.5588)
			(end -1.143 -0.5588)
			(stroke
				(width 0.1)
				(type default)
			)
			(layer "F.SilkS")
		)
		(fp_rect
			(start -1.143 0.5588)
			(end 1.143 -0.5588)
			(stroke
				(width 0)
				(type default)
			)
			(fill no)
			(layer "F.CrtYd")
		)
		(fp_line
			(start -0.508 0.3048)
			(end 0.508 0.3048)
			(stroke
				(width 0.1)
				(type default)
			)
			(layer "F.Fab")
		)
		(fp_line
			(start 0.508 0.3048)
			(end 0.508 -0.3048)
			(stroke
				(width 0.1)
				(type default)
			)
			(layer "F.Fab")
		)
		(fp_line
			(start -0.508 -0.3048)
			(end -0.508 0.3048)
			(stroke
				(width 0.1)
				(type default)
			)
			(layer "F.Fab")
		)
		(fp_line
			(start 0.508 -0.3048)
			(end -0.508 -0.3048)
			(stroke
				(width 0.1)
				(type default)
			)
			(layer "F.Fab")
		)
		(pad "1" smd rect
			(at -0.5334 0 270)
			(size 0.7112 0.6096)
			(layers "F.Cu" "F.Mask" "F.Paste")
			(net "XP3R3V_FPGA")
		)
		(pad "2" smd rect
			(at 0.5334 0 270)
			(size 0.7112 0.6096)
			(layers "F.Cu" "F.Mask" "F.Paste")
			(net "SG")
		)
		(zone
			(layer "F.Cu")
			(hatch none 0.5)
			(connect_pads
				(clearance 0)
			)
			(min_thickness 0.25)
			(keepout
				(tracks allowed)
				(vias not_allowed)
				(pads allowed)
				(copperpour not_allowed)
				(footprints allowed)
			)
			(placement
				(enabled no)
				(sheetname "")
			)
			(fill
				(thermal_gap 0.5)
				(thermal_bridge_width 0.5)
				(island_removal_mode 0)
			)
			(polygon
				(pts
					(xy 155.6766 -58.4708) (xy 155.6766 -58.3184) (xy 156.2862 -58.3184) (xy 156.2862 -58.4708)
				)
			)
		)
	)
	(footprint ""
		(layer "F.Cu")
		(at 135.89 -46.228 90)
		(property "Reference" "C270"
			(at 3.302 -0.35433 90)
			(unlocked yes)
			(layer "F.SilkS")
			(effects
				(font
					(size 0.7874 0.5842)
					(thickness 0.1524)
				)
			)
		)
		(property "Value" "VAL*"
			(at 0.0762 3.134106 90)
			(unlocked yes)
			(layer "F.Fab")
			(hide yes)
			(effects
				(font
					(size 0.7874 0.5842)
					(thickness 0.1524)
				)
			)
		)
		(property "Device Type" "CAPACITOR-G107-0F476-AM,47UF,2A"
			(at 0.0508 2.194306 90)
			(unlocked yes)
			(layer "F.Fab")
			(hide yes)
			(effects
				(font
					(size 0.7874 0.5842)
					(thickness 0.1524)
				)
			)
		)
		(property "User Part Number" "PARTNUM*"
			(at 0.1016 5.013706 90)
			(unlocked yes)
			(layer "Cmts.User")
			(hide yes)
			(effects
				(font
					(size 0.7874 0.5842)
					(thickness 0.1524)
				)
			)
		)
		(property "Tolerance" "TOL*"
			(at 0.0762 4.048506 90)
			(unlocked yes)
			(layer "Cmts.User")
			(hide yes)
			(effects
				(font
					(size 0.7874 0.5842)
					(thickness 0.1524)
				)
			)
		)
		(duplicate_pad_numbers_are_jumpers no)
		(fp_line
			(start 1.5748 -0.9398)
			(end -1.5748 -0.9398)
			(stroke
				(width 0.1)
				(type default)
			)
			(layer "F.SilkS")
		)
		(fp_line
			(start -1.5748 -0.9398)
			(end -1.5748 0.9398)
			(stroke
				(width 0.1)
				(type default)
			)
			(layer "F.SilkS")
		)
		(fp_line
			(start 1.5748 0.9398)
			(end 1.5748 -0.9398)
			(stroke
				(width 0.1)
				(type default)
			)
			(layer "F.SilkS")
		)
		(fp_line
			(start -1.5748 0.9398)
			(end 1.5748 0.9398)
			(stroke
				(width 0.1)
				(type default)
			)
			(layer "F.SilkS")
		)
		(fp_rect
			(start -1.5748 -0.9398)
			(end 1.5748 0.9398)
			(stroke
				(width 0)
				(type default)
			)
			(fill no)
			(layer "F.CrtYd")
		)
		(fp_line
			(start 1.016 -0.635)
			(end -1.016 -0.635)
			(stroke
				(width 0.1)
				(type default)
			)
			(layer "F.Fab")
		)
		(fp_line
			(start -1.016 -0.635)
			(end -1.016 0.635)
			(stroke
				(width 0.1)
				(type default)
			)
			(layer "F.Fab")
		)
		(fp_line
			(start 1.016 0.635)
			(end 1.016 -0.635)
			(stroke
				(width 0.1)
				(type default)
			)
			(layer "F.Fab")
		)
		(fp_line
			(start -1.016 0.635)
			(end 1.016 0.635)
			(stroke
				(width 0.1)
				(type default)
			)
			(layer "F.Fab")
		)
		(pad "1" smd rect
			(at -0.8382 0 90)
			(size 0.9652 1.3716)
			(layers "F.Cu" "F.Mask" "F.Paste")
			(net "XP1R0V_FPGA")
		)
		(pad "2" smd rect
			(at 0.8382 0 90)
			(size 0.9652 1.3716)
			(layers "F.Cu" "F.Mask" "F.Paste")
			(net "SG")
		)
		(zone
			(layer "F.Cu")
			(hatch none 0.5)
			(connect_pads
				(clearance 0)
			)
			(min_thickness 0.25)
			(keepout
				(tracks allowed)
				(vias not_allowed)
				(pads allowed)
				(copperpour not_allowed)
				(footprints allowed)
			)
			(placement
				(enabled no)
				(sheetname "")
			)
			(fill
				(thermal_gap 0.5)
				(thermal_bridge_width 0.5)
				(island_removal_mode 0)
			)
			(polygon
				(pts
					(xy 135.255 -45.9994) (xy 136.525 -45.9994) (xy 136.525 -46.4566) (xy 135.255 -46.4566)
				)
			)
		)
	)
	(footprint ""
		(layer "F.Cu")
		(at 82.296 -76.454 -90)
		(property "Reference" "TP2"
			(at 0 0 270)
			(layer "F.SilkS")
			(hide yes)
			(effects
				(font
					(size 1.27 1.27)
				)
			)
		)
		(property "Value" ""
			(at 0 0 270)
			(layer "F.Fab")
			(effects
				(font
					(size 1.27 1.27)
				)
			)
		)
		(property "Device Type" "TP_PIONT-TP010CT020B030_PTH-TPA"
			(at -1.341882 0.996696 270)
			(unlocked yes)
			(layer "F.Fab")
			(hide yes)
			(effects
				(font
					(size 0.7874 0.5842)
					(thickness 0.1524)
				)
				(justify left)
			)
		)
		(duplicate_pad_numbers_are_jumpers no)
		(fp_poly
			(pts
				(arc
					(start 0 -0.889)
					(mid 0 0.889)
					(end 0 -0.889)
				)
			)
			(stroke
				(width 0)
				(type default)
			)
			(fill no)
			(layer "B.CrtYd")
		)
		(fp_poly
			(pts
				(arc
					(start 0 -0.889)
					(mid 0 0.889)
					(end 0 -0.889)
				)
			)
			(stroke
				(width 0)
				(type default)
			)
			(fill no)
			(layer "F.CrtYd")
		)
		(pad "1" thru_hole circle
			(at 0 0 270)
			(size 0.508 0.508)
			(drill 0.254)
			(layers "*.Cu" "*.Mask")
			(remove_unused_layers no)
			(net "BNO080_EVN_SCL")
			(clearance 0.1016)
			(padstack
				(mode front_inner_back)
				(layer "Inner"
					(shape circle)
					(size 0.508 0.508)
					(clearance 0.1016)
				)
				(layer "B.Cu"
					(shape circle)
					(size 0.762 0.762)
					(clearance -0.0254)
				)
			)
		)
	)
	(footprint ""
		(layer "F.Cu")
		(at 138.303 -20.193)
		(property "Reference" "TP57"
			(at -2.6162 1.43637 0)
			(unlocked yes)
			(layer "F.SilkS")
			(effects
				(font
					(size 0.7874 0.5842)
					(thickness 0.1524)
				)
				(justify left)
			)
		)
		(property "Value" ""
			(at 0 0 0)
			(layer "F.Fab")
			(effects
				(font
					(size 1.27 1.27)
				)
			)
		)
		(property "Device Type" "TP_PIONT-TP010CT020B030_PTH-TPA"
			(at -1.341882 0.996696 0)
			(unlocked yes)
			(layer "F.Fab")
			(hide yes)
			(effects
				(font
					(size 0.7874 0.5842)
					(thickness 0.1524)
				)
				(justify left)
			)
		)
		(duplicate_pad_numbers_are_jumpers no)
		(fp_poly
			(pts
				(arc
					(start 0.889 0)
					(mid -0.889 0)
					(end 0.889 0)
				)
			)
			(stroke
				(width 0)
				(type default)
			)
			(fill no)
			(layer "B.CrtYd")
		)
		(fp_poly
			(pts
				(arc
					(start 0.889 0)
					(mid -0.889 0)
					(end 0.889 0)
				)
			)
			(stroke
				(width 0)
				(type default)
			)
			(fill no)
			(layer "F.CrtYd")
		)
		(pad "1" thru_hole circle
			(at 0 0)
			(size 0.508 0.508)
			(drill 0.254)
			(layers "*.Cu" "*.Mask")
			(remove_unused_layers no)
			(net "XP2R5V_FPGA")
			(clearance 0.1016)
			(padstack
				(mode front_inner_back)
				(layer "Inner"
					(shape circle)
					(size 0.508 0.508)
					(clearance 0.1016)
				)
				(layer "B.Cu"
					(shape circle)
					(size 0.762 0.762)
					(clearance -0.0254)
				)
			)
		)
	)
	(footprint ""
		(layer "F.Cu")
		(at 26.035 -75.184 90)
		(property "Reference" "R480"
			(at -3.175 0.54737 90)
			(unlocked yes)
			(layer "F.SilkS")
			(effects
				(font
					(size 0.7874 0.5842)
					(thickness 0.1524)
				)
			)
		)
		(property "Value" "VAL*"
			(at 0.02032 2.13233 90)
			(unlocked yes)
			(layer "F.Fab")
			(hide yes)
			(effects
				(font
					(size 0.7874 0.5842)
					(thickness 0.1524)
				)
			)
		)
		(property "Tolerance" "TOL*"
			(at 0.044704 3.05435 90)
			(unlocked yes)
			(layer "Cmts.User")
			(hide yes)
			(effects
				(font
					(size 0.7874 0.5842)
					(thickness 0.1524)
				)
			)
		)
		(property "User Part Number" "PARTNUM*"
			(at 0.02032 4.024884 90)
			(unlocked yes)
			(layer "Cmts.User")
			(hide yes)
			(effects
				(font
					(size 0.7874 0.5842)
					(thickness 0.1524)
				)
			)
		)
		(property "Device Type" "RESISTOR-G155-11003-01,100KOHMA"
			(at 0.008382 1.210564 90)
			(unlocked yes)
			(layer "F.Fab")
			(hide yes)
			(effects
				(font
					(size 0.7874 0.5842)
					(thickness 0.1524)
				)
			)
		)
		(duplicate_pad_numbers_are_jumpers no)
		(fp_line
			(start 1.143 -0.5588)
			(end -1.143 -0.5588)
			(stroke
				(width 0.1)
				(type default)
			)
			(layer "F.SilkS")
		)
		(fp_line
			(start -1.143 -0.5588)
			(end -1.143 0.5588)
			(stroke
				(width 0.1)
				(type default)
			)
			(layer "F.SilkS")
		)
		(fp_line
			(start 1.143 0.5588)
			(end 1.143 -0.5588)
			(stroke
				(width 0.1)
				(type default)
			)
			(layer "F.SilkS")
		)
		(fp_line
			(start -1.143 0.5588)
			(end 1.143 0.5588)
			(stroke
				(width 0.1)
				(type default)
			)
			(layer "F.SilkS")
		)
		(fp_poly
			(pts
				(xy -1.143 0.5588) (xy 1.143 0.5588) (xy 1.143 -0.5588) (xy -1.143 -0.5588)
			)
			(stroke
				(width 0)
				(type default)
			)
			(fill no)
			(layer "F.CrtYd")
		)
		(fp_line
			(start 0.508 -0.3048)
			(end -0.508 -0.3048)
			(stroke
				(width 0.1)
				(type default)
			)
			(layer "F.Fab")
		)
		(fp_line
			(start -0.508 -0.3048)
			(end -0.508 0.3048)
			(stroke
				(width 0.1)
				(type default)
			)
			(layer "F.Fab")
		)
		(fp_line
			(start 0.508 0.3048)
			(end 0.508 -0.3048)
			(stroke
				(width 0.1)
				(type default)
			)
			(layer "F.Fab")
		)
		(fp_line
			(start -0.508 0.3048)
			(end 0.508 0.3048)
			(stroke
				(width 0.1)
				(type default)
			)
			(layer "F.Fab")
		)
		(pad "1" smd rect
			(at -0.5334 0 90)
			(size 0.7112 0.6096)
			(layers "F.Cu" "F.Mask" "F.Paste")
			(net "UART_FT4232_TX_FPGA_RX")
		)
		(pad "2" smd rect
			(at 0.5334 0 90)
			(size 0.7112 0.6096)
			(layers "F.Cu" "F.Mask" "F.Paste")
			(net "XP3R3V_FT4232")
		)
		(zone
			(layer "F.Cu")
			(hatch none 0.5)
			(connect_pads
				(clearance 0)
			)
			(min_thickness 0.25)
			(keepout
				(tracks allowed)
				(vias not_allowed)
				(pads allowed)
				(copperpour not_allowed)
				(footprints allowed)
			)
			(placement
				(enabled no)
				(sheetname "")
			)
			(fill
				(thermal_gap 0.5)
				(thermal_bridge_width 0.5)
				(island_removal_mode 0)
			)
			(polygon
				(pts
					(xy 26.3398 -75.1078) (xy 26.3398 -75.2602) (xy 25.7302 -75.2602) (xy 25.7302 -75.1078)
				)
			)
		)
		(zone
			(layer "F.Cu")
			(hatch none 0.5)
			(connect_pads
				(clearance 0)
			)
			(min_thickness 0.25)
			(keepout
				(tracks not_allowed)
				(vias allowed)
				(pads allowed)
				(copperpour not_allowed)
				(footprints allowed)
			)
			(placement
				(enabled no)
				(sheetname "")
			)
			(fill
				(thermal_gap 0.5)
				(thermal_bridge_width 0.5)
				(island_removal_mode 0)
			)
			(polygon
				(pts
					(xy 26.3398 -75.1078) (xy 26.3398 -75.2602) (xy 25.7302 -75.2602) (xy 25.7302 -75.1078)
				)
			)
		)
	)
	(footprint ""
		(layer "F.Cu")
		(at 39.3192 -16.31188 90)
		(property "Reference" "C17"
			(at -3.10388 0.21717 90)
			(unlocked yes)
			(layer "F.SilkS")
			(effects
				(font
					(size 0.7874 0.5842)
					(thickness 0.1524)
				)
			)
		)
		(property "Value" "VAL*"
			(at 0.0762 2.067306 90)
			(unlocked yes)
			(layer "F.Fab")
			(hide yes)
			(effects
				(font
					(size 0.7874 0.5842)
					(thickness 0.1524)
				)
			)
		)
		(property "Tolerance" "TOL*"
			(at 0.0762 3.032506 90)
			(unlocked yes)
			(layer "Cmts.User")
			(hide yes)
			(effects
				(font
					(size 0.7874 0.5842)
					(thickness 0.1524)
				)
			)
		)
		(property "User Part Number" "PARTNUM*"
			(at 0.1016 4.023106 90)
			(unlocked yes)
			(layer "Cmts.User")
			(hide yes)
			(effects
				(font
					(size 0.7874 0.5842)
					(thickness 0.1524)
				)
			)
		)
		(property "Device Type" "CAPACITOR-G105-0B104-CK,0.1UF,A"
			(at 0.0508 1.127506 90)
			(unlocked yes)
			(layer "F.Fab")
			(hide yes)
			(effects
				(font
					(size 0.7874 0.5842)
					(thickness 0.1524)
				)
			)
		)
		(duplicate_pad_numbers_are_jumpers no)
		(fp_line
			(start 1.143 -0.5588)
			(end -1.143 -0.5588)
			(stroke
				(width 0.1)
				(type default)
			)
			(layer "F.SilkS")
		)
		(fp_line
			(start -1.143 -0.5588)
			(end -1.143 0.5588)
			(stroke
				(width 0.1)
				(type default)
			)
			(layer "F.SilkS")
		)
		(fp_line
			(start 1.143 0.5588)
			(end 1.143 -0.5588)
			(stroke
				(width 0.1)
				(type default)
			)
			(layer "F.SilkS")
		)
		(fp_line
			(start -1.143 0.5588)
			(end 1.143 0.5588)
			(stroke
				(width 0.1)
				(type default)
			)
			(layer "F.SilkS")
		)
		(fp_rect
			(start -1.143 -0.5588)
			(end 1.143 0.5588)
			(stroke
				(width 0)
				(type default)
			)
			(fill no)
			(layer "F.CrtYd")
		)
		(fp_line
			(start 0.508 -0.3048)
			(end -0.508 -0.3048)
			(stroke
				(width 0.1)
				(type default)
			)
			(layer "F.Fab")
		)
		(fp_line
			(start -0.508 -0.3048)
			(end -0.508 0.3048)
			(stroke
				(width 0.1)
				(type default)
			)
			(layer "F.Fab")
		)
		(fp_line
			(start 0.508 0.3048)
			(end 0.508 -0.3048)
			(stroke
				(width 0.1)
				(type default)
			)
			(layer "F.Fab")
		)
		(fp_line
			(start -0.508 0.3048)
			(end 0.508 0.3048)
			(stroke
				(width 0.1)
				(type default)
			)
			(layer "F.Fab")
		)
		(pad "1" smd rect
			(at -0.5334 0 90)
			(size 0.7112 0.6096)
			(layers "F.Cu" "F.Mask" "F.Paste")
			(net "XP3R3V_FPGA")
		)
		(pad "2" smd rect
			(at 0.5334 0 90)
			(size 0.7112 0.6096)
			(layers "F.Cu" "F.Mask" "F.Paste")
			(net "SG")
		)
		(zone
			(layer "F.Cu")
			(hatch none 0.5)
			(connect_pads
				(clearance 0)
			)
			(min_thickness 0.25)
			(keepout
				(tracks allowed)
				(vias not_allowed)
				(pads allowed)
				(copperpour not_allowed)
				(footprints allowed)
			)
			(placement
				(enabled no)
				(sheetname "")
			)
			(fill
				(thermal_gap 0.5)
				(thermal_bridge_width 0.5)
				(island_removal_mode 0)
			)
			(polygon
				(pts
					(xy 39.0144 -16.23568) (xy 39.624 -16.23568) (xy 39.624 -16.38808) (xy 39.0144 -16.38808)
				)
			)
		)
	)
	(footprint ""
		(layer "F.Cu")
		(at 16.256 -57.15 -90)
		(property "Reference" "C85"
			(at 2.286 -0.54737 90)
			(unlocked yes)
			(layer "F.SilkS")
			(effects
				(font
					(size 0.7874 0.5842)
					(thickness 0.1524)
				)
			)
		)
		(property "Value" "VAL*"
			(at 0.0762 2.067306 270)
			(unlocked yes)
			(layer "F.Fab")
			(hide yes)
			(effects
				(font
					(size 0.7874 0.5842)
					(thickness 0.1524)
				)
			)
		)
		(property "Device Type" "CAPACITOR-G105-0B104-CK,0.1UF,A"
			(at 0.0508 1.127506 270)
			(unlocked yes)
			(layer "F.Fab")
			(hide yes)
			(effects
				(font
					(size 0.7874 0.5842)
					(thickness 0.1524)
				)
			)
		)
		(property "User Part Number" "PARTNUM*"
			(at 0.1016 4.023106 270)
			(unlocked yes)
			(layer "Cmts.User")
			(hide yes)
			(effects
				(font
					(size 0.7874 0.5842)
					(thickness 0.1524)
				)
			)
		)
		(property "Tolerance" "TOL*"
			(at 0.0762 3.032506 270)
			(unlocked yes)
			(layer "Cmts.User")
			(hide yes)
			(effects
				(font
					(size 0.7874 0.5842)
					(thickness 0.1524)
				)
			)
		)
		(duplicate_pad_numbers_are_jumpers no)
		(fp_line
			(start -1.143 0.5588)
			(end 1.143 0.5588)
			(stroke
				(width 0.1)
				(type default)
			)
			(layer "F.SilkS")
		)
		(fp_line
			(start 1.143 0.5588)
			(end 1.143 -0.5588)
			(stroke
				(width 0.1)
				(type default)
			)
			(layer "F.SilkS")
		)
		(fp_line
			(start -1.143 -0.5588)
			(end -1.143 0.5588)
			(stroke
				(width 0.1)
				(type default)
			)
			(layer "F.SilkS")
		)
		(fp_line
			(start 1.143 -0.5588)
			(end -1.143 -0.5588)
			(stroke
				(width 0.1)
				(type default)
			)
			(layer "F.SilkS")
		)
		(fp_rect
			(start -1.143 -0.5588)
			(end 1.143 0.5588)
			(stroke
				(width 0)
				(type default)
			)
			(fill no)
			(layer "F.CrtYd")
		)
		(fp_line
			(start -0.508 0.3048)
			(end 0.508 0.3048)
			(stroke
				(width 0.1)
				(type default)
			)
			(layer "F.Fab")
		)
		(fp_line
			(start 0.508 0.3048)
			(end 0.508 -0.3048)
			(stroke
				(width 0.1)
				(type default)
			)
			(layer "F.Fab")
		)
		(fp_line
			(start -0.508 -0.3048)
			(end -0.508 0.3048)
			(stroke
				(width 0.1)
				(type default)
			)
			(layer "F.Fab")
		)
		(fp_line
			(start 0.508 -0.3048)
			(end -0.508 -0.3048)
			(stroke
				(width 0.1)
				(type default)
			)
			(layer "F.Fab")
		)
		(pad "1" smd rect
			(at -0.5334 0 270)
			(size 0.7112 0.6096)
			(layers "F.Cu" "F.Mask" "F.Paste")
			(net "XP3R3V_FPGA")
		)
		(pad "2" smd rect
			(at 0.5334 0 270)
			(size 0.7112 0.6096)
			(layers "F.Cu" "F.Mask" "F.Paste")
			(net "SG")
		)
		(zone
			(layer "F.Cu")
			(hatch none 0.5)
			(connect_pads
				(clearance 0)
			)
			(min_thickness 0.25)
			(keepout
				(tracks allowed)
				(vias not_allowed)
				(pads allowed)
				(copperpour not_allowed)
				(footprints allowed)
			)
			(placement
				(enabled no)
				(sheetname "")
			)
			(fill
				(thermal_gap 0.5)
				(thermal_bridge_width 0.5)
				(island_removal_mode 0)
			)
			(polygon
				(pts
					(xy 16.5608 -57.2262) (xy 15.9512 -57.2262) (xy 15.9512 -57.0738) (xy 16.5608 -57.0738)
				)
			)
		)
	)
	(footprint ""
		(layer "F.Cu")
		(at 80.772 -58.3946 180)
		(property "Reference" "R78"
			(at 10.668 19.39163 0)
			(unlocked yes)
			(layer "F.SilkS")
			(effects
				(font
					(size 0.7874 0.5842)
					(thickness 0.1524)
				)
			)
		)
		(property "Value" "VAL*"
			(at 0.02032 2.13233 180)
			(unlocked yes)
			(layer "F.Fab")
			(hide yes)
			(effects
				(font
					(size 0.7874 0.5842)
					(thickness 0.1524)
				)
			)
		)
		(property "Tolerance" "TOL*"
			(at 0.044704 3.05435 180)
			(unlocked yes)
			(layer "Cmts.User")
			(hide yes)
			(effects
				(font
					(size 0.7874 0.5842)
					(thickness 0.1524)
				)
			)
		)
		(property "User Part Number" "PARTNUM*"
			(at 0.02032 4.024884 180)
			(unlocked yes)
			(layer "Cmts.User")
			(hide yes)
			(effects
				(font
					(size 0.7874 0.5842)
					(thickness 0.1524)
				)
			)
		)
		(property "Device Type" "RESISTOR-G155-133R0-01,33OHM,1%"
			(at 0.008382 1.210564 180)
			(unlocked yes)
			(layer "F.Fab")
			(hide yes)
			(effects
				(font
					(size 0.7874 0.5842)
					(thickness 0.1524)
				)
			)
		)
		(duplicate_pad_numbers_are_jumpers no)
		(fp_line
			(start 1.143 0.5588)
			(end 1.143 -0.5588)
			(stroke
				(width 0.1)
				(type default)
			)
			(layer "F.SilkS")
		)
		(fp_line
			(start 1.143 -0.5588)
			(end -1.143 -0.5588)
			(stroke
				(width 0.1)
				(type default)
			)
			(layer "F.SilkS")
		)
		(fp_line
			(start -1.143 0.5588)
			(end 1.143 0.5588)
			(stroke
				(width 0.1)
				(type default)
			)
			(layer "F.SilkS")
		)
		(fp_line
			(start -1.143 -0.5588)
			(end -1.143 0.5588)
			(stroke
				(width 0.1)
				(type default)
			)
			(layer "F.SilkS")
		)
		(fp_rect
			(start 1.143 -0.5588)
			(end -1.143 0.5588)
			(stroke
				(width 0)
				(type default)
			)
			(fill no)
			(layer "F.CrtYd")
		)
		(fp_line
			(start 0.508 0.3048)
			(end 0.508 -0.3048)
			(stroke
				(width 0.1)
				(type default)
			)
			(layer "F.Fab")
		)
		(fp_line
			(start 0.508 -0.3048)
			(end -0.508 -0.3048)
			(stroke
				(width 0.1)
				(type default)
			)
			(layer "F.Fab")
		)
		(fp_line
			(start -0.508 0.3048)
			(end 0.508 0.3048)
			(stroke
				(width 0.1)
				(type default)
			)
			(layer "F.Fab")
		)
		(fp_line
			(start -0.508 -0.3048)
			(end -0.508 0.3048)
			(stroke
				(width 0.1)
				(type default)
			)
			(layer "F.Fab")
		)
		(pad "1" smd rect
			(at -0.5334 0 180)
			(size 0.7112 0.6096)
			(layers "F.Cu" "F.Mask" "F.Paste")
			(net "R_BNO080_RST_N")
		)
		(pad "2" smd rect
			(at 0.5334 0 180)
			(size 0.7112 0.6096)
			(layers "F.Cu" "F.Mask" "F.Paste")
			(net "FPGA_OUT_BNO080_RST_N")
		)
		(zone
			(layer "F.Cu")
			(hatch none 0.5)
			(connect_pads
				(clearance 0)
			)
			(min_thickness 0.25)
			(keepout
				(tracks allowed)
				(vias not_allowed)
				(pads allowed)
				(copperpour not_allowed)
				(footprints allowed)
			)
			(placement
				(enabled no)
				(sheetname "")
			)
			(fill
				(thermal_gap 0.5)
				(thermal_bridge_width 0.5)
				(island_removal_mode 0)
			)
			(polygon
				(pts
					(xy 80.6958 -58.0898) (xy 80.8482 -58.0898) (xy 80.8482 -58.6994) (xy 80.6958 -58.6994)
				)
			)
		)
	)
	(footprint ""
		(layer "F.Cu")
		(at 133.096 -31.496)
		(property "Reference" "C173"
			(at 4.572 0.29337 0)
			(unlocked yes)
			(layer "F.SilkS")
			(effects
				(font
					(size 0.7874 0.5842)
					(thickness 0.1524)
				)
			)
		)
		(property "Value" "VAL*"
			(at 0.0762 3.134106 0)
			(unlocked yes)
			(layer "F.Fab")
			(hide yes)
			(effects
				(font
					(size 0.7874 0.5842)
					(thickness 0.1524)
				)
			)
		)
		(property "Tolerance" "TOL*"
			(at 0.0762 4.048506 0)
			(unlocked yes)
			(layer "Cmts.User")
			(hide yes)
			(effects
				(font
					(size 0.7874 0.5842)
					(thickness 0.1524)
				)
			)
		)
		(property "User Part Number" "PARTNUM*"
			(at 0.1016 5.013706 0)
			(unlocked yes)
			(layer "Cmts.User")
			(hide yes)
			(effects
				(font
					(size 0.7874 0.5842)
					(thickness 0.1524)
				)
			)
		)
		(property "Device Type" "CAPACITOR-G107-0F476-AM,47UF,2A"
			(at 0.0508 2.194306 0)
			(unlocked yes)
			(layer "F.Fab")
			(hide yes)
			(effects
				(font
					(size 0.7874 0.5842)
					(thickness 0.1524)
				)
			)
		)
		(duplicate_pad_numbers_are_jumpers no)
		(fp_line
			(start -1.5748 -0.9398)
			(end -1.5748 0.9398)
			(stroke
				(width 0.1)
				(type default)
			)
			(layer "F.SilkS")
		)
		(fp_line
			(start -1.5748 0.9398)
			(end 1.5748 0.9398)
			(stroke
				(width 0.1)
				(type default)
			)
			(layer "F.SilkS")
		)
		(fp_line
			(start 1.5748 -0.9398)
			(end -1.5748 -0.9398)
			(stroke
				(width 0.1)
				(type default)
			)
			(layer "F.SilkS")
		)
		(fp_line
			(start 1.5748 0.9398)
			(end 1.5748 -0.9398)
			(stroke
				(width 0.1)
				(type default)
			)
			(layer "F.SilkS")
		)
		(fp_rect
			(start 1.5748 -0.9398)
			(end -1.5748 0.9398)
			(stroke
				(width 0)
				(type default)
			)
			(fill no)
			(layer "F.CrtYd")
		)
		(fp_line
			(start -1.016 -0.635)
			(end -1.016 0.635)
			(stroke
				(width 0.1)
				(type default)
			)
			(layer "F.Fab")
		)
		(fp_line
			(start -1.016 0.635)
			(end 1.016 0.635)
			(stroke
				(width 0.1)
				(type default)
			)
			(layer "F.Fab")
		)
		(fp_line
			(start 1.016 -0.635)
			(end -1.016 -0.635)
			(stroke
				(width 0.1)
				(type default)
			)
			(layer "F.Fab")
		)
		(fp_line
			(start 1.016 0.635)
			(end 1.016 -0.635)
			(stroke
				(width 0.1)
				(type default)
			)
			(layer "F.Fab")
		)
		(pad "1" smd rect
			(at -0.8382 0)
			(size 0.9652 1.3716)
			(layers "F.Cu" "F.Mask" "F.Paste")
			(net "XP1R0V_FPGA_VCCINT")
		)
		(pad "2" smd rect
			(at 0.8382 0)
			(size 0.9652 1.3716)
			(layers "F.Cu" "F.Mask" "F.Paste")
			(net "SG")
		)
		(zone
			(layer "F.Cu")
			(hatch none 0.5)
			(connect_pads
				(clearance 0)
			)
			(min_thickness 0.25)
			(keepout
				(tracks allowed)
				(vias not_allowed)
				(pads allowed)
				(copperpour not_allowed)
				(footprints allowed)
			)
			(placement
				(enabled no)
				(sheetname "")
			)
			(fill
				(thermal_gap 0.5)
				(thermal_bridge_width 0.5)
				(island_removal_mode 0)
			)
			(polygon
				(pts
					(xy 133.3246 -32.131) (xy 132.8674 -32.131) (xy 132.8674 -30.861) (xy 133.3246 -30.861)
				)
			)
		)
	)
	(footprint ""
		(layer "F.Cu")
		(at 31.75 -95.25 180)
		(property "Reference" "R455"
			(at -2.667 -1.69037 0)
			(unlocked yes)
			(layer "F.SilkS")
			(effects
				(font
					(size 0.7874 0.5842)
					(thickness 0.1524)
				)
			)
		)
		(property "Value" "VAL*"
			(at 0.02032 2.13233 180)
			(unlocked yes)
			(layer "F.Fab")
			(hide yes)
			(effects
				(font
					(size 0.7874 0.5842)
					(thickness 0.1524)
				)
			)
		)
		(property "Tolerance" "TOL*"
			(at 0.044704 3.05435 180)
			(unlocked yes)
			(layer "Cmts.User")
			(hide yes)
			(effects
				(font
					(size 0.7874 0.5842)
					(thickness 0.1524)
				)
			)
		)
		(property "User Part Number" "PARTNUM*"
			(at 0.02032 4.024884 180)
			(unlocked yes)
			(layer "Cmts.User")
			(hide yes)
			(effects
				(font
					(size 0.7874 0.5842)
					(thickness 0.1524)
				)
			)
		)
		(property "Device Type" "RESISTOR-G155-11004-01,1MOHM,1%"
			(at 0.008382 1.210564 180)
			(unlocked yes)
			(layer "F.Fab")
			(hide yes)
			(effects
				(font
					(size 0.7874 0.5842)
					(thickness 0.1524)
				)
			)
		)
		(duplicate_pad_numbers_are_jumpers no)
		(fp_line
			(start 1.143 0.5588)
			(end 1.143 -0.5588)
			(stroke
				(width 0.1)
				(type default)
			)
			(layer "F.SilkS")
		)
		(fp_line
			(start 1.143 -0.5588)
			(end -1.143 -0.5588)
			(stroke
				(width 0.1)
				(type default)
			)
			(layer "F.SilkS")
		)
		(fp_line
			(start -1.143 0.5588)
			(end 1.143 0.5588)
			(stroke
				(width 0.1)
				(type default)
			)
			(layer "F.SilkS")
		)
		(fp_line
			(start -1.143 -0.5588)
			(end -1.143 0.5588)
			(stroke
				(width 0.1)
				(type default)
			)
			(layer "F.SilkS")
		)
		(fp_poly
			(pts
				(xy -1.143 0.5588) (xy 1.143 0.5588) (xy 1.143 -0.5588) (xy -1.143 -0.5588)
			)
			(stroke
				(width 0)
				(type default)
			)
			(fill no)
			(layer "F.CrtYd")
		)
		(fp_line
			(start 0.508 0.3048)
			(end 0.508 -0.3048)
			(stroke
				(width 0.1)
				(type default)
			)
			(layer "F.Fab")
		)
		(fp_line
			(start 0.508 -0.3048)
			(end -0.508 -0.3048)
			(stroke
				(width 0.1)
				(type default)
			)
			(layer "F.Fab")
		)
		(fp_line
			(start -0.508 0.3048)
			(end 0.508 0.3048)
			(stroke
				(width 0.1)
				(type default)
			)
			(layer "F.Fab")
		)
		(fp_line
			(start -0.508 -0.3048)
			(end -0.508 0.3048)
			(stroke
				(width 0.1)
				(type default)
			)
			(layer "F.Fab")
		)
		(pad "1" smd rect
			(at -0.5334 0 180)
			(size 0.7112 0.6096)
			(layers "F.Cu" "F.Mask" "F.Paste")
			(net "UNNAMED_524_CAPACITOR_I7_2")
		)
		(pad "2" smd rect
			(at 0.5334 0 180)
			(size 0.7112 0.6096)
			(layers "F.Cu" "F.Mask" "F.Paste")
			(net "UNNAMED_524_CAPACITOR_I10_2")
		)
		(zone
			(layer "F.Cu")
			(hatch none 0.5)
			(connect_pads
				(clearance 0)
			)
			(min_thickness 0.25)
			(keepout
				(tracks allowed)
				(vias not_allowed)
				(pads allowed)
				(copperpour not_allowed)
				(footprints allowed)
			)
			(placement
				(enabled no)
				(sheetname "")
			)
			(fill
				(thermal_gap 0.5)
				(thermal_bridge_width 0.5)
				(island_removal_mode 0)
			)
			(polygon
				(pts
					(xy 31.8262 -95.5548) (xy 31.6738 -95.5548) (xy 31.6738 -94.9452) (xy 31.8262 -94.9452)
				)
			)
		)
		(zone
			(layer "F.Cu")
			(hatch none 0.5)
			(connect_pads
				(clearance 0)
			)
			(min_thickness 0.25)
			(keepout
				(tracks not_allowed)
				(vias allowed)
				(pads allowed)
				(copperpour not_allowed)
				(footprints allowed)
			)
			(placement
				(enabled no)
				(sheetname "")
			)
			(fill
				(thermal_gap 0.5)
				(thermal_bridge_width 0.5)
				(island_removal_mode 0)
			)
			(polygon
				(pts
					(xy 31.8262 -95.5548) (xy 31.6738 -95.5548) (xy 31.6738 -94.9452) (xy 31.8262 -94.9452)
				)
			)
		)
	)
	(footprint ""
		(layer "F.Cu")
		(at 122.6312 -28.0162 90)
		(property "Reference" "TP194"
			(at -1.37795 -0.635 0)
			(unlocked yes)
			(layer "F.SilkS")
			(effects
				(font
					(size 0.635 0.4064)
					(thickness 0.1524)
				)
				(justify left)
			)
		)
		(property "Value" ""
			(at 0 0 90)
			(layer "F.Fab")
			(effects
				(font
					(size 1.27 1.27)
				)
			)
		)
		(property "Device Type" "TP_PIONT-TP010CT020B030_PTH-TPA"
			(at -1.341882 0.996696 90)
			(unlocked yes)
			(layer "F.Fab")
			(hide yes)
			(effects
				(font
					(size 0.7874 0.5842)
					(thickness 0.1524)
				)
				(justify left)
			)
		)
		(duplicate_pad_numbers_are_jumpers no)
		(fp_poly
			(pts
				(arc
					(start 0 0.889)
					(mid 0 -0.889)
					(end 0 0.889)
				)
			)
			(stroke
				(width 0)
				(type default)
			)
			(fill no)
			(layer "B.CrtYd")
		)
		(fp_poly
			(pts
				(arc
					(start 0 0.889)
					(mid 0 -0.889)
					(end 0 0.889)
				)
			)
			(stroke
				(width 0)
				(type default)
			)
			(fill no)
			(layer "F.CrtYd")
		)
		(pad "1" thru_hole circle
			(at 0 0 90)
			(size 0.508 0.508)
			(drill 0.254)
			(layers "*.Cu" "*.Mask")
			(remove_unused_layers no)
			(net "IO_L21N_35")
			(clearance 0.1016)
			(padstack
				(mode front_inner_back)
				(layer "Inner"
					(shape circle)
					(size 0.508 0.508)
					(clearance 0.1016)
				)
				(layer "B.Cu"
					(shape circle)
					(size 0.762 0.762)
					(clearance -0.0254)
				)
			)
		)
	)
	(footprint ""
		(layer "F.Cu")
		(at 142.4432 -71.6534 90)
		(property "Reference" "J14"
			(at 7.17423 0.4318 0)
			(unlocked yes)
			(layer "F.SilkS")
			(effects
				(font
					(size 0.7874 0.5842)
					(thickness 0.1524)
				)
			)
		)
		(property "Value" ""
			(at 0 0 90)
			(layer "F.Fab")
			(effects
				(font
					(size 1.27 1.27)
				)
			)
		)
		(property "User Part Number" "PARTNUM*"
			(at 0.191262 6.403086 90)
			(unlocked yes)
			(layer "Cmts.User")
			(hide yes)
			(effects
				(font
					(size 0.7874 0.5842)
					(thickness 0.1524)
				)
			)
		)
		(property "Device Type" "G200_10283_01-G200-10283-01"
			(at 0.241808 5.437378 90)
			(unlocked yes)
			(layer "F.Fab")
			(hide yes)
			(effects
				(font
					(size 0.7874 0.5842)
					(thickness 0.1524)
				)
			)
		)
		(duplicate_pad_numbers_are_jumpers no)
		(fp_line
			(start 6.4008 -4.6355)
			(end 6.4008 4.6355)
			(stroke
				(width 0.1)
				(type default)
			)
			(layer "F.SilkS")
		)
		(fp_line
			(start -6.4008 -4.6355)
			(end 6.4008 -4.6355)
			(stroke
				(width 0.1)
				(type default)
			)
			(layer "F.SilkS")
		)
		(fp_line
			(start 6.4008 4.6355)
			(end -6.4008 4.6355)
			(stroke
				(width 0.1)
				(type default)
			)
			(layer "F.SilkS")
		)
		(fp_line
			(start -6.4008 4.6355)
			(end -6.4008 -4.6355)
			(stroke
				(width 0.1)
				(type default)
			)
			(layer "F.SilkS")
		)
		(fp_rect
			(start 6.6548 -4.8895)
			(end -6.6548 4.8895)
			(stroke
				(width 0)
				(type default)
			)
			(fill no)
			(layer "F.CrtYd")
		)
		(fp_line
			(start 5.386832 -3.7084)
			(end 5.386832 -2.436876)
			(stroke
				(width 0.1)
				(type default)
			)
			(layer "F.Fab")
		)
		(fp_line
			(start 4.746752 -3.7084)
			(end 5.386832 -3.7084)
			(stroke
				(width 0.1)
				(type default)
			)
			(layer "F.Fab")
		)
		(fp_line
			(start 2.872232 -3.7084)
			(end 2.872232 -2.436876)
			(stroke
				(width 0.1)
				(type default)
			)
			(layer "F.Fab")
		)
		(fp_line
			(start 2.232152 -3.7084)
			(end 2.872232 -3.7084)
			(stroke
				(width 0.1)
				(type default)
			)
			(layer "F.Fab")
		)
		(fp_line
			(start 0.306832 -3.7084)
			(end 0.306832 -2.436876)
			(stroke
				(width 0.1)
				(type default)
			)
			(layer "F.Fab")
		)
		(fp_line
			(start -0.333248 -3.7084)
			(end 0.306832 -3.7084)
			(stroke
				(width 0.1)
				(type default)
			)
			(layer "F.Fab")
		)
		(fp_line
			(start -2.233168 -3.7084)
			(end -2.233168 -2.436876)
			(stroke
				(width 0.1)
				(type default)
			)
			(layer "F.Fab")
		)
		(fp_line
			(start -2.873248 -3.7084)
			(end -2.233168 -3.7084)
			(stroke
				(width 0.1)
				(type default)
			)
			(layer "F.Fab")
		)
		(fp_line
			(start -4.773168 -3.7084)
			(end -4.773168 -2.436876)
			(stroke
				(width 0.1)
				(type default)
			)
			(layer "F.Fab")
		)
		(fp_line
			(start -5.413248 -3.7084)
			(end -4.773168 -3.7084)
			(stroke
				(width 0.1)
				(type default)
			)
			(layer "F.Fab")
		)
		(fp_line
			(start 6.145022 -2.4384)
			(end 6.145022 2.4384)
			(stroke
				(width 0.1)
				(type default)
			)
			(layer "F.Fab")
		)
		(fp_line
			(start -6.145022 -2.4384)
			(end 6.145022 -2.4384)
			(stroke
				(width 0.1)
				(type default)
			)
			(layer "F.Fab")
		)
		(fp_line
			(start 5.386832 -2.436876)
			(end 4.746752 -2.436876)
			(stroke
				(width 0.1)
				(type default)
			)
			(layer "F.Fab")
		)
		(fp_line
			(start 4.746752 -2.436876)
			(end 4.746752 -3.7084)
			(stroke
				(width 0.1)
				(type default)
			)
			(layer "F.Fab")
		)
		(fp_line
			(start 2.872232 -2.436876)
			(end 2.232152 -2.436876)
			(stroke
				(width 0.1)
				(type default)
			)
			(layer "F.Fab")
		)
		(fp_line
			(start 2.232152 -2.436876)
			(end 2.232152 -3.7084)
			(stroke
				(width 0.1)
				(type default)
			)
			(layer "F.Fab")
		)
		(fp_line
			(start 0.306832 -2.436876)
			(end -0.333248 -2.436876)
			(stroke
				(width 0.1)
				(type default)
			)
			(layer "F.Fab")
		)
		(fp_line
			(start -0.333248 -2.436876)
			(end -0.333248 -3.7084)
			(stroke
				(width 0.1)
				(type default)
			)
			(layer "F.Fab")
		)
		(fp_line
			(start -2.233168 -2.436876)
			(end -2.873248 -2.436876)
			(stroke
				(width 0.1)
				(type default)
			)
			(layer "F.Fab")
		)
		(fp_line
			(start -2.873248 -2.436876)
			(end -2.873248 -3.7084)
			(stroke
				(width 0.1)
				(type default)
			)
			(layer "F.Fab")
		)
		(fp_line
			(start -4.773168 -2.436876)
			(end -5.413248 -2.436876)
			(stroke
				(width 0.1)
				(type default)
			)
			(layer "F.Fab")
		)
		(fp_line
			(start -5.413248 -2.436876)
			(end -5.413248 -3.7084)
			(stroke
				(width 0.1)
				(type default)
			)
			(layer "F.Fab")
		)
		(fp_line
			(start 6.145022 2.4384)
			(end -6.145022 2.4384)
			(stroke
				(width 0.1)
				(type default)
			)
			(layer "F.Fab")
		)
		(fp_line
			(start 5.386832 2.4384)
			(end 5.386832 3.709924)
			(stroke
				(width 0.1)
				(type default)
			)
			(layer "F.Fab")
		)
		(fp_line
			(start 4.746752 2.4384)
			(end 5.386832 2.4384)
			(stroke
				(width 0.1)
				(type default)
			)
			(layer "F.Fab")
		)
		(fp_line
			(start 2.846832 2.4384)
			(end 2.846832 3.709924)
			(stroke
				(width 0.1)
				(type default)
			)
			(layer "F.Fab")
		)
		(fp_line
			(start 2.206752 2.4384)
			(end 2.846832 2.4384)
			(stroke
				(width 0.1)
				(type default)
			)
			(layer "F.Fab")
		)
		(fp_line
			(start 0.306832 2.4384)
			(end 0.306832 3.709924)
			(stroke
				(width 0.1)
				(type default)
			)
			(layer "F.Fab")
		)
		(fp_line
			(start -0.333248 2.4384)
			(end 0.306832 2.4384)
			(stroke
				(width 0.1)
				(type default)
			)
			(layer "F.Fab")
		)
		(fp_line
			(start -2.233168 2.4384)
			(end -2.233168 3.709924)
			(stroke
				(width 0.1)
				(type default)
			)
			(layer "F.Fab")
		)
		(fp_line
			(start -2.873248 2.4384)
			(end -2.233168 2.4384)
			(stroke
				(width 0.1)
				(type default)
			)
			(layer "F.Fab")
		)
		(fp_line
			(start -4.747768 2.4384)
			(end -4.747768 3.709924)
			(stroke
				(width 0.1)
				(type default)
			)
			(layer "F.Fab")
		)
		(fp_line
			(start -5.387848 2.4384)
			(end -4.747768 2.4384)
			(stroke
				(width 0.1)
				(type default)
			)
			(layer "F.Fab")
		)
		(fp_line
			(start -6.145022 2.4384)
			(end -6.145022 -2.4384)
			(stroke
				(width 0.1)
				(type default)
			)
			(layer "F.Fab")
		)
		(fp_line
			(start 5.386832 3.709924)
			(end 4.746752 3.709924)
			(stroke
				(width 0.1)
				(type default)
			)
			(layer "F.Fab")
		)
		(fp_line
			(start 4.746752 3.709924)
			(end 4.746752 2.4384)
			(stroke
				(width 0.1)
				(type default)
			)
			(layer "F.Fab")
		)
		(fp_line
			(start 2.846832 3.709924)
			(end 2.206752 3.709924)
			(stroke
				(width 0.1)
				(type default)
			)
			(layer "F.Fab")
		)
		(fp_line
			(start 2.206752 3.709924)
			(end 2.206752 2.4384)
			(stroke
				(width 0.1)
				(type default)
			)
			(layer "F.Fab")
		)
		(fp_line
			(start 0.306832 3.709924)
			(end -0.333248 3.709924)
			(stroke
				(width 0.1)
				(type default)
			)
			(layer "F.Fab")
		)
		(fp_line
			(start -0.333248 3.709924)
			(end -0.333248 2.4384)
			(stroke
				(width 0.1)
				(type default)
			)
			(layer "F.Fab")
		)
		(fp_line
			(start -2.233168 3.709924)
			(end -2.873248 3.709924)
			(stroke
				(width 0.1)
				(type default)
			)
			(layer "F.Fab")
		)
		(fp_line
			(start -2.873248 3.709924)
			(end -2.873248 2.4384)
			(stroke
				(width 0.1)
				(type default)
			)
			(layer "F.Fab")
		)
		(fp_line
			(start -4.747768 3.709924)
			(end -5.387848 3.709924)
			(stroke
				(width 0.1)
				(type default)
			)
			(layer "F.Fab")
		)
		(fp_line
			(start -5.387848 3.709924)
			(end -5.387848 2.4384)
			(stroke
				(width 0.1)
				(type default)
			)
			(layer "F.Fab")
		)
		(fp_text user "10"
			(at 6.28523 -5.4102 0)
			(unlocked yes)
			(layer "F.SilkS")
			(effects
				(font
					(size 0.7874 0.5842)
					(thickness 0.1524)
				)
			)
		)
		(fp_text user "2"
			(at -6.92277 -4.5212 0)
			(unlocked yes)
			(layer "F.SilkS")
			(effects
				(font
					(size 0.7874 0.5842)
					(thickness 0.1524)
				)
			)
		)
		(fp_text user "9"
			(at 5.90423 5.5118 0)
			(unlocked yes)
			(layer "F.SilkS")
			(effects
				(font
					(size 0.7874 0.5842)
					(thickness 0.1524)
				)
			)
		)
		(fp_text user "1"
			(at -5.14477 5.7658 0)
			(unlocked yes)
			(layer "F.SilkS")
			(effects
				(font
					(size 0.7874 0.5842)
					(thickness 0.1524)
				)
			)
		)
		(fp_text user "10"
			(at 5.15493 -4.9022 0)
			(unlocked yes)
			(layer "F.Fab")
			(effects
				(font
					(size 0.7874 0.5842)
					(thickness 0.1524)
				)
			)
		)
		(fp_text user "2"
			(at -5.65277 -4.9022 0)
			(unlocked yes)
			(layer "F.Fab")
			(effects
				(font
					(size 0.7874 0.5842)
					(thickness 0.1524)
				)
			)
		)
		(fp_text user "9"
			(at 5.02793 4.2418 0)
			(unlocked yes)
			(layer "F.Fab")
			(effects
				(font
					(size 0.7874 0.5842)
					(thickness 0.1524)
				)
			)
		)
		(fp_text user "1"
			(at -5.13207 4.4958 0)
			(unlocked yes)
			(layer "F.Fab")
			(effects
				(font
					(size 0.7874 0.5842)
					(thickness 0.1524)
				)
			)
		)
		(pad "1" smd rect
			(at -5.08 2.605024 90)
			(size 1.27 3.556)
			(layers "F.Cu" "F.Mask" "F.Paste")
			(net "FT4232_FPGA_TCK")
		)
		(pad "2" smd rect
			(at -5.08 -2.605024 90)
			(size 1.27 3.556)
			(layers "F.Cu" "F.Mask" "F.Paste")
			(net "SG")
		)
		(pad "3" smd rect
			(at -2.54 2.605024 90)
			(size 1.27 3.556)
			(layers "F.Cu" "F.Mask" "F.Paste")
			(net "FT4232_FPGA_TDO")
		)
		(pad "4" smd rect
			(at -2.54 -2.605024 90)
			(size 1.27 3.556)
			(layers "F.Cu" "F.Mask" "F.Paste")
			(net "UNNAMED_127_G2001028301_I427_4")
		)
		(pad "5" smd rect
			(at 0 2.605024 90)
			(size 1.27 3.556)
			(layers "F.Cu" "F.Mask" "F.Paste")
			(net "FT4232_FPGA_TMS")
		)
		(pad "6" smd rect
			(at 0 -2.605024 90)
			(size 1.27 3.556)
			(layers "F.Cu" "F.Mask" "F.Paste")
			(net "Net_625")
		)
		(pad "7" smd rect
			(at 2.54 2.605024 90)
			(size 1.27 3.556)
			(layers "F.Cu" "F.Mask" "F.Paste")
			(net "Net_626")
		)
		(pad "8" smd rect
			(at 2.54 -2.605024 90)
			(size 1.27 3.556)
			(layers "F.Cu" "F.Mask" "F.Paste")
			(net "Net_627")
		)
		(pad "9" smd rect
			(at 5.08 2.605024 90)
			(size 1.27 3.556)
			(layers "F.Cu" "F.Mask" "F.Paste")
			(net "FT4232_FPGA_TDI")
		)
		(pad "10" smd rect
			(at 5.08 -2.605024 90)
			(size 1.27 3.556)
			(layers "F.Cu" "F.Mask" "F.Paste")
			(net "SG")
		)
		(zone
			(layer "F.Cu")
			(hatch none 0.5)
			(connect_pads
				(clearance 0)
			)
			(min_thickness 0.25)
			(keepout
				(tracks allowed)
				(vias not_allowed)
				(pads allowed)
				(copperpour not_allowed)
				(footprints allowed)
			)
			(placement
				(enabled no)
				(sheetname "")
			)
			(fill
				(thermal_gap 0.5)
				(thermal_bridge_width 0.5)
				(island_removal_mode 0)
			)
			(polygon
				(pts
					(xy 141.6304 -77.371702) (xy 141.6304 -65.941702) (xy 143.256 -65.941702) (xy 143.256 -77.371702)
				)
			)
		)
	)
	(footprint ""
		(layer "F.Cu")
		(at 80.772 -56.1086 180)
		(property "Reference" "R289"
			(at 10.287 19.51863 0)
			(unlocked yes)
			(layer "F.SilkS")
			(effects
				(font
					(size 0.7874 0.5842)
					(thickness 0.1524)
				)
			)
		)
		(property "Value" "VAL*"
			(at 0.02032 2.13233 180)
			(unlocked yes)
			(layer "F.Fab")
			(hide yes)
			(effects
				(font
					(size 0.7874 0.5842)
					(thickness 0.1524)
				)
			)
		)
		(property "Tolerance" "TOL*"
			(at 0.044704 3.05435 180)
			(unlocked yes)
			(layer "Cmts.User")
			(hide yes)
			(effects
				(font
					(size 0.7874 0.5842)
					(thickness 0.1524)
				)
			)
		)
		(property "User Part Number" "PARTNUM*"
			(at 0.02032 4.024884 180)
			(unlocked yes)
			(layer "Cmts.User")
			(hide yes)
			(effects
				(font
					(size 0.7874 0.5842)
					(thickness 0.1524)
				)
			)
		)
		(property "Device Type" "RESISTOR-G155-14701-01,4.7KOHMA"
			(at 0.008382 1.210564 180)
			(unlocked yes)
			(layer "F.Fab")
			(hide yes)
			(effects
				(font
					(size 0.7874 0.5842)
					(thickness 0.1524)
				)
			)
		)
		(duplicate_pad_numbers_are_jumpers no)
		(fp_line
			(start 1.143 0.5588)
			(end 1.143 -0.5588)
			(stroke
				(width 0.1)
				(type default)
			)
			(layer "F.SilkS")
		)
		(fp_line
			(start 1.143 -0.5588)
			(end -1.143 -0.5588)
			(stroke
				(width 0.1)
				(type default)
			)
			(layer "F.SilkS")
		)
		(fp_line
			(start -1.143 0.5588)
			(end 1.143 0.5588)
			(stroke
				(width 0.1)
				(type default)
			)
			(layer "F.SilkS")
		)
		(fp_line
			(start -1.143 -0.5588)
			(end -1.143 0.5588)
			(stroke
				(width 0.1)
				(type default)
			)
			(layer "F.SilkS")
		)
		(fp_rect
			(start 1.143 -0.5588)
			(end -1.143 0.5588)
			(stroke
				(width 0)
				(type default)
			)
			(fill no)
			(layer "F.CrtYd")
		)
		(fp_line
			(start 0.508 0.3048)
			(end 0.508 -0.3048)
			(stroke
				(width 0.1)
				(type default)
			)
			(layer "F.Fab")
		)
		(fp_line
			(start 0.508 -0.3048)
			(end -0.508 -0.3048)
			(stroke
				(width 0.1)
				(type default)
			)
			(layer "F.Fab")
		)
		(fp_line
			(start -0.508 0.3048)
			(end 0.508 0.3048)
			(stroke
				(width 0.1)
				(type default)
			)
			(layer "F.Fab")
		)
		(fp_line
			(start -0.508 -0.3048)
			(end -0.508 0.3048)
			(stroke
				(width 0.1)
				(type default)
			)
			(layer "F.Fab")
		)
		(pad "1" smd rect
			(at -0.5334 0 180)
			(size 0.7112 0.6096)
			(layers "F.Cu" "F.Mask" "F.Paste")
			(net "XP3R3V_FPGA")
		)
		(pad "2" smd rect
			(at 0.5334 0 180)
			(size 0.7112 0.6096)
			(layers "F.Cu" "F.Mask" "F.Paste")
			(net "FPGA_IN_BNO080_INT_N")
		)
		(zone
			(layer "F.Cu")
			(hatch none 0.5)
			(connect_pads
				(clearance 0)
			)
			(min_thickness 0.25)
			(keepout
				(tracks allowed)
				(vias not_allowed)
				(pads allowed)
				(copperpour not_allowed)
				(footprints allowed)
			)
			(placement
				(enabled no)
				(sheetname "")
			)
			(fill
				(thermal_gap 0.5)
				(thermal_bridge_width 0.5)
				(island_removal_mode 0)
			)
			(polygon
				(pts
					(xy 80.6958 -55.8038) (xy 80.8482 -55.8038) (xy 80.8482 -56.4134) (xy 80.6958 -56.4134)
				)
			)
		)
	)
	(footprint ""
		(layer "F.Cu")
		(at 47.879 -75.184 90)
		(property "Reference" "C302"
			(at -0.381 2.19837 90)
			(unlocked yes)
			(layer "F.SilkS")
			(effects
				(font
					(size 0.7874 0.5842)
					(thickness 0.1524)
				)
			)
		)
		(property "Value" "VAL*"
			(at 0.0762 2.067306 90)
			(unlocked yes)
			(layer "F.Fab")
			(hide yes)
			(effects
				(font
					(size 0.7874 0.5842)
					(thickness 0.1524)
				)
			)
		)
		(property "Tolerance" "TOL*"
			(at 0.0762 3.032506 90)
			(unlocked yes)
			(layer "Cmts.User")
			(hide yes)
			(effects
				(font
					(size 0.7874 0.5842)
					(thickness 0.1524)
				)
			)
		)
		(property "User Part Number" "PARTNUM*"
			(at 0.1016 4.023106 90)
			(unlocked yes)
			(layer "Cmts.User")
			(hide yes)
			(effects
				(font
					(size 0.7874 0.5842)
					(thickness 0.1524)
				)
			)
		)
		(property "Device Type" "CAPACITOR-G105-0B104-EK,0.1UF,A"
			(at 0.0508 1.127506 90)
			(unlocked yes)
			(layer "F.Fab")
			(hide yes)
			(effects
				(font
					(size 0.7874 0.5842)
					(thickness 0.1524)
				)
			)
		)
		(duplicate_pad_numbers_are_jumpers no)
		(fp_line
			(start 1.143 -0.5588)
			(end -1.143 -0.5588)
			(stroke
				(width 0.1)
				(type default)
			)
			(layer "F.SilkS")
		)
		(fp_line
			(start -1.143 -0.5588)
			(end -1.143 0.5588)
			(stroke
				(width 0.1)
				(type default)
			)
			(layer "F.SilkS")
		)
		(fp_line
			(start 1.143 0.5588)
			(end 1.143 -0.5588)
			(stroke
				(width 0.1)
				(type default)
			)
			(layer "F.SilkS")
		)
		(fp_line
			(start -1.143 0.5588)
			(end 1.143 0.5588)
			(stroke
				(width 0.1)
				(type default)
			)
			(layer "F.SilkS")
		)
		(fp_poly
			(pts
				(xy -1.143 0.5588) (xy 1.143 0.5588) (xy 1.143 -0.5588) (xy -1.143 -0.5588)
			)
			(stroke
				(width 0)
				(type default)
			)
			(fill no)
			(layer "F.CrtYd")
		)
		(fp_line
			(start 0.508 -0.3048)
			(end -0.508 -0.3048)
			(stroke
				(width 0.1)
				(type default)
			)
			(layer "F.Fab")
		)
		(fp_line
			(start -0.508 -0.3048)
			(end -0.508 0.3048)
			(stroke
				(width 0.1)
				(type default)
			)
			(layer "F.Fab")
		)
		(fp_line
			(start 0.508 0.3048)
			(end 0.508 -0.3048)
			(stroke
				(width 0.1)
				(type default)
			)
			(layer "F.Fab")
		)
		(fp_line
			(start -0.508 0.3048)
			(end 0.508 0.3048)
			(stroke
				(width 0.1)
				(type default)
			)
			(layer "F.Fab")
		)
		(pad "1" smd rect
			(at -0.5334 0 90)
			(size 0.7112 0.6096)
			(layers "F.Cu" "F.Mask" "F.Paste")
			(net "UNNAMED_525_CAPACITOR_I14_1")
		)
		(pad "2" smd rect
			(at 0.5334 0 90)
			(size 0.7112 0.6096)
			(layers "F.Cu" "F.Mask" "F.Paste")
			(net "SG")
		)
		(zone
			(layer "F.Cu")
			(hatch none 0.5)
			(connect_pads
				(clearance 0)
			)
			(min_thickness 0.25)
			(keepout
				(tracks not_allowed)
				(vias allowed)
				(pads allowed)
				(copperpour not_allowed)
				(footprints allowed)
			)
			(placement
				(enabled no)
				(sheetname "")
			)
			(fill
				(thermal_gap 0.5)
				(thermal_bridge_width 0.5)
				(island_removal_mode 0)
			)
			(polygon
				(pts
					(xy 48.1838 -75.1078) (xy 48.1838 -75.2602) (xy 47.5742 -75.2602) (xy 47.5742 -75.1078)
				)
			)
		)
		(zone
			(layer "F.Cu")
			(hatch none 0.5)
			(connect_pads
				(clearance 0)
			)
			(min_thickness 0.25)
			(keepout
				(tracks allowed)
				(vias not_allowed)
				(pads allowed)
				(copperpour not_allowed)
				(footprints allowed)
			)
			(placement
				(enabled no)
				(sheetname "")
			)
			(fill
				(thermal_gap 0.5)
				(thermal_bridge_width 0.5)
				(island_removal_mode 0)
			)
			(polygon
				(pts
					(xy 48.1838 -75.1078) (xy 48.1838 -75.2602) (xy 47.5742 -75.2602) (xy 47.5742 -75.1078)
				)
			)
		)
	)
	(footprint ""
		(layer "F.Cu")
		(at 52.451 -122.428)
		(property "Reference" "SP78"
			(at 0 0 0)
			(layer "F.SilkS")
			(hide yes)
			(effects
				(font
					(size 1.27 1.27)
				)
			)
		)
		(property "Value" ""
			(at 0 0 0)
			(layer "F.Fab")
			(effects
				(font
					(size 1.27 1.27)
				)
			)
		)
		(duplicate_pad_numbers_are_jumpers no)
	)
	(footprint ""
		(layer "F.Cu")
		(at 136.906 -41.402 -90)
		(property "Reference" "C271"
			(at 3.302 -0.03937 90)
			(unlocked yes)
			(layer "F.SilkS")
			(effects
				(font
					(size 0.7874 0.5842)
					(thickness 0.1524)
				)
			)
		)
		(property "Value" "VAL*"
			(at 0.0762 3.134106 270)
			(unlocked yes)
			(layer "F.Fab")
			(hide yes)
			(effects
				(font
					(size 0.7874 0.5842)
					(thickness 0.1524)
				)
			)
		)
		(property "Device Type" "CAPACITOR-G107-0F476-AM,47UF,2A"
			(at 0.0508 2.194306 270)
			(unlocked yes)
			(layer "F.Fab")
			(hide yes)
			(effects
				(font
					(size 0.7874 0.5842)
					(thickness 0.1524)
				)
			)
		)
		(property "User Part Number" "PARTNUM*"
			(at 0.1016 5.013706 270)
			(unlocked yes)
			(layer "Cmts.User")
			(hide yes)
			(effects
				(font
					(size 0.7874 0.5842)
					(thickness 0.1524)
				)
			)
		)
		(property "Tolerance" "TOL*"
			(at 0.0762 4.048506 270)
			(unlocked yes)
			(layer "Cmts.User")
			(hide yes)
			(effects
				(font
					(size 0.7874 0.5842)
					(thickness 0.1524)
				)
			)
		)
		(duplicate_pad_numbers_are_jumpers no)
		(fp_line
			(start -1.5748 0.9398)
			(end 1.5748 0.9398)
			(stroke
				(width 0.1)
				(type default)
			)
			(layer "F.SilkS")
		)
		(fp_line
			(start 1.5748 0.9398)
			(end 1.5748 -0.9398)
			(stroke
				(width 0.1)
				(type default)
			)
			(layer "F.SilkS")
		)
		(fp_line
			(start -1.5748 -0.9398)
			(end -1.5748 0.9398)
			(stroke
				(width 0.1)
				(type default)
			)
			(layer "F.SilkS")
		)
		(fp_line
			(start 1.5748 -0.9398)
			(end -1.5748 -0.9398)
			(stroke
				(width 0.1)
				(type default)
			)
			(layer "F.SilkS")
		)
		(fp_rect
			(start -1.5748 0.9398)
			(end 1.5748 -0.9398)
			(stroke
				(width 0)
				(type default)
			)
			(fill no)
			(layer "F.CrtYd")
		)
		(fp_line
			(start -1.016 0.635)
			(end 1.016 0.635)
			(stroke
				(width 0.1)
				(type default)
			)
			(layer "F.Fab")
		)
		(fp_line
			(start 1.016 0.635)
			(end 1.016 -0.635)
			(stroke
				(width 0.1)
				(type default)
			)
			(layer "F.Fab")
		)
		(fp_line
			(start -1.016 -0.635)
			(end -1.016 0.635)
			(stroke
				(width 0.1)
				(type default)
			)
			(layer "F.Fab")
		)
		(fp_line
			(start 1.016 -0.635)
			(end -1.016 -0.635)
			(stroke
				(width 0.1)
				(type default)
			)
			(layer "F.Fab")
		)
		(pad "1" smd rect
			(at -0.8382 0 270)
			(size 0.9652 1.3716)
			(layers "F.Cu" "F.Mask" "F.Paste")
			(net "XP1R0V_FPGA")
		)
		(pad "2" smd rect
			(at 0.8382 0 270)
			(size 0.9652 1.3716)
			(layers "F.Cu" "F.Mask" "F.Paste")
			(net "SG")
		)
		(zone
			(layer "F.Cu")
			(hatch none 0.5)
			(connect_pads
				(clearance 0)
			)
			(min_thickness 0.25)
			(keepout
				(tracks allowed)
				(vias not_allowed)
				(pads allowed)
				(copperpour not_allowed)
				(footprints allowed)
			)
			(placement
				(enabled no)
				(sheetname "")
			)
			(fill
				(thermal_gap 0.5)
				(thermal_bridge_width 0.5)
				(island_removal_mode 0)
			)
			(polygon
				(pts
					(xy 136.271 -41.6306) (xy 136.271 -41.1734) (xy 137.541 -41.1734) (xy 137.541 -41.6306)
				)
			)
		)
	)
	(footprint ""
		(layer "F.Cu")
		(at 12.7 -39.878 180)
		(property "Reference" "C310"
			(at -1.016 -1.04775 0)
			(unlocked yes)
			(layer "F.SilkS")
			(effects
				(font
					(size 0.635 0.4064)
					(thickness 0.1524)
				)
			)
		)
		(property "Value" "VAL*"
			(at 0.193548 2.13614 180)
			(unlocked yes)
			(layer "F.Fab")
			(hide yes)
			(effects
				(font
					(size 0.7874 0.5842)
					(thickness 0.1524)
				)
			)
		)
		(property "User Part Number" "PARTNUM*"
			(at 0.216154 4.185666 180)
			(unlocked yes)
			(layer "Cmts.User")
			(hide yes)
			(effects
				(font
					(size 0.7874 0.5842)
					(thickness 0.1524)
				)
			)
		)
		(property "Device Type" "CAPACITOR-G104-0A180-FJ,18PF,5%"
			(at 0.184404 1.180592 180)
			(unlocked yes)
			(layer "F.Fab")
			(hide yes)
			(effects
				(font
					(size 0.7874 0.5842)
					(thickness 0.1524)
				)
			)
		)
		(property "Tolerance" "TOL*"
			(at 0.216154 3.1496 180)
			(unlocked yes)
			(layer "Cmts.User")
			(hide yes)
			(effects
				(font
					(size 0.7874 0.5842)
					(thickness 0.1524)
				)
			)
		)
		(duplicate_pad_numbers_are_jumpers no)
		(fp_line
			(start 0.671322 0.4445)
			(end -0.671322 0.4445)
			(stroke
				(width 0.1)
				(type default)
			)
			(layer "F.SilkS")
		)
		(fp_line
			(start 0.671322 -0.4445)
			(end 0.671322 0.4445)
			(stroke
				(width 0.1)
				(type default)
			)
			(layer "F.SilkS")
		)
		(fp_line
			(start -0.671322 0.4445)
			(end -0.671322 -0.4445)
			(stroke
				(width 0.1)
				(type default)
			)
			(layer "F.SilkS")
		)
		(fp_line
			(start -0.671322 -0.4445)
			(end 0.671322 -0.4445)
			(stroke
				(width 0.1)
				(type default)
			)
			(layer "F.SilkS")
		)
		(fp_rect
			(start -0.671322 0.4445)
			(end 0.671322 -0.4445)
			(stroke
				(width 0)
				(type default)
			)
			(fill no)
			(layer "F.CrtYd")
		)
		(fp_line
			(start 0.31496 0.1651)
			(end 0.31496 -0.1651)
			(stroke
				(width 0.1)
				(type default)
			)
			(layer "F.Fab")
		)
		(fp_line
			(start 0.31496 -0.1651)
			(end -0.31496 -0.1651)
			(stroke
				(width 0.1)
				(type default)
			)
			(layer "F.Fab")
		)
		(fp_line
			(start -0.31496 0.1651)
			(end 0.31496 0.1651)
			(stroke
				(width 0.1)
				(type default)
			)
			(layer "F.Fab")
		)
		(fp_line
			(start -0.31496 -0.1651)
			(end -0.31496 0.1651)
			(stroke
				(width 0.1)
				(type default)
			)
			(layer "F.Fab")
		)
		(pad "1" smd rect
			(at -0.264922 0 180)
			(size 0.3048 0.381)
			(layers "F.Cu" "F.Mask" "F.Paste")
			(net "SG")
		)
		(pad "2" smd rect
			(at 0.264922 0 180)
			(size 0.3048 0.381)
			(layers "F.Cu" "F.Mask" "F.Paste")
			(net "UNNAMED_12_CAPACITOR_I318_2")
		)
		(zone
			(layer "F.Cu")
			(hatch none 0.5)
			(connect_pads
				(clearance 0)
			)
			(min_thickness 0.25)
			(keepout
				(tracks not_allowed)
				(vias allowed)
				(pads allowed)
				(copperpour not_allowed)
				(footprints allowed)
			)
			(placement
				(enabled no)
				(sheetname "")
			)
			(fill
				(thermal_gap 0.5)
				(thermal_bridge_width 0.5)
				(island_removal_mode 0)
			)
			(polygon
				(pts
					(xy 12.812522 -40.0685) (xy 12.587478 -40.0685) (xy 12.587478 -39.6875) (xy 12.812522 -39.6875)
				)
			)
		)
		(zone
			(layer "F.Cu")
			(hatch none 0.5)
			(connect_pads
				(clearance 0)
			)
			(min_thickness 0.25)
			(keepout
				(tracks allowed)
				(vias not_allowed)
				(pads allowed)
				(copperpour not_allowed)
				(footprints allowed)
			)
			(placement
				(enabled no)
				(sheetname "")
			)
			(fill
				(thermal_gap 0.5)
				(thermal_bridge_width 0.5)
				(island_removal_mode 0)
			)
			(polygon
				(pts
					(xy 12.812522 -39.6875) (xy 12.812522 -40.0685) (xy 12.587478 -40.0685) (xy 12.587478 -39.6875)
				)
			)
		)
	)
	(footprint ""
		(layer "F.Cu")
		(at 4.073906 -61.60008)
		(property "Reference" "J3"
			(at 4.943094 -2.24155 0)
			(unlocked yes)
			(layer "F.SilkS")
			(effects
				(font
					(size 0.7874 0.5842)
					(thickness 0.1524)
				)
			)
		)
		(property "Value" ""
			(at 0 0 0)
			(layer "F.Fab")
			(effects
				(font
					(size 1.27 1.27)
				)
			)
		)
		(property "Device Type" "CONN_JACK_1P_GH4_S_TH-G200-130A"
			(at -5.098288 5.899912 0)
			(unlocked yes)
			(layer "F.Fab")
			(hide yes)
			(effects
				(font
					(size 0.7874 0.5842)
					(thickness 0.1524)
				)
			)
		)
		(property "User Part Number" "PARTNUM*"
			(at -5.098288 7.093712 0)
			(unlocked yes)
			(layer "Cmts.User")
			(hide yes)
			(effects
				(font
					(size 0.7874 0.5842)
					(thickness 0.1524)
				)
			)
		)
		(duplicate_pad_numbers_are_jumpers no)
		(fp_line
			(start -13.953998 -3.937)
			(end 3.937 -3.937)
			(stroke
				(width 0.1)
				(type default)
			)
			(layer "F.SilkS")
		)
		(fp_line
			(start -13.953998 3.937)
			(end -13.953998 -3.937)
			(stroke
				(width 0.1)
				(type default)
			)
			(layer "F.SilkS")
		)
		(fp_line
			(start 3.937 -3.937)
			(end 3.937 3.937)
			(stroke
				(width 0.1)
				(type default)
			)
			(layer "F.SilkS")
		)
		(fp_line
			(start 3.937 3.937)
			(end -13.953998 3.937)
			(stroke
				(width 0.1)
				(type default)
			)
			(layer "F.SilkS")
		)
		(fp_rect
			(start -8.763 8.763)
			(end 8.763 -8.763)
			(stroke
				(width 0)
				(type default)
			)
			(fill no)
			(layer "B.CrtYd")
		)
		(fp_rect
			(start -14.207998 4.191)
			(end 4.191 -4.191)
			(stroke
				(width 0)
				(type default)
			)
			(fill no)
			(layer "F.CrtYd")
		)
		(fp_line
			(start -13.699998 -3.599942)
			(end 3.599942 -3.599942)
			(stroke
				(width 0.1)
				(type default)
			)
			(layer "F.Fab")
		)
		(fp_line
			(start -13.699998 3.599942)
			(end -13.699998 -3.599942)
			(stroke
				(width 0.1)
				(type default)
			)
			(layer "F.Fab")
		)
		(fp_line
			(start 3.599942 -3.599942)
			(end 3.599942 3.599942)
			(stroke
				(width 0.1)
				(type default)
			)
			(layer "F.Fab")
		)
		(fp_line
			(start 3.599942 3.599942)
			(end -13.699998 3.599942)
			(stroke
				(width 0.1)
				(type default)
			)
			(layer "F.Fab")
		)
		(fp_text user "GH1"
			(at 0.117094 -4.28117 0)
			(unlocked yes)
			(layer "F.SilkS")
			(effects
				(font
					(size 0.635 0.4064)
					(thickness 0.1524)
				)
			)
		)
		(fp_text user "GH3"
			(at 0.752094 4.68503 0)
			(unlocked yes)
			(layer "F.SilkS")
			(effects
				(font
					(size 0.635 0.4064)
					(thickness 0.1524)
				)
			)
		)
		(fp_text user "GH2"
			(at 2.530094 -4.28117 0)
			(unlocked yes)
			(layer "F.SilkS")
			(effects
				(font
					(size 0.635 0.4064)
					(thickness 0.1524)
				)
			)
		)
		(fp_text user "GH4"
			(at 3.038094 4.68503 0)
			(unlocked yes)
			(layer "F.SilkS")
			(effects
				(font
					(size 0.635 0.4064)
					(thickness 0.1524)
				)
			)
		)
		(fp_text user "1"
			(at 4.191 -0.35433 0)
			(unlocked yes)
			(layer "F.SilkS")
			(effects
				(font
					(size 0.7874 0.5842)
					(thickness 0.1524)
				)
				(justify left)
			)
		)
		(fp_text user "GH1"
			(at -2.549906 -4.14655 0)
			(unlocked yes)
			(layer "F.Fab")
			(effects
				(font
					(size 0.7874 0.5842)
					(thickness 0.1524)
				)
			)
		)
		(fp_text user "GH3"
			(at -2.422906 4.229608 0)
			(unlocked yes)
			(layer "F.Fab")
			(effects
				(font
					(size 0.7874 0.5842)
					(thickness 0.1524)
				)
			)
		)
		(fp_text user "GH4"
			(at 2.403094 4.229608 0)
			(unlocked yes)
			(layer "F.Fab")
			(effects
				(font
					(size 0.7874 0.5842)
					(thickness 0.1524)
				)
			)
		)
		(fp_text user "GH2"
			(at 2.54 -4.57073 0)
			(unlocked yes)
			(layer "F.Fab")
			(effects
				(font
					(size 0.7874 0.5842)
					(thickness 0.1524)
				)
			)
		)
		(fp_text user "1"
			(at 4.191 -0.35433 0)
			(unlocked yes)
			(layer "F.Fab")
			(effects
				(font
					(size 0.7874 0.5842)
					(thickness 0.1524)
				)
				(justify left)
			)
		)
		(pad "1" thru_hole circle
			(at 0 0)
			(size 2.1844 2.1844)
			(drill 1.4986)
			(layers "*.Cu" "*.Mask")
			(remove_unused_layers no)
			(net "SMA1_SIG_IO_CONN")
			(padstack
				(mode front_inner_back)
				(layer "Inner"
					(shape circle)
					(size 2.1844 2.1844)
					(clearance -0.0508)
				)
				(layer "B.Cu"
					(shape circle)
					(size 2.1844 2.1844)
				)
			)
		)
		(pad "GH1" thru_hole circle
			(at -2.54 -2.54)
			(size 2.286 2.286)
			(drill 1.6002)
			(layers "*.Cu" "*.Mask")
			(remove_unused_layers no)
			(net "SG")
			(padstack
				(mode front_inner_back)
				(layer "Inner"
					(shape circle)
					(size 2.286 2.286)
					(clearance -0.0508)
				)
				(layer "B.Cu"
					(shape circle)
					(size 2.286 2.286)
				)
			)
		)
		(pad "GH2" thru_hole circle
			(at 2.54 -2.54)
			(size 2.286 2.286)
			(drill 1.6002)
			(layers "*.Cu" "*.Mask")
			(remove_unused_layers no)
			(net "SG")
			(padstack
				(mode front_inner_back)
				(layer "Inner"
					(shape circle)
					(size 2.286 2.286)
					(clearance -0.0508)
				)
				(layer "B.Cu"
					(shape circle)
					(size 2.286 2.286)
				)
			)
		)
		(pad "GH3" thru_hole circle
			(at -2.54 2.54)
			(size 2.286 2.286)
			(drill 1.6002)
			(layers "*.Cu" "*.Mask")
			(remove_unused_layers no)
			(net "SG")
			(padstack
				(mode front_inner_back)
				(layer "Inner"
					(shape circle)
					(size 2.286 2.286)
					(clearance -0.0508)
				)
				(layer "B.Cu"
					(shape circle)
					(size 2.286 2.286)
				)
			)
		)
		(pad "GH4" thru_hole circle
			(at 2.54 2.54)
			(size 2.286 2.286)
			(drill 1.6002)
			(layers "*.Cu" "*.Mask")
			(remove_unused_layers no)
			(net "SG")
			(padstack
				(mode front_inner_back)
				(layer "Inner"
					(shape circle)
					(size 2.286 2.286)
					(clearance -0.0508)
				)
				(layer "B.Cu"
					(shape circle)
					(size 2.286 2.286)
				)
			)
		)
	)
	(footprint ""
		(layer "F.Cu")
		(at 5.0038 -68.201032 90)
		(property "Reference" "R391"
			(at 3.553968 -0.51943 90)
			(unlocked yes)
			(layer "F.SilkS")
			(effects
				(font
					(size 0.7874 0.5842)
					(thickness 0.1524)
				)
			)
		)
		(property "Value" "VAL*"
			(at 0.02032 2.13233 90)
			(unlocked yes)
			(layer "F.Fab")
			(hide yes)
			(effects
				(font
					(size 0.7874 0.5842)
					(thickness 0.1524)
				)
			)
		)
		(property "Tolerance" "TOL*"
			(at 0.044704 3.05435 90)
			(unlocked yes)
			(layer "Cmts.User")
			(hide yes)
			(effects
				(font
					(size 0.7874 0.5842)
					(thickness 0.1524)
				)
			)
		)
		(property "User Part Number" "PARTNUM*"
			(at 0.02032 4.024884 90)
			(unlocked yes)
			(layer "Cmts.User")
			(hide yes)
			(effects
				(font
					(size 0.7874 0.5842)
					(thickness 0.1524)
				)
			)
		)
		(property "Device Type" "RESISTOR-G155-133R0-01,33OHM,1%"
			(at 0.008382 1.210564 90)
			(unlocked yes)
			(layer "F.Fab")
			(hide yes)
			(effects
				(font
					(size 0.7874 0.5842)
					(thickness 0.1524)
				)
			)
		)
		(duplicate_pad_numbers_are_jumpers no)
		(fp_line
			(start 1.143 -0.5588)
			(end -1.143 -0.5588)
			(stroke
				(width 0.1)
				(type default)
			)
			(layer "F.SilkS")
		)
		(fp_line
			(start -1.143 -0.5588)
			(end -1.143 0.5588)
			(stroke
				(width 0.1)
				(type default)
			)
			(layer "F.SilkS")
		)
		(fp_line
			(start 1.143 0.5588)
			(end 1.143 -0.5588)
			(stroke
				(width 0.1)
				(type default)
			)
			(layer "F.SilkS")
		)
		(fp_line
			(start -1.143 0.5588)
			(end 1.143 0.5588)
			(stroke
				(width 0.1)
				(type default)
			)
			(layer "F.SilkS")
		)
		(fp_rect
			(start -1.143 -0.5588)
			(end 1.143 0.5588)
			(stroke
				(width 0)
				(type default)
			)
			(fill no)
			(layer "F.CrtYd")
		)
		(fp_line
			(start 0.508 -0.3048)
			(end -0.508 -0.3048)
			(stroke
				(width 0.1)
				(type default)
			)
			(layer "F.Fab")
		)
		(fp_line
			(start -0.508 -0.3048)
			(end -0.508 0.3048)
			(stroke
				(width 0.1)
				(type default)
			)
			(layer "F.Fab")
		)
		(fp_line
			(start 0.508 0.3048)
			(end 0.508 -0.3048)
			(stroke
				(width 0.1)
				(type default)
			)
			(layer "F.Fab")
		)
		(fp_line
			(start -0.508 0.3048)
			(end 0.508 0.3048)
			(stroke
				(width 0.1)
				(type default)
			)
			(layer "F.Fab")
		)
		(pad "1" smd rect
			(at -0.5334 0 90)
			(size 0.7112 0.6096)
			(layers "F.Cu" "F.Mask" "F.Paste")
			(net "SMA3_LED_BLUE_N")
		)
		(pad "2" smd rect
			(at 0.5334 0 90)
			(size 0.7112 0.6096)
			(layers "F.Cu" "F.Mask" "F.Paste")
			(net "UNNAMED_14_LED4PV14_I267_1")
		)
		(zone
			(layer "F.Cu")
			(hatch none 0.5)
			(connect_pads
				(clearance 0)
			)
			(min_thickness 0.25)
			(keepout
				(tracks not_allowed)
				(vias allowed)
				(pads allowed)
				(copperpour not_allowed)
				(footprints allowed)
			)
			(placement
				(enabled no)
				(sheetname "")
			)
			(fill
				(thermal_gap 0.5)
				(thermal_bridge_width 0.5)
				(island_removal_mode 0)
			)
			(polygon
				(pts
					(xy 4.699 -68.124832) (xy 5.3086 -68.124832) (xy 5.3086 -68.277232) (xy 4.699 -68.277232)
				)
			)
		)
		(zone
			(layer "F.Cu")
			(hatch none 0.5)
			(connect_pads
				(clearance 0)
			)
			(min_thickness 0.25)
			(keepout
				(tracks allowed)
				(vias not_allowed)
				(pads allowed)
				(copperpour not_allowed)
				(footprints allowed)
			)
			(placement
				(enabled no)
				(sheetname "")
			)
			(fill
				(thermal_gap 0.5)
				(thermal_bridge_width 0.5)
				(island_removal_mode 0)
			)
			(polygon
				(pts
					(xy 4.699 -68.124832) (xy 5.3086 -68.124832) (xy 5.3086 -68.277232) (xy 4.699 -68.277232)
				)
			)
		)
	)
	(footprint ""
		(layer "F.Cu")
		(at 50.419 -131.953)
		(property "Reference" "SP72"
			(at 0 0 0)
			(layer "F.SilkS")
			(hide yes)
			(effects
				(font
					(size 1.27 1.27)
				)
			)
		)
		(property "Value" ""
			(at 0 0 0)
			(layer "F.Fab")
			(effects
				(font
					(size 1.27 1.27)
				)
			)
		)
		(duplicate_pad_numbers_are_jumpers no)
	)
	(footprint ""
		(layer "F.Cu")
		(at 19.177 -15.748)
		(property "Reference" "TP20"
			(at 0.9398 0.86995 0)
			(unlocked yes)
			(layer "F.SilkS")
			(effects
				(font
					(size 0.635 0.4064)
					(thickness 0.1524)
				)
				(justify left)
			)
		)
		(property "Value" ""
			(at 0 0 0)
			(layer "F.Fab")
			(effects
				(font
					(size 1.27 1.27)
				)
			)
		)
		(property "Device Type" "TP_PIONT-TP010CT020B030_PTH-TPA"
			(at -1.341882 0.996696 0)
			(unlocked yes)
			(layer "F.Fab")
			(hide yes)
			(effects
				(font
					(size 0.7874 0.5842)
					(thickness 0.000001)
				)
				(justify left)
			)
		)
		(duplicate_pad_numbers_are_jumpers no)
		(fp_poly
			(pts
				(arc
					(start 0.889 0)
					(mid -0.889 0)
					(end 0.889 0)
				)
			)
			(stroke
				(width 0)
				(type default)
			)
			(fill no)
			(layer "B.CrtYd")
		)
		(fp_poly
			(pts
				(arc
					(start 0.889 0)
					(mid -0.889 0)
					(end 0.889 0)
				)
			)
			(stroke
				(width 0)
				(type default)
			)
			(fill no)
			(layer "F.CrtYd")
		)
		(pad "1" thru_hole circle
			(at 0 0)
			(size 0.508 0.508)
			(drill 0.254)
			(layers "*.Cu" "*.Mask")
			(remove_unused_layers no)
			(net "SEC_EEPROM_WP")
			(clearance 0.1016)
			(padstack
				(mode front_inner_back)
				(layer "Inner"
					(shape circle)
					(size 0.508 0.508)
					(clearance 0.1016)
				)
				(layer "B.Cu"
					(shape circle)
					(size 0.762 0.762)
					(clearance -0.0254)
				)
			)
		)
	)
	(footprint ""
		(layer "F.Cu")
		(at 109.347 -44.323 90)
		(property "Reference" "U24"
			(at 12.27963 3.683 0)
			(unlocked yes)
			(layer "F.SilkS")
			(effects
				(font
					(size 0.7874 0.5842)
					(thickness 0.1524)
				)
			)
		)
		(property "Value" ""
			(at 0 0 90)
			(layer "F.Fab")
			(effects
				(font
					(size 1.27 1.27)
				)
			)
		)
		(property "User Part Number" "PARTNUM*"
			(at 0 14.056868 90)
			(unlocked yes)
			(layer "Cmts.User")
			(hide yes)
			(effects
				(font
					(size 0.7874 0.5842)
					(thickness 0.1524)
				)
			)
		)
		(property "Device Type" "XC7A200T_2FBG484C_FBG484-G240-A"
			(at 0 12.863068 90)
			(unlocked yes)
			(layer "F.Fab")
			(hide yes)
			(effects
				(font
					(size 0.7874 0.5842)
					(thickness 0.1524)
				)
			)
		)
		(duplicate_pad_numbers_are_jumpers no)
		(fp_line
			(start 11.754104 -11.754104)
			(end 11.754104 11.754104)
			(stroke
				(width 0.1)
				(type default)
			)
			(layer "F.SilkS")
		)
		(fp_line
			(start -11.754104 -11.754104)
			(end 11.754104 -11.754104)
			(stroke
				(width 0.1)
				(type default)
			)
			(layer "F.SilkS")
		)
		(fp_line
			(start 11.754104 11.754104)
			(end -11.754104 11.754104)
			(stroke
				(width 0.1)
				(type default)
			)
			(layer "F.SilkS")
		)
		(fp_line
			(start -11.754104 11.754104)
			(end -11.754104 -11.754104)
			(stroke
				(width 0.1)
				(type default)
			)
			(layer "F.SilkS")
		)
		(fp_poly
			(pts
				(arc
					(start -12.827 -11.938)
					(mid -12.827 -13.208)
					(end -12.827 -11.938)
				)
			)
			(stroke
				(width 0)
				(type default)
			)
			(fill yes)
			(layer "F.SilkS")
		)
		(fp_rect
			(start -12.008104 -12.008104)
			(end 12.008104 12.008104)
			(stroke
				(width 0)
				(type default)
			)
			(fill no)
			(layer "F.CrtYd")
		)
		(fp_line
			(start 11.500104 -11.500104)
			(end -11.500104 -11.500104)
			(stroke
				(width 0.1)
				(type default)
			)
			(layer "F.Fab")
		)
		(fp_line
			(start -11.500104 -11.500104)
			(end -11.500104 11.500104)
			(stroke
				(width 0.1)
				(type default)
			)
			(layer "F.Fab")
		)
		(fp_line
			(start 11.500104 11.500104)
			(end 11.500104 -11.500104)
			(stroke
				(width 0.1)
				(type default)
			)
			(layer "F.Fab")
		)
		(fp_line
			(start -11.500104 11.500104)
			(end 11.500104 11.500104)
			(stroke
				(width 0.1)
				(type default)
			)
			(layer "F.Fab")
		)
		(fp_poly
			(pts
				(arc
					(start -12.18946 -12.20724)
					(mid -12.18946 -13.47724)
					(end -12.18946 -12.20724)
				)
			)
			(stroke
				(width 0)
				(type default)
			)
			(fill yes)
			(layer "F.Fab")
		)
		(fp_text user "22"
			(at 10.28446 -13.513308 90)
			(unlocked yes)
			(layer "F.SilkS")
			(effects
				(font
					(size 0.635 0.4064)
					(thickness 0.1524)
				)
			)
		)
		(fp_text user "20"
			(at 8.25246 -13.513308 90)
			(unlocked yes)
			(layer "F.SilkS")
			(effects
				(font
					(size 0.635 0.4064)
					(thickness 0.1524)
				)
			)
		)
		(fp_text user "18"
			(at 6.09346 -13.513308 90)
			(unlocked yes)
			(layer "F.SilkS")
			(effects
				(font
					(size 0.635 0.4064)
					(thickness 0.1524)
				)
			)
		)
		(fp_text user "16"
			(at 4.18846 -13.513308 90)
			(unlocked yes)
			(layer "F.SilkS")
			(effects
				(font
					(size 0.635 0.4064)
					(thickness 0.1524)
				)
			)
		)
		(fp_text user "14"
			(at 2.15646 -13.513308 90)
			(unlocked yes)
			(layer "F.SilkS")
			(effects
				(font
					(size 0.635 0.4064)
					(thickness 0.1524)
				)
			)
		)
		(fp_text user "10"
			(at -1.65354 -13.513308 90)
			(unlocked yes)
			(layer "F.SilkS")
			(effects
				(font
					(size 0.635 0.4064)
					(thickness 0.1524)
				)
			)
		)
		(fp_text user "8"
			(at -3.43154 -13.513308 90)
			(unlocked yes)
			(layer "F.SilkS")
			(effects
				(font
					(size 0.635 0.4064)
					(thickness 0.1524)
				)
			)
		)
		(fp_text user "4"
			(at -7.49554 -13.513308 90)
			(unlocked yes)
			(layer "F.SilkS")
			(effects
				(font
					(size 0.635 0.4064)
					(thickness 0.1524)
				)
			)
		)
		(fp_text user "2"
			(at -9.40054 -13.513308 90)
			(unlocked yes)
			(layer "F.SilkS")
			(effects
				(font
					(size 0.635 0.4064)
					(thickness 0.1524)
				)
			)
		)
		(fp_text user "12"
			(at -0.254 -13.43025 90)
			(unlocked yes)
			(layer "F.SilkS")
			(effects
				(font
					(size 0.635 0.4064)
					(thickness 0.1524)
				)
			)
		)
		(fp_text user "6"
			(at -5.588 -13.30325 90)
			(unlocked yes)
			(layer "F.SilkS")
			(effects
				(font
					(size 0.635 0.4064)
					(thickness 0.1524)
				)
			)
		)
		(fp_text user "17"
			(at 5.20446 -12.624308 90)
			(unlocked yes)
			(layer "F.SilkS")
			(effects
				(font
					(size 0.635 0.4064)
					(thickness 0.1524)
				)
			)
		)
		(fp_text user "11"
			(at -0.89154 -12.624308 90)
			(unlocked yes)
			(layer "F.SilkS")
			(effects
				(font
					(size 0.635 0.4064)
					(thickness 0.1524)
				)
			)
		)
		(fp_text user "9"
			(at -2.41554 -12.624308 90)
			(unlocked yes)
			(layer "F.SilkS")
			(effects
				(font
					(size 0.635 0.4064)
					(thickness 0.1524)
				)
			)
		)
		(fp_text user "7"
			(at -4.32054 -12.624308 90)
			(unlocked yes)
			(layer "F.SilkS")
			(effects
				(font
					(size 0.635 0.4064)
					(thickness 0.1524)
				)
			)
		)
		(fp_text user "5"
			(at -6.35254 -12.624308 90)
			(unlocked yes)
			(layer "F.SilkS")
			(effects
				(font
					(size 0.635 0.4064)
					(thickness 0.1524)
				)
			)
		)
		(fp_text user "19"
			(at 6.858 -12.54125 90)
			(unlocked yes)
			(layer "F.SilkS")
			(effects
				(font
					(size 0.635 0.4064)
					(thickness 0.1524)
				)
			)
		)
		(fp_text user "13"
			(at 1.524 -12.54125 90)
			(unlocked yes)
			(layer "F.SilkS")
			(effects
				(font
					(size 0.635 0.4064)
					(thickness 0.1524)
				)
			)
		)
		(fp_text user "21"
			(at 9.779 -12.41425 90)
			(unlocked yes)
			(layer "F.SilkS")
			(effects
				(font
					(size 0.635 0.4064)
					(thickness 0.1524)
				)
			)
		)
		(fp_text user "3"
			(at -8.763 -12.28725 90)
			(unlocked yes)
			(layer "F.SilkS")
			(effects
				(font
					(size 0.635 0.4064)
					(thickness 0.1524)
				)
			)
		)
		(fp_text user "1"
			(at -10.16 -12.16025 90)
			(unlocked yes)
			(layer "F.SilkS")
			(effects
				(font
					(size 0.635 0.4064)
					(thickness 0.1524)
				)
			)
		)
		(fp_text user "A"
			(at -12.192 -9.79805 90)
			(unlocked yes)
			(layer "F.SilkS")
			(effects
				(font
					(size 0.635 0.4064)
					(thickness 0.1524)
				)
			)
		)
		(fp_text user "B"
			(at -13.1445 -9.294368 90)
			(unlocked yes)
			(layer "F.SilkS")
			(effects
				(font
					(size 0.635 0.4064)
					(thickness 0.1524)
				)
			)
		)
		(fp_text user "C"
			(at -12.5095 -8.024368 90)
			(unlocked yes)
			(layer "F.SilkS")
			(effects
				(font
					(size 0.635 0.4064)
					(thickness 0.1524)
				)
			)
		)
		(fp_text user "D"
			(at -13.1445 -6.754368 90)
			(unlocked yes)
			(layer "F.SilkS")
			(effects
				(font
					(size 0.635 0.4064)
					(thickness 0.1524)
				)
			)
		)
		(fp_text user "E"
			(at -12.5095 -5.611368 90)
			(unlocked yes)
			(layer "F.SilkS")
			(effects
				(font
					(size 0.635 0.4064)
					(thickness 0.1524)
				)
			)
		)
		(fp_text user "F"
			(at -13.208 -4.66725 90)
			(unlocked yes)
			(layer "F.SilkS")
			(effects
				(font
					(size 0.635 0.4064)
					(thickness 0.1524)
				)
			)
		)
		(fp_text user "G"
			(at -12.5095 -3.579368 90)
			(unlocked yes)
			(layer "F.SilkS")
			(effects
				(font
					(size 0.635 0.4064)
					(thickness 0.1524)
				)
			)
		)
		(fp_text user "H"
			(at -13.1445 -2.563368 90)
			(unlocked yes)
			(layer "F.SilkS")
			(effects
				(font
					(size 0.635 0.4064)
					(thickness 0.1524)
				)
			)
		)
		(fp_text user "J"
			(at -12.5095 -1.674368 90)
			(unlocked yes)
			(layer "F.SilkS")
			(effects
				(font
					(size 0.635 0.4064)
					(thickness 0.1524)
				)
			)
		)
		(fp_text user "K"
			(at -13.1445 -0.912368 90)
			(unlocked yes)
			(layer "F.SilkS")
			(effects
				(font
					(size 0.635 0.4064)
					(thickness 0.1524)
				)
			)
		)
		(fp_text user "L"
			(at -12.5095 -0.023368 90)
			(unlocked yes)
			(layer "F.SilkS")
			(effects
				(font
					(size 0.635 0.4064)
					(thickness 0.1524)
				)
			)
		)
		(fp_text user "M"
			(at -13.1445 0.738632 90)
			(unlocked yes)
			(layer "F.SilkS")
			(effects
				(font
					(size 0.635 0.4064)
					(thickness 0.1524)
				)
			)
		)
		(fp_text user "N"
			(at -12.5095 1.881632 90)
			(unlocked yes)
			(layer "F.SilkS")
			(effects
				(font
					(size 0.635 0.4064)
					(thickness 0.1524)
				)
			)
		)
		(fp_text user "P"
			(at -13.1445 2.516632 90)
			(unlocked yes)
			(layer "F.SilkS")
			(effects
				(font
					(size 0.635 0.4064)
					(thickness 0.1524)
				)
			)
		)
		(fp_text user "R"
			(at -12.5095 3.659632 90)
			(unlocked yes)
			(layer "F.SilkS")
			(effects
				(font
					(size 0.635 0.4064)
					(thickness 0.1524)
				)
			)
		)
		(fp_text user "T"
			(at -13.1445 4.421632 90)
			(unlocked yes)
			(layer "F.SilkS")
			(effects
				(font
					(size 0.635 0.4064)
					(thickness 0.1524)
				)
			)
		)
		(fp_text user "U"
			(at -12.5095 5.310632 90)
			(unlocked yes)
			(layer "F.SilkS")
			(effects
				(font
					(size 0.635 0.4064)
					(thickness 0.1524)
				)
			)
		)
		(fp_text user "V"
			(at -13.1445 6.326632 90)
			(unlocked yes)
			(layer "F.SilkS")
			(effects
				(font
					(size 0.635 0.4064)
					(thickness 0.1524)
				)
			)
		)
		(fp_text user "W"
			(at -12.5095 7.342632 90)
			(unlocked yes)
			(layer "F.SilkS")
			(effects
				(font
					(size 0.635 0.4064)
					(thickness 0.1524)
				)
			)
		)
		(fp_text user "Y"
			(at -13.1445 8.104632 90)
			(unlocked yes)
			(layer "F.SilkS")
			(effects
				(font
					(size 0.635 0.4064)
					(thickness 0.1524)
				)
			)
		)
		(fp_text user "AA"
			(at -12.8905 9.306052 90)
			(unlocked yes)
			(layer "F.SilkS")
			(effects
				(font
					(size 0.7874 0.5842)
					(thickness 0.1524)
				)
			)
		)
		(fp_text user "AB"
			(at -12.90828 10.642092 90)
			(unlocked yes)
			(layer "F.SilkS")
			(effects
				(font
					(size 0.635 0.4064)
					(thickness 0.1524)
				)
			)
		)
		(fp_text user "22"
			(at 10.28446 -13.581888 90)
			(unlocked yes)
			(layer "F.Fab")
			(effects
				(font
					(size 0.7874 0.5842)
					(thickness 0.1524)
				)
			)
		)
		(fp_text user "20"
			(at 8.25246 -13.581888 90)
			(unlocked yes)
			(layer "F.Fab")
			(effects
				(font
					(size 0.7874 0.5842)
					(thickness 0.1524)
				)
			)
		)
		(fp_text user "18"
			(at 6.09346 -13.581888 90)
			(unlocked yes)
			(layer "F.Fab")
			(effects
				(font
					(size 0.7874 0.5842)
					(thickness 0.1524)
				)
			)
		)
		(fp_text user "16"
			(at 4.18846 -13.581888 90)
			(unlocked yes)
			(layer "F.Fab")
			(effects
				(font
					(size 0.7874 0.5842)
					(thickness 0.1524)
				)
			)
		)
		(fp_text user "14"
			(at 2.15646 -13.581888 90)
			(unlocked yes)
			(layer "F.Fab")
			(effects
				(font
					(size 0.7874 0.5842)
					(thickness 0.1524)
				)
			)
		)
		(fp_text user "12"
			(at 0.12446 -13.581888 90)
			(unlocked yes)
			(layer "F.Fab")
			(effects
				(font
					(size 0.7874 0.5842)
					(thickness 0.1524)
				)
			)
		)
		(fp_text user "10"
			(at -1.65354 -13.581888 90)
			(unlocked yes)
			(layer "F.Fab")
			(effects
				(font
					(size 0.7874 0.5842)
					(thickness 0.1524)
				)
			)
		)
		(fp_text user "8"
			(at -3.43154 -13.581888 90)
			(unlocked yes)
			(layer "F.Fab")
			(effects
				(font
					(size 0.7874 0.5842)
					(thickness 0.1524)
				)
			)
		)
		(fp_text user "6"
			(at -5.33654 -13.581888 90)
			(unlocked yes)
			(layer "F.Fab")
			(effects
				(font
					(size 0.7874 0.5842)
					(thickness 0.1524)
				)
			)
		)
		(fp_text user "4"
			(at -7.49554 -13.581888 90)
			(unlocked yes)
			(layer "F.Fab")
			(effects
				(font
					(size 0.7874 0.5842)
					(thickness 0.1524)
				)
			)
		)
		(fp_text user "2"
			(at -9.40054 -13.581888 90)
			(unlocked yes)
			(layer "F.Fab")
			(effects
				(font
					(size 0.7874 0.5842)
					(thickness 0.1524)
				)
			)
		)
		(fp_text user "21"
			(at 9.39546 -12.438888 90)
			(unlocked yes)
			(layer "F.Fab")
			(effects
				(font
					(size 0.7874 0.5842)
					(thickness 0.1524)
				)
			)
		)
		(fp_text user "19"
			(at 7.23646 -12.438888 90)
			(unlocked yes)
			(layer "F.Fab")
			(effects
				(font
					(size 0.7874 0.5842)
					(thickness 0.1524)
				)
			)
		)
		(fp_text user "17"
			(at 5.33146 -12.438888 90)
			(unlocked yes)
			(layer "F.Fab")
			(effects
				(font
					(size 0.7874 0.5842)
					(thickness 0.1524)
				)
			)
		)
		(fp_text user "15"
			(at 3.29946 -12.438888 90)
			(unlocked yes)
			(layer "F.Fab")
			(effects
				(font
					(size 0.7874 0.5842)
					(thickness 0.1524)
				)
			)
		)
		(fp_text user "13"
			(at 1.26746 -12.438888 90)
			(unlocked yes)
			(layer "F.Fab")
			(effects
				(font
					(size 0.7874 0.5842)
					(thickness 0.1524)
				)
			)
		)
		(fp_text user "11"
			(at -0.76454 -12.438888 90)
			(unlocked yes)
			(layer "F.Fab")
			(effects
				(font
					(size 0.7874 0.5842)
					(thickness 0.1524)
				)
			)
		)
		(fp_text user "9"
			(at -2.28854 -12.438888 90)
			(unlocked yes)
			(layer "F.Fab")
			(effects
				(font
					(size 0.7874 0.5842)
					(thickness 0.1524)
				)
			)
		)
		(fp_text user "7"
			(at -4.19354 -12.438888 90)
			(unlocked yes)
			(layer "F.Fab")
			(effects
				(font
					(size 0.7874 0.5842)
					(thickness 0.1524)
				)
			)
		)
		(fp_text user "5"
			(at -6.22554 -12.438888 90)
			(unlocked yes)
			(layer "F.Fab")
			(effects
				(font
					(size 0.7874 0.5842)
					(thickness 0.1524)
				)
			)
		)
		(fp_text user "3"
			(at -8.25754 -12.438888 90)
			(unlocked yes)
			(layer "F.Fab")
			(effects
				(font
					(size 0.7874 0.5842)
					(thickness 0.1524)
				)
			)
		)
		(fp_text user "1"
			(at -10.28954 -12.438888 90)
			(unlocked yes)
			(layer "F.Fab")
			(effects
				(font
					(size 0.7874 0.5842)
					(thickness 0.1524)
				)
			)
		)
		(fp_text user "A"
			(at -12.3825 -10.378948 90)
			(unlocked yes)
			(layer "F.Fab")
			(effects
				(font
					(size 0.7874 0.5842)
					(thickness 0.1524)
				)
			)
		)
		(fp_text user "B"
			(at -13.1445 -9.362948 90)
			(unlocked yes)
			(layer "F.Fab")
			(effects
				(font
					(size 0.7874 0.5842)
					(thickness 0.1524)
				)
			)
		)
		(fp_text user "C"
			(at -12.3825 -8.092948 90)
			(unlocked yes)
			(layer "F.Fab")
			(effects
				(font
					(size 0.7874 0.5842)
					(thickness 0.1524)
				)
			)
		)
		(fp_text user "D"
			(at -13.1445 -6.822948 90)
			(unlocked yes)
			(layer "F.Fab")
			(effects
				(font
					(size 0.7874 0.5842)
					(thickness 0.1524)
				)
			)
		)
		(fp_text user "E"
			(at -12.3825 -5.679948 90)
			(unlocked yes)
			(layer "F.Fab")
			(effects
				(font
					(size 0.7874 0.5842)
					(thickness 0.1524)
				)
			)
		)
		(fp_text user "F"
			(at -13.1445 -4.663948 90)
			(unlocked yes)
			(layer "F.Fab")
			(effects
				(font
					(size 0.7874 0.5842)
					(thickness 0.1524)
				)
			)
		)
		(fp_text user "G"
			(at -12.3825 -3.647948 90)
			(unlocked yes)
			(layer "F.Fab")
			(effects
				(font
					(size 0.7874 0.5842)
					(thickness 0.1524)
				)
			)
		)
		(fp_text user "H"
			(at -13.1445 -2.631948 90)
			(unlocked yes)
			(layer "F.Fab")
			(effects
				(font
					(size 0.7874 0.5842)
					(thickness 0.1524)
				)
			)
		)
		(fp_text user "J"
			(at -12.3825 -1.742948 90)
			(unlocked yes)
			(layer "F.Fab")
			(effects
				(font
					(size 0.7874 0.5842)
					(thickness 0.1524)
				)
			)
		)
		(fp_text user "K"
			(at -13.1445 -0.980948 90)
			(unlocked yes)
			(layer "F.Fab")
			(effects
				(font
					(size 0.7874 0.5842)
					(thickness 0.1524)
				)
			)
		)
		(fp_text user "L"
			(at -12.3825 -0.091948 90)
			(unlocked yes)
			(layer "F.Fab")
			(effects
				(font
					(size 0.7874 0.5842)
					(thickness 0.1524)
				)
			)
		)
		(fp_text user "M"
			(at -13.1445 0.670052 90)
			(unlocked yes)
			(layer "F.Fab")
			(effects
				(font
					(size 0.7874 0.5842)
					(thickness 0.1524)
				)
			)
		)
		(fp_text user "N"
			(at -12.3825 1.813052 90)
			(unlocked yes)
			(layer "F.Fab")
			(effects
				(font
					(size 0.7874 0.5842)
					(thickness 0.1524)
				)
			)
		)
		(fp_text user "P"
			(at -13.1445 2.448052 90)
			(unlocked yes)
			(layer "F.Fab")
			(effects
				(font
					(size 0.7874 0.5842)
					(thickness 0.1524)
				)
			)
		)
		(fp_text user "R"
			(at -12.3825 3.591052 90)
			(unlocked yes)
			(layer "F.Fab")
			(effects
				(font
					(size 0.7874 0.5842)
					(thickness 0.1524)
				)
			)
		)
		(fp_text user "T"
			(at -13.1445 4.353052 90)
			(unlocked yes)
			(layer "F.Fab")
			(effects
				(font
					(size 0.7874 0.5842)
					(thickness 0.1524)
				)
			)
		)
		(fp_text user "U"
			(at -12.3825 5.242052 90)
			(unlocked yes)
			(layer "F.Fab")
			(effects
				(font
					(size 0.7874 0.5842)
					(thickness 0.1524)
				)
			)
		)
		(fp_text user "V"
			(at -13.1445 6.258052 90)
			(unlocked yes)
			(layer "F.Fab")
			(effects
				(font
					(size 0.7874 0.5842)
					(thickness 0.1524)
				)
			)
		)
		(fp_text user "W"
			(at -12.3825 7.274052 90)
			(unlocked yes)
			(layer "F.Fab")
			(effects
				(font
					(size 0.7874 0.5842)
					(thickness 0.1524)
				)
			)
		)
		(fp_text user "Y"
			(at -13.1445 8.036052 90)
			(unlocked yes)
			(layer "F.Fab")
			(effects
				(font
					(size 0.7874 0.5842)
					(thickness 0.1524)
				)
			)
		)
		(fp_text user "AA"
			(at -12.7635 9.306052 90)
			(unlocked yes)
			(layer "F.Fab")
			(effects
				(font
					(size 0.7874 0.5842)
					(thickness 0.1524)
				)
			)
		)
		(fp_text user "AB"
			(at -12.78128 10.573512 90)
			(unlocked yes)
			(layer "F.Fab")
			(effects
				(font
					(size 0.7874 0.5842)
					(thickness 0.1524)
				)
			)
		)
		(pad "A1" smd circle
			(at -10.500106 -10.500106 90)
			(size 0.50038 0.50038)
			(layers "F.Cu" "F.Mask" "F.Paste")
			(net "Net_124")
		)
		(pad "A2" smd circle
			(at -9.500108 -10.500106 90)
			(size 0.50038 0.50038)
			(layers "F.Cu" "F.Mask" "F.Paste")
			(net "SG")
		)
		(pad "A3" smd circle
			(at -8.50011 -10.500106 90)
			(size 0.50038 0.50038)
			(layers "F.Cu" "F.Mask" "F.Paste")
			(net "SG")
		)
		(pad "A4" smd circle
			(at -7.499858 -10.500106 90)
			(size 0.50038 0.50038)
			(layers "F.Cu" "F.Mask" "F.Paste")
			(net "CPU_RX_PCIE_MGT0_TXN")
		)
		(pad "A5" smd circle
			(at -6.49986 -10.500106 90)
			(size 0.50038 0.50038)
			(layers "F.Cu" "F.Mask" "F.Paste")
			(net "SG")
		)
		(pad "A6" smd circle
			(at -5.499862 -10.500106 90)
			(size 0.50038 0.50038)
			(layers "F.Cu" "F.Mask" "F.Paste")
			(net "CPU_RX_PCIE_MGT2_TXN")
		)
		(pad "A7" smd circle
			(at -4.499864 -10.500106 90)
			(size 0.50038 0.50038)
			(layers "F.Cu" "F.Mask" "F.Paste")
			(net "SG")
		)
		(pad "A8" smd circle
			(at -3.499866 -10.500106 90)
			(size 0.50038 0.50038)
			(layers "F.Cu" "F.Mask" "F.Paste")
			(net "CPU_TX_PCIE_MGT_0_RXN")
		)
		(pad "A9" smd circle
			(at -2.499868 -10.500106 90)
			(size 0.50038 0.50038)
			(layers "F.Cu" "F.Mask" "F.Paste")
			(net "SG")
		)
		(pad "A10" smd circle
			(at -1.49987 -10.500106 90)
			(size 0.50038 0.50038)
			(layers "F.Cu" "F.Mask" "F.Paste")
			(net "CPU_TX_PCIE_MGT_2_RXN")
		)
		(pad "A11" smd circle
			(at -0.499872 -10.500106 90)
			(size 0.50038 0.50038)
			(layers "F.Cu" "F.Mask" "F.Paste")
			(net "SG")
		)
		(pad "A12" smd circle
			(at 0.500126 -10.500106 90)
			(size 0.50038 0.50038)
			(layers "F.Cu" "F.Mask" "F.Paste")
			(net "SG")
		)
		(pad "A13" smd circle
			(at 1.500124 -10.500106 90)
			(size 0.50038 0.50038)
			(layers "F.Cu" "F.Mask" "F.Paste")
			(net "FPGA_USR_LED1")
		)
		(pad "A14" smd circle
			(at 2.500122 -10.500106 90)
			(size 0.50038 0.50038)
			(layers "F.Cu" "F.Mask" "F.Paste")
			(net "FPGA_USR_LED0")
		)
		(pad "A15" smd circle
			(at 3.50012 -10.500106 90)
			(size 0.50038 0.50038)
			(layers "F.Cu" "F.Mask" "F.Paste")
			(net "Net_85")
		)
		(pad "A16" smd circle
			(at 4.500118 -10.500106 90)
			(size 0.50038 0.50038)
			(layers "F.Cu" "F.Mask" "F.Paste")
			(net "Net_83")
		)
		(pad "A17" smd circle
			(at 5.500116 -10.500106 90)
			(size 0.50038 0.50038)
			(layers "F.Cu" "F.Mask" "F.Paste")
			(net "XP3R3V_FPGA")
		)
		(pad "A18" smd circle
			(at 6.500114 -10.500106 90)
			(size 0.50038 0.50038)
			(layers "F.Cu" "F.Mask" "F.Paste")
			(net "FPGA_OUT_GPS_LED_RED_N")
		)
		(pad "A19" smd circle
			(at 7.500112 -10.500106 90)
			(size 0.50038 0.50038)
			(layers "F.Cu" "F.Mask" "F.Paste")
			(net "Net_48")
		)
		(pad "A20" smd circle
			(at 8.50011 -10.500106 90)
			(size 0.50038 0.50038)
			(layers "F.Cu" "F.Mask" "F.Paste")
			(net "FPGA_OUT_GPS_LED_GREEN_N")
		)
		(pad "A21" smd circle
			(at 9.500108 -10.500106 90)
			(size 0.50038 0.50038)
			(layers "F.Cu" "F.Mask" "F.Paste")
			(net "IO_L21N_16")
		)
		(pad "A22" smd circle
			(at 10.500106 -10.500106 90)
			(size 0.50038 0.50038)
			(layers "F.Cu" "F.Mask" "F.Paste")
			(net "SG")
		)
		(pad "AA1" smd circle
			(at -10.500106 9.500108 90)
			(size 0.50038 0.50038)
			(layers "F.Cu" "F.Mask" "F.Paste")
			(net "Net_154")
		)
		(pad "AA2" smd circle
			(at -9.500108 9.500108 90)
			(size 0.50038 0.50038)
			(layers "F.Cu" "F.Mask" "F.Paste")
			(net "SG")
		)
		(pad "AA3" smd circle
			(at -8.50011 9.500108 90)
			(size 0.50038 0.50038)
			(layers "F.Cu" "F.Mask" "F.Paste")
			(net "Net_158")
		)
		(pad "AA4" smd circle
			(at -7.499858 9.500108 90)
			(size 0.50038 0.50038)
			(layers "F.Cu" "F.Mask" "F.Paste")
			(net "Net_94")
		)
		(pad "AA5" smd circle
			(at -6.49986 9.500108 90)
			(size 0.50038 0.50038)
			(layers "F.Cu" "F.Mask" "F.Paste")
			(net "FPGA_OUT_MAC_PPS_IN1P")
		)
		(pad "AA6" smd circle
			(at -5.499862 9.500108 90)
			(size 0.50038 0.50038)
			(layers "F.Cu" "F.Mask" "F.Paste")
			(net "Net_52")
		)
		(pad "AA7" smd circle
			(at -4.499864 9.500108 90)
			(size 0.50038 0.50038)
			(layers "F.Cu" "F.Mask" "F.Paste")
			(net "XP2R5V_FPGA")
		)
		(pad "AA8" smd circle
			(at -3.499866 9.500108 90)
			(size 0.50038 0.50038)
			(layers "F.Cu" "F.Mask" "F.Paste")
			(net "IO_L22P_34")
		)
		(pad "AA9" smd circle
			(at -2.499868 9.500108 90)
			(size 0.50038 0.50038)
			(layers "F.Cu" "F.Mask" "F.Paste")
			(net "FPGA_IN_MAC_BITEOUT")
		)
		(pad "AA10" smd circle
			(at -1.49987 9.500108 90)
			(size 0.50038 0.50038)
			(layers "F.Cu" "F.Mask" "F.Paste")
			(net "Net_177")
		)
		(pad "AA11" smd circle
			(at -0.499872 9.500108 90)
			(size 0.50038 0.50038)
			(layers "F.Cu" "F.Mask" "F.Paste")
			(net "Net_176")
		)
		(pad "AA12" smd circle
			(at 0.500126 9.500108 90)
			(size 0.50038 0.50038)
			(layers "F.Cu" "F.Mask" "F.Paste")
			(net "SG")
		)
		(pad "AA13" smd circle
			(at 1.500124 9.500108 90)
			(size 0.50038 0.50038)
			(layers "F.Cu" "F.Mask" "F.Paste")
			(net "FPGA_OUT_SN_EEPROM_WP")
		)
		(pad "AA14" smd circle
			(at 2.500122 9.500108 90)
			(size 0.50038 0.50038)
			(layers "F.Cu" "F.Mask" "F.Paste")
			(net "Net_140")
		)
		(pad "AA15" smd circle
			(at 3.50012 9.500108 90)
			(size 0.50038 0.50038)
			(layers "F.Cu" "F.Mask" "F.Paste")
			(net "FPGA_IO_FT_USBDET_RST_N")
		)
		(pad "AA16" smd circle
			(at 4.500118 9.500108 90)
			(size 0.50038 0.50038)
			(layers "F.Cu" "F.Mask" "F.Paste")
			(net "Net_60")
		)
		(pad "AA17" smd circle
			(at 5.500116 9.500108 90)
			(size 0.50038 0.50038)
			(layers "F.Cu" "F.Mask" "F.Paste")
			(net "XP3R3V_FPGA")
		)
		(pad "AA18" smd circle
			(at 6.500114 9.500108 90)
			(size 0.50038 0.50038)
			(layers "F.Cu" "F.Mask" "F.Paste")
			(net "UART_MAC_RX_FPGA_TX")
		)
		(pad "AA19" smd circle
			(at 7.500112 9.500108 90)
			(size 0.50038 0.50038)
			(layers "F.Cu" "F.Mask" "F.Paste")
			(net "Net_42")
		)
		(pad "AA20" smd circle
			(at 8.50011 9.500108 90)
			(size 0.50038 0.50038)
			(layers "F.Cu" "F.Mask" "F.Paste")
			(net "ANT2_IN")
		)
		(pad "AA21" smd circle
			(at 9.500108 9.500108 90)
			(size 0.50038 0.50038)
			(layers "F.Cu" "F.Mask" "F.Paste")
			(net "ANT1_IN")
		)
		(pad "AA22" smd circle
			(at 10.500106 9.500108 90)
			(size 0.50038 0.50038)
			(layers "F.Cu" "F.Mask" "F.Paste")
			(net "SG")
		)
		(pad "AB1" smd circle
			(at -10.500106 10.500106 90)
			(size 0.50038 0.50038)
			(layers "F.Cu" "F.Mask" "F.Paste")
			(net "Net_151")
		)
		(pad "AB2" smd circle
			(at -9.500108 10.500106 90)
			(size 0.50038 0.50038)
			(layers "F.Cu" "F.Mask" "F.Paste")
			(net "FPGA_OUT_MAC_PPS_IN0N")
		)
		(pad "AB3" smd circle
			(at -8.50011 10.500106 90)
			(size 0.50038 0.50038)
			(layers "F.Cu" "F.Mask" "F.Paste")
			(net "FPGA_OUT_MAC_PPS_IN0P")
		)
		(pad "AB4" smd circle
			(at -7.499858 10.500106 90)
			(size 0.50038 0.50038)
			(layers "F.Cu" "F.Mask" "F.Paste")
			(net "XP2R5V_FPGA")
		)
		(pad "AB5" smd circle
			(at -6.49986 10.500106 90)
			(size 0.50038 0.50038)
			(layers "F.Cu" "F.Mask" "F.Paste")
			(net "FPGA_OUT_MAC_PPS_IN1N")
		)
		(pad "AB6" smd circle
			(at -5.499862 10.500106 90)
			(size 0.50038 0.50038)
			(layers "F.Cu" "F.Mask" "F.Paste")
			(net "IO_L20N_34")
		)
		(pad "AB7" smd circle
			(at -4.499864 10.500106 90)
			(size 0.50038 0.50038)
			(layers "F.Cu" "F.Mask" "F.Paste")
			(net "IO_L20P_34")
		)
		(pad "AB8" smd circle
			(at -3.499866 10.500106 90)
			(size 0.50038 0.50038)
			(layers "F.Cu" "F.Mask" "F.Paste")
			(net "IO_L22N_34")
		)
		(pad "AB9" smd circle
			(at -2.499868 10.500106 90)
			(size 0.50038 0.50038)
			(layers "F.Cu" "F.Mask" "F.Paste")
			(net "SG")
		)
		(pad "AB10" smd circle
			(at -1.49987 10.500106 90)
			(size 0.50038 0.50038)
			(layers "F.Cu" "F.Mask" "F.Paste")
			(net "FPGA_IN_MAC_ALARM_OUT_N")
		)
		(pad "AB11" smd circle
			(at -0.499872 10.500106 90)
			(size 0.50038 0.50038)
			(layers "F.Cu" "F.Mask" "F.Paste")
			(net "Net_153")
		)
		(pad "AB12" smd circle
			(at 0.500126 10.500106 90)
			(size 0.50038 0.50038)
			(layers "F.Cu" "F.Mask" "F.Paste")
			(net "Net_150")
		)
		(pad "AB13" smd circle
			(at 1.500124 10.500106 90)
			(size 0.50038 0.50038)
			(layers "F.Cu" "F.Mask" "F.Paste")
			(net "FPGA_OUT_SEC_EEPROM_WP")
		)
		(pad "AB14" smd circle
			(at 2.500122 10.500106 90)
			(size 0.50038 0.50038)
			(layers "F.Cu" "F.Mask" "F.Paste")
			(net "XP3R3V_FPGA")
		)
		(pad "AB15" smd circle
			(at 3.50012 10.500106 90)
			(size 0.50038 0.50038)
			(layers "F.Cu" "F.Mask" "F.Paste")
			(net "Net_71")
		)
		(pad "AB16" smd circle
			(at 4.500118 10.500106 90)
			(size 0.50038 0.50038)
			(layers "F.Cu" "F.Mask" "F.Paste")
			(net "FPGA_EEPROM_I2C_SCL")
		)
		(pad "AB17" smd circle
			(at 5.500116 10.500106 90)
			(size 0.50038 0.50038)
			(layers "F.Cu" "F.Mask" "F.Paste")
			(net "FPGA_EEPROM_I2C_SDA")
		)
		(pad "AB18" smd circle
			(at 6.500114 10.500106 90)
			(size 0.50038 0.50038)
			(layers "F.Cu" "F.Mask" "F.Paste")
			(net "UART_MAC_TX_FPGA_RX")
		)
		(pad "AB19" smd circle
			(at 7.500112 10.500106 90)
			(size 0.50038 0.50038)
			(layers "F.Cu" "F.Mask" "F.Paste")
			(net "SG")
		)
		(pad "AB20" smd circle
			(at 8.50011 10.500106 90)
			(size 0.50038 0.50038)
			(layers "F.Cu" "F.Mask" "F.Paste")
			(net "Net_39")
		)
		(pad "AB21" smd circle
			(at 9.500108 10.500106 90)
			(size 0.50038 0.50038)
			(layers "F.Cu" "F.Mask" "F.Paste")
			(net "Net_163")
		)
		(pad "AB22" smd circle
			(at 10.500106 10.500106 90)
			(size 0.50038 0.50038)
			(layers "F.Cu" "F.Mask" "F.Paste")
			(net "Net_162")
		)
		(pad "B1" smd circle
			(at -10.500106 -9.500108 90)
			(size 0.50038 0.50038)
			(layers "F.Cu" "F.Mask" "F.Paste")
			(net "Net_126")
		)
		(pad "B2" smd circle
			(at -9.500108 -9.500108 90)
			(size 0.50038 0.50038)
			(layers "F.Cu" "F.Mask" "F.Paste")
			(net "Net_129")
		)
		(pad "B3" smd circle
			(at -8.50011 -9.500108 90)
			(size 0.50038 0.50038)
			(layers "F.Cu" "F.Mask" "F.Paste")
			(net "SG")
		)
		(pad "B4" smd circle
			(at -7.499858 -9.500108 90)
			(size 0.50038 0.50038)
			(layers "F.Cu" "F.Mask" "F.Paste")
			(net "CPU_RX_PCIE_MGT0_TXP")
		)
		(pad "B5" smd circle
			(at -6.49986 -9.500108 90)
			(size 0.50038 0.50038)
			(layers "F.Cu" "F.Mask" "F.Paste")
			(net "FPGA_MGTAVTT")
		)
		(pad "B6" smd circle
			(at -5.499862 -9.500108 90)
			(size 0.50038 0.50038)
			(layers "F.Cu" "F.Mask" "F.Paste")
			(net "CPU_RX_PCIE_MGT2_TXP")
		)
		(pad "B7" smd circle
			(at -4.499864 -9.500108 90)
			(size 0.50038 0.50038)
			(layers "F.Cu" "F.Mask" "F.Paste")
			(net "FPGA_MGTAVTT")
		)
		(pad "B8" smd circle
			(at -3.499866 -9.500108 90)
			(size 0.50038 0.50038)
			(layers "F.Cu" "F.Mask" "F.Paste")
			(net "CPU_TX_PCIE_MGT_0_RXP")
		)
		(pad "B9" smd circle
			(at -2.499868 -9.500108 90)
			(size 0.50038 0.50038)
			(layers "F.Cu" "F.Mask" "F.Paste")
			(net "FPGA_MGTAVTT")
		)
		(pad "B10" smd circle
			(at -1.49987 -9.500108 90)
			(size 0.50038 0.50038)
			(layers "F.Cu" "F.Mask" "F.Paste")
			(net "CPU_TX_PCIE_MGT_2_RXP")
		)
		(pad "B11" smd circle
			(at -0.499872 -9.500108 90)
			(size 0.50038 0.50038)
			(layers "F.Cu" "F.Mask" "F.Paste")
			(net "FPGA_MGTAVTT")
		)
		(pad "B12" smd circle
			(at 0.500126 -9.500108 90)
			(size 0.50038 0.50038)
			(layers "F.Cu" "F.Mask" "F.Paste")
			(net "SG")
		)
		(pad "B13" smd circle
			(at 1.500124 -9.500108 90)
			(size 0.50038 0.50038)
			(layers "F.Cu" "F.Mask" "F.Paste")
			(net "LED_DATOUT0")
		)
		(pad "B14" smd circle
			(at 2.500122 -9.500108 90)
			(size 0.50038 0.50038)
			(layers "F.Cu" "F.Mask" "F.Paste")
			(net "XP3R3V_FPGA")
		)
		(pad "B15" smd circle
			(at 3.50012 -9.500108 90)
			(size 0.50038 0.50038)
			(layers "F.Cu" "F.Mask" "F.Paste")
			(net "Net_81")
		)
		(pad "B16" smd circle
			(at 4.500118 -9.500108 90)
			(size 0.50038 0.50038)
			(layers "F.Cu" "F.Mask" "F.Paste")
			(net "Net_80")
		)
		(pad "B17" smd circle
			(at 5.500116 -9.500108 90)
			(size 0.50038 0.50038)
			(layers "F.Cu" "F.Mask" "F.Paste")
			(net "Net_32")
		)
		(pad "B18" smd circle
			(at 6.500114 -9.500108 90)
			(size 0.50038 0.50038)
			(layers "F.Cu" "F.Mask" "F.Paste")
			(net "Net_31")
		)
		(pad "B19" smd circle
			(at 7.500112 -9.500108 90)
			(size 0.50038 0.50038)
			(layers "F.Cu" "F.Mask" "F.Paste")
			(net "SG")
		)
		(pad "B20" smd circle
			(at 8.50011 -9.500108 90)
			(size 0.50038 0.50038)
			(layers "F.Cu" "F.Mask" "F.Paste")
			(net "FPGA_OUT_GPS_LED_BLUE_N")
		)
		(pad "B21" smd circle
			(at 9.500108 -9.500108 90)
			(size 0.50038 0.50038)
			(layers "F.Cu" "F.Mask" "F.Paste")
			(net "IO_L21P_16")
		)
		(pad "B22" smd circle
			(at 10.500106 -9.500108 90)
			(size 0.50038 0.50038)
			(layers "F.Cu" "F.Mask" "F.Paste")
			(net "IO_L20N_16")
		)
		(pad "C1" smd circle
			(at -10.500106 -8.50011 90)
			(size 0.50038 0.50038)
			(layers "F.Cu" "F.Mask" "F.Paste")
			(net "XP2R5V_FPGA")
		)
		(pad "C2" smd circle
			(at -9.500108 -8.50011 90)
			(size 0.50038 0.50038)
			(layers "F.Cu" "F.Mask" "F.Paste")
			(net "Net_131")
		)
		(pad "C3" smd circle
			(at -8.50011 -8.50011 90)
			(size 0.50038 0.50038)
			(layers "F.Cu" "F.Mask" "F.Paste")
			(net "SG")
		)
		(pad "C4" smd circle
			(at -7.499858 -8.50011 90)
			(size 0.50038 0.50038)
			(layers "F.Cu" "F.Mask" "F.Paste")
			(net "FPGA_MGTAVTT")
		)
		(pad "C5" smd circle
			(at -6.49986 -8.50011 90)
			(size 0.50038 0.50038)
			(layers "F.Cu" "F.Mask" "F.Paste")
			(net "CPU_RX_PCIE_MGT1_TXN")
		)
		(pad "C6" smd circle
			(at -5.499862 -8.50011 90)
			(size 0.50038 0.50038)
			(layers "F.Cu" "F.Mask" "F.Paste")
			(net "SG")
		)
		(pad "C7" smd circle
			(at -4.499864 -8.50011 90)
			(size 0.50038 0.50038)
			(layers "F.Cu" "F.Mask" "F.Paste")
			(net "CPU_RX_PCIE_MGT3_TXN")
		)
		(pad "C8" smd circle
			(at -3.499866 -8.50011 90)
			(size 0.50038 0.50038)
			(layers "F.Cu" "F.Mask" "F.Paste")
			(net "FPGA_MGTAVTT")
		)
		(pad "C9" smd circle
			(at -2.499868 -8.50011 90)
			(size 0.50038 0.50038)
			(layers "F.Cu" "F.Mask" "F.Paste")
			(net "CPU_TX_PCIE_MGT_3_RXN")
		)
		(pad "C10" smd circle
			(at -1.49987 -8.50011 90)
			(size 0.50038 0.50038)
			(layers "F.Cu" "F.Mask" "F.Paste")
			(net "SG")
		)
		(pad "C11" smd circle
			(at -0.499872 -8.50011 90)
			(size 0.50038 0.50038)
			(layers "F.Cu" "F.Mask" "F.Paste")
			(net "CPU_TX_PCIE_MGT_1_RXN")
		)
		(pad "C12" smd circle
			(at 0.500126 -8.50011 90)
			(size 0.50038 0.50038)
			(layers "F.Cu" "F.Mask" "F.Paste")
			(net "SG")
		)
		(pad "C13" smd circle
			(at 1.500124 -8.50011 90)
			(size 0.50038 0.50038)
			(layers "F.Cu" "F.Mask" "F.Paste")
			(net "LED_DATOUT1")
		)
		(pad "C14" smd circle
			(at 2.500122 -8.50011 90)
			(size 0.50038 0.50038)
			(layers "F.Cu" "F.Mask" "F.Paste")
			(net "FPGA_OUT_SMA2_LED_BLUE_N")
		)
		(pad "C15" smd circle
			(at 3.50012 -8.50011 90)
			(size 0.50038 0.50038)
			(layers "F.Cu" "F.Mask" "F.Paste")
			(net "FPGA_OUT_SMA2_LED_GREEN_N")
		)
		(pad "C16" smd circle
			(at 4.500118 -8.50011 90)
			(size 0.50038 0.50038)
			(layers "F.Cu" "F.Mask" "F.Paste")
			(net "SG")
		)
		(pad "C17" smd circle
			(at 5.500116 -8.50011 90)
			(size 0.50038 0.50038)
			(layers "F.Cu" "F.Mask" "F.Paste")
			(net "FPGA_OUT_SMA3_LED_GREEN_N")
		)
		(pad "C18" smd circle
			(at 6.500114 -8.50011 90)
			(size 0.50038 0.50038)
			(layers "F.Cu" "F.Mask" "F.Paste")
			(net "FPGA_OUT_SMA3_LED_RED_N")
		)
		(pad "C19" smd circle
			(at 7.500112 -8.50011 90)
			(size 0.50038 0.50038)
			(layers "F.Cu" "F.Mask" "F.Paste")
			(net "Net_34")
		)
		(pad "C20" smd circle
			(at 8.50011 -8.50011 90)
			(size 0.50038 0.50038)
			(layers "F.Cu" "F.Mask" "F.Paste")
			(net "Net_56")
		)
		(pad "C21" smd circle
			(at 9.500108 -8.50011 90)
			(size 0.50038 0.50038)
			(layers "F.Cu" "F.Mask" "F.Paste")
			(net "XP3R3V_FPGA")
		)
		(pad "C22" smd circle
			(at 10.500106 -8.50011 90)
			(size 0.50038 0.50038)
			(layers "F.Cu" "F.Mask" "F.Paste")
			(net "IO_L20P_16")
		)
		(pad "D1" smd circle
			(at -10.500106 -7.499858 90)
			(size 0.50038 0.50038)
			(layers "F.Cu" "F.Mask" "F.Paste")
			(net "Net_133")
		)
		(pad "D2" smd circle
			(at -9.500108 -7.499858 90)
			(size 0.50038 0.50038)
			(layers "F.Cu" "F.Mask" "F.Paste")
			(net "Net_137")
		)
		(pad "D3" smd circle
			(at -8.50011 -7.499858 90)
			(size 0.50038 0.50038)
			(layers "F.Cu" "F.Mask" "F.Paste")
			(net "SG")
		)
		(pad "D4" smd circle
			(at -7.499858 -7.499858 90)
			(size 0.50038 0.50038)
			(layers "F.Cu" "F.Mask" "F.Paste")
			(net "SG")
		)
		(pad "D5" smd circle
			(at -6.49986 -7.499858 90)
			(size 0.50038 0.50038)
			(layers "F.Cu" "F.Mask" "F.Paste")
			(net "CPU_RX_PCIE_MGT1_TXP")
		)
		(pad "D6" smd circle
			(at -5.499862 -7.499858 90)
			(size 0.50038 0.50038)
			(layers "F.Cu" "F.Mask" "F.Paste")
			(net "XP1R0V_FPGA_MGTAVCC")
		)
		(pad "D7" smd circle
			(at -4.499864 -7.499858 90)
			(size 0.50038 0.50038)
			(layers "F.Cu" "F.Mask" "F.Paste")
			(net "CPU_RX_PCIE_MGT3_TXP")
		)
		(pad "D8" smd circle
			(at -3.499866 -7.499858 90)
			(size 0.50038 0.50038)
			(layers "F.Cu" "F.Mask" "F.Paste")
			(net "SG")
		)
		(pad "D9" smd circle
			(at -2.499868 -7.499858 90)
			(size 0.50038 0.50038)
			(layers "F.Cu" "F.Mask" "F.Paste")
			(net "CPU_TX_PCIE_MGT_3_RXP")
		)
		(pad "D10" smd circle
			(at -1.49987 -7.499858 90)
			(size 0.50038 0.50038)
			(layers "F.Cu" "F.Mask" "F.Paste")
			(net "XP1R0V_FPGA_MGTAVCC")
		)
		(pad "D11" smd circle
			(at -0.499872 -7.499858 90)
			(size 0.50038 0.50038)
			(layers "F.Cu" "F.Mask" "F.Paste")
			(net "CPU_TX_PCIE_MGT_1_RXP")
		)
		(pad "D12" smd circle
			(at 0.500126 -7.499858 90)
			(size 0.50038 0.50038)
			(layers "F.Cu" "F.Mask" "F.Paste")
			(net "SG")
		)
		(pad "D13" smd circle
			(at 1.500124 -7.499858 90)
			(size 0.50038 0.50038)
			(layers "F.Cu" "F.Mask" "F.Paste")
			(net "SG")
		)
		(pad "D14" smd circle
			(at 2.500122 -7.499858 90)
			(size 0.50038 0.50038)
			(layers "F.Cu" "F.Mask" "F.Paste")
			(net "LED_DATOUT2")
		)
		(pad "D15" smd circle
			(at 3.50012 -7.499858 90)
			(size 0.50038 0.50038)
			(layers "F.Cu" "F.Mask" "F.Paste")
			(net "LED_DATOUT3")
		)
		(pad "D16" smd circle
			(at 4.500118 -7.499858 90)
			(size 0.50038 0.50038)
			(layers "F.Cu" "F.Mask" "F.Paste")
			(net "Net_75")
		)
		(pad "D17" smd circle
			(at 5.500116 -7.499858 90)
			(size 0.50038 0.50038)
			(layers "F.Cu" "F.Mask" "F.Paste")
			(net "FPGA_OUT_SMA3_LED_BLUE_N")
		)
		(pad "D18" smd circle
			(at 6.500114 -7.499858 90)
			(size 0.50038 0.50038)
			(layers "F.Cu" "F.Mask" "F.Paste")
			(net "XP3R3V_FPGA")
		)
		(pad "D19" smd circle
			(at 7.500112 -7.499858 90)
			(size 0.50038 0.50038)
			(layers "F.Cu" "F.Mask" "F.Paste")
			(net "FPGA_OUT_SMA4_LED_GREEN_N")
		)
		(pad "D20" smd circle
			(at 8.50011 -7.499858 90)
			(size 0.50038 0.50038)
			(layers "F.Cu" "F.Mask" "F.Paste")
			(net "Net_58")
		)
		(pad "D21" smd circle
			(at 9.500108 -7.499858 90)
			(size 0.50038 0.50038)
			(layers "F.Cu" "F.Mask" "F.Paste")
			(net "IO_L23N_16")
		)
		(pad "D22" smd circle
			(at 10.500106 -7.499858 90)
			(size 0.50038 0.50038)
			(layers "F.Cu" "F.Mask" "F.Paste")
			(net "IO_L22N_16")
		)
		(pad "E1" smd circle
			(at -10.500106 -6.49986 90)
			(size 0.50038 0.50038)
			(layers "F.Cu" "F.Mask" "F.Paste")
			(net "Net_135")
		)
		(pad "E2" smd circle
			(at -9.500108 -6.49986 90)
			(size 0.50038 0.50038)
			(layers "F.Cu" "F.Mask" "F.Paste")
			(net "Net_139")
		)
		(pad "E3" smd circle
			(at -8.50011 -6.49986 90)
			(size 0.50038 0.50038)
			(layers "F.Cu" "F.Mask" "F.Paste")
			(net "Net_147")
		)
		(pad "E4" smd circle
			(at -7.499858 -6.49986 90)
			(size 0.50038 0.50038)
			(layers "F.Cu" "F.Mask" "F.Paste")
			(net "SG")
		)
		(pad "E5" smd circle
			(at -6.49986 -6.49986 90)
			(size 0.50038 0.50038)
			(layers "F.Cu" "F.Mask" "F.Paste")
			(net "SG")
		)
		(pad "E6" smd circle
			(at -5.499862 -6.49986 90)
			(size 0.50038 0.50038)
			(layers "F.Cu" "F.Mask" "F.Paste")
			(net "MHZ125CLKN_CLKIN")
		)
		(pad "E7" smd circle
			(at -4.499864 -6.49986 90)
			(size 0.50038 0.50038)
			(layers "F.Cu" "F.Mask" "F.Paste")
			(net "SG")
		)
		(pad "E8" smd circle
			(at -3.499866 -6.49986 90)
			(size 0.50038 0.50038)
			(layers "F.Cu" "F.Mask" "F.Paste")
			(net "XP1R0V_FPGA_MGTAVCC")
		)
		(pad "E9" smd circle
			(at -2.499868 -6.49986 90)
			(size 0.50038 0.50038)
			(layers "F.Cu" "F.Mask" "F.Paste")
			(net "SG")
		)
		(pad "E10" smd circle
			(at -1.49987 -6.49986 90)
			(size 0.50038 0.50038)
			(layers "F.Cu" "F.Mask" "F.Paste")
			(net "PCIE_REFCLKN")
		)
		(pad "E11" smd circle
			(at -0.499872 -6.49986 90)
			(size 0.50038 0.50038)
			(layers "F.Cu" "F.Mask" "F.Paste")
			(net "SG")
		)
		(pad "E12" smd circle
			(at 0.500126 -6.49986 90)
			(size 0.50038 0.50038)
			(layers "F.Cu" "F.Mask" "F.Paste")
			(net "XP1R8V_FPGA_VCCAUX")
		)
		(pad "E13" smd circle
			(at 1.500124 -6.49986 90)
			(size 0.50038 0.50038)
			(layers "F.Cu" "F.Mask" "F.Paste")
			(net "FPGA_OUT_SMA2_LED_RED_N")
		)
		(pad "E14" smd circle
			(at 2.500122 -6.49986 90)
			(size 0.50038 0.50038)
			(layers "F.Cu" "F.Mask" "F.Paste")
			(net "Net_86")
		)
		(pad "E15" smd circle
			(at 3.50012 -6.49986 90)
			(size 0.50038 0.50038)
			(layers "F.Cu" "F.Mask" "F.Paste")
			(net "XP3R3V_FPGA")
		)
		(pad "E16" smd circle
			(at 4.500118 -6.49986 90)
			(size 0.50038 0.50038)
			(layers "F.Cu" "F.Mask" "F.Paste")
			(net "Net_76")
		)
		(pad "E17" smd circle
			(at 5.500116 -6.49986 90)
			(size 0.50038 0.50038)
			(layers "F.Cu" "F.Mask" "F.Paste")
			(net "Net_69")
		)
		(pad "E18" smd circle
			(at 6.500114 -6.49986 90)
			(size 0.50038 0.50038)
			(layers "F.Cu" "F.Mask" "F.Paste")
			(net "Net_40")
		)
		(pad "E19" smd circle
			(at 7.500112 -6.49986 90)
			(size 0.50038 0.50038)
			(layers "F.Cu" "F.Mask" "F.Paste")
			(net "FPGA_OUT_SMA4_LED_BLUE_N")
		)
		(pad "E20" smd circle
			(at 8.50011 -6.49986 90)
			(size 0.50038 0.50038)
			(layers "F.Cu" "F.Mask" "F.Paste")
			(net "SG")
		)
		(pad "E21" smd circle
			(at 9.500108 -6.49986 90)
			(size 0.50038 0.50038)
			(layers "F.Cu" "F.Mask" "F.Paste")
			(net "IO_L23P_16")
		)
		(pad "E22" smd circle
			(at 10.500106 -6.49986 90)
			(size 0.50038 0.50038)
			(layers "F.Cu" "F.Mask" "F.Paste")
			(net "IO_L22P_16")
		)
		(pad "F1" smd circle
			(at -10.500106 -5.499862 90)
			(size 0.50038 0.50038)
			(layers "F.Cu" "F.Mask" "F.Paste")
			(net "Net_142")
		)
		(pad "F2" smd circle
			(at -9.500108 -5.499862 90)
			(size 0.50038 0.50038)
			(layers "F.Cu" "F.Mask" "F.Paste")
			(net "XP2R5V_FPGA")
		)
		(pad "F3" smd circle
			(at -8.50011 -5.499862 90)
			(size 0.50038 0.50038)
			(layers "F.Cu" "F.Mask" "F.Paste")
			(net "Net_149")
		)
		(pad "F4" smd circle
			(at -7.499858 -5.499862 90)
			(size 0.50038 0.50038)
			(layers "F.Cu" "F.Mask" "F.Paste")
			(net "Net_87")
		)
		(pad "F5" smd circle
			(at -6.49986 -5.499862 90)
			(size 0.50038 0.50038)
			(layers "F.Cu" "F.Mask" "F.Paste")
			(net "SG")
		)
		(pad "F6" smd circle
			(at -5.499862 -5.499862 90)
			(size 0.50038 0.50038)
			(layers "F.Cu" "F.Mask" "F.Paste")
			(net "MHZ125CLKP_CLKIN")
		)
		(pad "F7" smd circle
			(at -4.499864 -5.499862 90)
			(size 0.50038 0.50038)
			(layers "F.Cu" "F.Mask" "F.Paste")
			(net "XP1R0V_FPGA_MGTAVCC")
		)
		(pad "F8" smd circle
			(at -3.499866 -5.499862 90)
			(size 0.50038 0.50038)
			(layers "F.Cu" "F.Mask" "F.Paste")
			(net "FPGA_MGTRREF")
		)
		(pad "F9" smd circle
			(at -2.499868 -5.499862 90)
			(size 0.50038 0.50038)
			(layers "F.Cu" "F.Mask" "F.Paste")
			(net "XP1R0V_FPGA_MGTAVCC")
		)
		(pad "F10" smd circle
			(at -1.49987 -5.499862 90)
			(size 0.50038 0.50038)
			(layers "F.Cu" "F.Mask" "F.Paste")
			(net "PCIE_REFCLKP")
		)
		(pad "F11" smd circle
			(at -0.499872 -5.499862 90)
			(size 0.50038 0.50038)
			(layers "F.Cu" "F.Mask" "F.Paste")
			(net "SG")
		)
		(pad "F12" smd circle
			(at 0.500126 -5.499862 90)
			(size 0.50038 0.50038)
			(layers "F.Cu" "F.Mask" "F.Paste")
			(net "XP3R3V_FPGA")
		)
		(pad "F13" smd circle
			(at 1.500124 -5.499862 90)
			(size 0.50038 0.50038)
			(layers "F.Cu" "F.Mask" "F.Paste")
			(net "FPGA_OUT_SMA1_LED_BLUE_N")
		)
		(pad "F14" smd circle
			(at 2.500122 -5.499862 90)
			(size 0.50038 0.50038)
			(layers "F.Cu" "F.Mask" "F.Paste")
			(net "FPGA_OUT_SMA1_LED_GREEN_N")
		)
		(pad "F15" smd circle
			(at 3.50012 -5.499862 90)
			(size 0.50038 0.50038)
			(layers "F.Cu" "F.Mask" "F.Paste")
			(net "Net_28")
		)
		(pad "F16" smd circle
			(at 4.500118 -5.499862 90)
			(size 0.50038 0.50038)
			(layers "F.Cu" "F.Mask" "F.Paste")
			(net "FPGA_OUT_SMA1_LED_RED_N")
		)
		(pad "F17" smd circle
			(at 5.500116 -5.499862 90)
			(size 0.50038 0.50038)
			(layers "F.Cu" "F.Mask" "F.Paste")
			(net "SG")
		)
		(pad "F18" smd circle
			(at 6.500114 -5.499862 90)
			(size 0.50038 0.50038)
			(layers "F.Cu" "F.Mask" "F.Paste")
			(net "FPGA_OUT_SMA4_LED_RED_N")
		)
		(pad "F19" smd circle
			(at 7.500112 -5.499862 90)
			(size 0.50038 0.50038)
			(layers "F.Cu" "F.Mask" "F.Paste")
			(net "Net_54")
		)
		(pad "F20" smd circle
			(at 8.50011 -5.499862 90)
			(size 0.50038 0.50038)
			(layers "F.Cu" "F.Mask" "F.Paste")
			(net "Net_51")
		)
		(pad "F21" smd circle
			(at 9.500108 -5.499862 90)
			(size 0.50038 0.50038)
			(layers "F.Cu" "F.Mask" "F.Paste")
			(net "Net_30")
		)
		(pad "F22" smd circle
			(at 10.500106 -5.499862 90)
			(size 0.50038 0.50038)
			(layers "F.Cu" "F.Mask" "F.Paste")
			(net "XP3R3V_FPGA")
		)
		(pad "G1" smd circle
			(at -10.500106 -4.499864 90)
			(size 0.50038 0.50038)
			(layers "F.Cu" "F.Mask" "F.Paste")
			(net "Net_145")
		)
		(pad "G2" smd circle
			(at -9.500108 -4.499864 90)
			(size 0.50038 0.50038)
			(layers "F.Cu" "F.Mask" "F.Paste")
			(net "Net_156")
		)
		(pad "G3" smd circle
			(at -8.50011 -4.499864 90)
			(size 0.50038 0.50038)
			(layers "F.Cu" "F.Mask" "F.Paste")
			(net "Net_95")
		)
		(pad "G4" smd circle
			(at -7.499858 -4.499864 90)
			(size 0.50038 0.50038)
			(layers "F.Cu" "F.Mask" "F.Paste")
			(net "Net_99")
		)
		(pad "G5" smd circle
			(at -6.49986 -4.499864 90)
			(size 0.50038 0.50038)
			(layers "F.Cu" "F.Mask" "F.Paste")
			(net "SG")
		)
		(pad "G6" smd circle
			(at -5.499862 -4.499864 90)
			(size 0.50038 0.50038)
			(layers "F.Cu" "F.Mask" "F.Paste")
			(net "SG")
		)
		(pad "G7" smd circle
			(at -4.499864 -4.499864 90)
			(size 0.50038 0.50038)
			(layers "F.Cu" "F.Mask" "F.Paste")
			(net "SG")
		)
		(pad "G8" smd circle
			(at -3.499866 -4.499864 90)
			(size 0.50038 0.50038)
			(layers "F.Cu" "F.Mask" "F.Paste")
			(net "SG")
		)
		(pad "G9" smd circle
			(at -2.499868 -4.499864 90)
			(size 0.50038 0.50038)
			(layers "F.Cu" "F.Mask" "F.Paste")
			(net "SG")
		)
		(pad "G10" smd circle
			(at -1.49987 -4.499864 90)
			(size 0.50038 0.50038)
			(layers "F.Cu" "F.Mask" "F.Paste")
			(net "SG")
		)
		(pad "G11" smd circle
			(at -0.499872 -4.499864 90)
			(size 0.50038 0.50038)
			(layers "F.Cu" "F.Mask" "F.Paste")
			(net "FPGA_DONE")
		)
		(pad "G12" smd circle
			(at 0.500126 -4.499864 90)
			(size 0.50038 0.50038)
			(layers "F.Cu" "F.Mask" "F.Paste")
			(net "SG")
		)
		(pad "G13" smd circle
			(at 1.500124 -4.499864 90)
			(size 0.50038 0.50038)
			(layers "F.Cu" "F.Mask" "F.Paste")
			(net "FPGA_OUT_MUX2_SEL")
		)
		(pad "G14" smd circle
			(at 2.500122 -4.499864 90)
			(size 0.50038 0.50038)
			(layers "F.Cu" "F.Mask" "F.Paste")
			(net "SG")
		)
		(pad "G15" smd circle
			(at 3.50012 -4.499864 90)
			(size 0.50038 0.50038)
			(layers "F.Cu" "F.Mask" "F.Paste")
			(net "FPGA_OUT_MUX3_SEL")
		)
		(pad "G16" smd circle
			(at 4.500118 -4.499864 90)
			(size 0.50038 0.50038)
			(layers "F.Cu" "F.Mask" "F.Paste")
			(net "Net_68")
		)
		(pad "G17" smd circle
			(at 5.500116 -4.499864 90)
			(size 0.50038 0.50038)
			(layers "F.Cu" "F.Mask" "F.Paste")
			(net "Net_173")
		)
		(pad "G18" smd circle
			(at 6.500114 -4.499864 90)
			(size 0.50038 0.50038)
			(layers "F.Cu" "F.Mask" "F.Paste")
			(net "Net_73")
		)
		(pad "G19" smd circle
			(at 7.500112 -4.499864 90)
			(size 0.50038 0.50038)
			(layers "F.Cu" "F.Mask" "F.Paste")
			(net "XP3R3V_FPGA")
		)
		(pad "G20" smd circle
			(at 8.50011 -4.499864 90)
			(size 0.50038 0.50038)
			(layers "F.Cu" "F.Mask" "F.Paste")
			(net "FPGA_IO_3")
		)
		(pad "G21" smd circle
			(at 9.500108 -4.499864 90)
			(size 0.50038 0.50038)
			(layers "F.Cu" "F.Mask" "F.Paste")
			(net "IO_L24P_16")
		)
		(pad "G22" smd circle
			(at 10.500106 -4.499864 90)
			(size 0.50038 0.50038)
			(layers "F.Cu" "F.Mask" "F.Paste")
			(net "IO_L24N_16")
		)
		(pad "H1" smd circle
			(at -10.500106 -3.499866 90)
			(size 0.50038 0.50038)
			(layers "F.Cu" "F.Mask" "F.Paste")
			(net "SG")
		)
		(pad "H2" smd circle
			(at -9.500108 -3.499866 90)
			(size 0.50038 0.50038)
			(layers "F.Cu" "F.Mask" "F.Paste")
			(net "Net_157")
		)
		(pad "H3" smd circle
			(at -8.50011 -3.499866 90)
			(size 0.50038 0.50038)
			(layers "F.Cu" "F.Mask" "F.Paste")
			(net "Net_97")
		)
		(pad "H4" smd circle
			(at -7.499858 -3.499866 90)
			(size 0.50038 0.50038)
			(layers "F.Cu" "F.Mask" "F.Paste")
			(net "Net_101")
		)
		(pad "H5" smd circle
			(at -6.49986 -3.499866 90)
			(size 0.50038 0.50038)
			(layers "F.Cu" "F.Mask" "F.Paste")
			(net "Net_91")
		)
		(pad "H6" smd circle
			(at -5.499862 -3.499866 90)
			(size 0.50038 0.50038)
			(layers "F.Cu" "F.Mask" "F.Paste")
			(net "XP2R5V_FPGA")
		)
		(pad "H7" smd circle
			(at -4.499864 -3.499866 90)
			(size 0.50038 0.50038)
			(layers "F.Cu" "F.Mask" "F.Paste")
			(net "SG")
		)
		(pad "H8" smd circle
			(at -3.499866 -3.499866 90)
			(size 0.50038 0.50038)
			(layers "F.Cu" "F.Mask" "F.Paste")
			(net "XP1R0V_FPGA_VCCINT")
		)
		(pad "H9" smd circle
			(at -2.499868 -3.499866 90)
			(size 0.50038 0.50038)
			(layers "F.Cu" "F.Mask" "F.Paste")
			(net "SG")
		)
		(pad "H10" smd circle
			(at -1.49987 -3.499866 90)
			(size 0.50038 0.50038)
			(layers "F.Cu" "F.Mask" "F.Paste")
			(net "XP1R0V_FPGA_VCCINT")
		)
		(pad "H11" smd circle
			(at -0.499872 -3.499866 90)
			(size 0.50038 0.50038)
			(layers "F.Cu" "F.Mask" "F.Paste")
			(net "SG")
		)
		(pad "H12" smd circle
			(at 0.500126 -3.499866 90)
			(size 0.50038 0.50038)
			(layers "F.Cu" "F.Mask" "F.Paste")
			(net "XP1R8V_FPGA_VCCAUX")
		)
		(pad "H13" smd circle
			(at 1.500124 -3.499866 90)
			(size 0.50038 0.50038)
			(layers "F.Cu" "F.Mask" "F.Paste")
			(net "FPGA_OUT_MUX1_SEL")
		)
		(pad "H14" smd circle
			(at 2.500122 -3.499866 90)
			(size 0.50038 0.50038)
			(layers "F.Cu" "F.Mask" "F.Paste")
			(net "SMA4_SIG_OUT_BF_EN_N")
		)
		(pad "H15" smd circle
			(at 3.50012 -3.499866 90)
			(size 0.50038 0.50038)
			(layers "F.Cu" "F.Mask" "F.Paste")
			(net "SMA3_SIG_IN_BF_EN_N")
		)
		(pad "H16" smd circle
			(at 4.500118 -3.499866 90)
			(size 0.50038 0.50038)
			(layers "F.Cu" "F.Mask" "F.Paste")
			(net "XP3R3V_FPGA")
		)
		(pad "H17" smd circle
			(at 5.500116 -3.499866 90)
			(size 0.50038 0.50038)
			(layers "F.Cu" "F.Mask" "F.Paste")
			(net "Net_174")
		)
		(pad "H18" smd circle
			(at 6.500114 -3.499866 90)
			(size 0.50038 0.50038)
			(layers "F.Cu" "F.Mask" "F.Paste")
			(net "Net_78")
		)
		(pad "H19" smd circle
			(at 7.500112 -3.499866 90)
			(size 0.50038 0.50038)
			(layers "F.Cu" "F.Mask" "F.Paste")
			(net "FPGA_OUT_SHT3X_RST_N")
		)
		(pad "H20" smd circle
			(at 8.50011 -3.499866 90)
			(size 0.50038 0.50038)
			(layers "F.Cu" "F.Mask" "F.Paste")
			(net "FPGA_IO_2")
		)
		(pad "H21" smd circle
			(at 9.500108 -3.499866 90)
			(size 0.50038 0.50038)
			(layers "F.Cu" "F.Mask" "F.Paste")
			(net "SG")
		)
		(pad "H22" smd circle
			(at 10.500106 -3.499866 90)
			(size 0.50038 0.50038)
			(layers "F.Cu" "F.Mask" "F.Paste")
			(net "FPGA_IO_1")
		)
		(pad "J1" smd circle
			(at -10.500106 -2.499868 90)
			(size 0.50038 0.50038)
			(layers "F.Cu" "F.Mask" "F.Paste")
			(net "Net_152")
		)
		(pad "J2" smd circle
			(at -9.500108 -2.499868 90)
			(size 0.50038 0.50038)
			(layers "F.Cu" "F.Mask" "F.Paste")
			(net "Net_159")
		)
		(pad "J3" smd circle
			(at -8.50011 -2.499868 90)
			(size 0.50038 0.50038)
			(layers "F.Cu" "F.Mask" "F.Paste")
			(net "XP2R5V_FPGA")
		)
		(pad "J4" smd circle
			(at -7.499858 -2.499868 90)
			(size 0.50038 0.50038)
			(layers "F.Cu" "F.Mask" "F.Paste")
			(net "Net_102")
		)
		(pad "J5" smd circle
			(at -6.49986 -2.499868 90)
			(size 0.50038 0.50038)
			(layers "F.Cu" "F.Mask" "F.Paste")
			(net "Net_92")
		)
		(pad "J6" smd circle
			(at -5.499862 -2.499868 90)
			(size 0.50038 0.50038)
			(layers "F.Cu" "F.Mask" "F.Paste")
			(net "Net_116")
		)
		(pad "J7" smd circle
			(at -4.499864 -2.499868 90)
			(size 0.50038 0.50038)
			(layers "F.Cu" "F.Mask" "F.Paste")
			(net "XP1R0V_FPGA_VCCINT")
		)
		(pad "J8" smd circle
			(at -3.499866 -2.499868 90)
			(size 0.50038 0.50038)
			(layers "F.Cu" "F.Mask" "F.Paste")
			(net "SG")
		)
		(pad "J9" smd circle
			(at -2.499868 -2.499868 90)
			(size 0.50038 0.50038)
			(layers "F.Cu" "F.Mask" "F.Paste")
			(net "XP1R0V_FPGA_VCCINT")
		)
		(pad "J10" smd circle
			(at -1.49987 -2.499868 90)
			(size 0.50038 0.50038)
			(layers "F.Cu" "F.Mask" "F.Paste")
			(net "SG")
		)
		(pad "J11" smd circle
			(at -0.499872 -2.499868 90)
			(size 0.50038 0.50038)
			(layers "F.Cu" "F.Mask" "F.Paste")
			(net "XP1R0V_FPGA_VCCINT")
		)
		(pad "J12" smd circle
			(at 0.500126 -2.499868 90)
			(size 0.50038 0.50038)
			(layers "F.Cu" "F.Mask" "F.Paste")
			(net "SG")
		)
		(pad "J13" smd circle
			(at 1.500124 -2.499868 90)
			(size 0.50038 0.50038)
			(layers "F.Cu" "F.Mask" "F.Paste")
			(net "XP3R3V_FPGA")
		)
		(pad "J14" smd circle
			(at 2.500122 -2.499868 90)
			(size 0.50038 0.50038)
			(layers "F.Cu" "F.Mask" "F.Paste")
			(net "SMA4_SIG_IN_BF_EN_N")
		)
		(pad "J15" smd circle
			(at 3.50012 -2.499868 90)
			(size 0.50038 0.50038)
			(layers "F.Cu" "F.Mask" "F.Paste")
			(net "SMA3_SIG_OUT_BF_EN_N")
		)
		(pad "J16" smd circle
			(at 4.500118 -2.499868 90)
			(size 0.50038 0.50038)
			(layers "F.Cu" "F.Mask" "F.Paste")
			(net "Net_90")
		)
		(pad "J17" smd circle
			(at 5.500116 -2.499868 90)
			(size 0.50038 0.50038)
			(layers "F.Cu" "F.Mask" "F.Paste")
			(net "FPGA_OUT_BNO080_RST_N")
		)
		(pad "J18" smd circle
			(at 6.500114 -2.499868 90)
			(size 0.50038 0.50038)
			(layers "F.Cu" "F.Mask" "F.Paste")
			(net "SG")
		)
		(pad "J19" smd circle
			(at 7.500112 -2.499868 90)
			(size 0.50038 0.50038)
			(layers "F.Cu" "F.Mask" "F.Paste")
			(net "FPGA_IN_SHT3X_ALERT_N")
		)
		(pad "J20" smd circle
			(at 8.50011 -2.499868 90)
			(size 0.50038 0.50038)
			(layers "F.Cu" "F.Mask" "F.Paste")
			(net "FPGA_IN_RST_DLY_N")
		)
		(pad "J21" smd circle
			(at 9.500108 -2.499868 90)
			(size 0.50038 0.50038)
			(layers "F.Cu" "F.Mask" "F.Paste")
			(net "Net_93")
		)
		(pad "J22" smd circle
			(at 10.500106 -2.499868 90)
			(size 0.50038 0.50038)
			(layers "F.Cu" "F.Mask" "F.Paste")
			(net "FPGA_IO_0")
		)
		(pad "K1" smd circle
			(at -10.500106 -1.49987 90)
			(size 0.50038 0.50038)
			(layers "F.Cu" "F.Mask" "F.Paste")
			(net "Net_155")
		)
		(pad "K2" smd circle
			(at -9.500108 -1.49987 90)
			(size 0.50038 0.50038)
			(layers "F.Cu" "F.Mask" "F.Paste")
			(net "Net_161")
		)
		(pad "K3" smd circle
			(at -8.50011 -1.49987 90)
			(size 0.50038 0.50038)
			(layers "F.Cu" "F.Mask" "F.Paste")
			(net "Net_105")
		)
		(pad "K4" smd circle
			(at -7.499858 -1.49987 90)
			(size 0.50038 0.50038)
			(layers "F.Cu" "F.Mask" "F.Paste")
			(net "Net_103")
		)
		(pad "K5" smd circle
			(at -6.49986 -1.49987 90)
			(size 0.50038 0.50038)
			(layers "F.Cu" "F.Mask" "F.Paste")
			(net "SG")
		)
		(pad "K6" smd circle
			(at -5.499862 -1.49987 90)
			(size 0.50038 0.50038)
			(layers "F.Cu" "F.Mask" "F.Paste")
			(net "Net_118")
		)
		(pad "K7" smd circle
			(at -4.499864 -1.49987 90)
			(size 0.50038 0.50038)
			(layers "F.Cu" "F.Mask" "F.Paste")
			(net "SG")
		)
		(pad "K8" smd circle
			(at -3.499866 -1.49987 90)
			(size 0.50038 0.50038)
			(layers "F.Cu" "F.Mask" "F.Paste")
			(net "XP1R0V_FPGA_VCCINT")
		)
		(pad "K9" smd circle
			(at -2.499868 -1.49987 90)
			(size 0.50038 0.50038)
			(layers "F.Cu" "F.Mask" "F.Paste")
			(net "SG")
		)
		(pad "K10" smd circle
			(at -1.49987 -1.49987 90)
			(size 0.50038 0.50038)
			(layers "F.Cu" "F.Mask" "F.Paste")
			(net "XP1R8V_FPGA_VCCAUX")
		)
		(pad "K11" smd circle
			(at -0.499872 -1.49987 90)
			(size 0.50038 0.50038)
			(layers "F.Cu" "F.Mask" "F.Paste")
			(net "SG")
		)
		(pad "K12" smd circle
			(at 0.500126 -1.49987 90)
			(size 0.50038 0.50038)
			(layers "F.Cu" "F.Mask" "F.Paste")
			(net "XP1R8V_FPGA_VCCAUX")
		)
		(pad "K13" smd circle
			(at 1.500124 -1.49987 90)
			(size 0.50038 0.50038)
			(layers "F.Cu" "F.Mask" "F.Paste")
			(net "SMA1_SIG_OUT_BF_EN_N")
		)
		(pad "K14" smd circle
			(at 2.500122 -1.49987 90)
			(size 0.50038 0.50038)
			(layers "F.Cu" "F.Mask" "F.Paste")
			(net "SMA1_SIG_IN_BF_EN_N")
		)
		(pad "K15" smd circle
			(at 3.50012 -1.49987 90)
			(size 0.50038 0.50038)
			(layers "F.Cu" "F.Mask" "F.Paste")
			(net "SG")
		)
		(pad "K16" smd circle
			(at 4.500118 -1.49987 90)
			(size 0.50038 0.50038)
			(layers "F.Cu" "F.Mask" "F.Paste")
			(net "FPGA_OUT_I2C_BUFFER_EN")
		)
		(pad "K17" smd circle
			(at 5.500116 -1.49987 90)
			(size 0.50038 0.50038)
			(layers "F.Cu" "F.Mask" "F.Paste")
			(net "Net_171")
		)
		(pad "K18" smd circle
			(at 6.500114 -1.49987 90)
			(size 0.50038 0.50038)
			(layers "F.Cu" "F.Mask" "F.Paste")
			(net "Net_35")
		)
		(pad "K19" smd circle
			(at 7.500112 -1.49987 90)
			(size 0.50038 0.50038)
			(layers "F.Cu" "F.Mask" "F.Paste")
			(net "Net_33")
		)
		(pad "K20" smd circle
			(at 8.50011 -1.49987 90)
			(size 0.50038 0.50038)
			(layers "F.Cu" "F.Mask" "F.Paste")
			(net "XP3R3V_FPGA")
		)
		(pad "K21" smd circle
			(at 9.500108 -1.49987 90)
			(size 0.50038 0.50038)
			(layers "F.Cu" "F.Mask" "F.Paste")
			(net "FPGA_IO_4")
		)
		(pad "K22" smd circle
			(at 10.500106 -1.49987 90)
			(size 0.50038 0.50038)
			(layers "F.Cu" "F.Mask" "F.Paste")
			(net "FPGA_IO_5")
		)
		(pad "L1" smd circle
			(at -10.500106 -0.499872 90)
			(size 0.50038 0.50038)
			(layers "F.Cu" "F.Mask" "F.Paste")
			(net "Net_109")
		)
		(pad "L2" smd circle
			(at -9.500108 -0.499872 90)
			(size 0.50038 0.50038)
			(layers "F.Cu" "F.Mask" "F.Paste")
			(net "SG")
		)
		(pad "L3" smd circle
			(at -8.50011 -0.499872 90)
			(size 0.50038 0.50038)
			(layers "F.Cu" "F.Mask" "F.Paste")
			(net "Net_107")
		)
		(pad "L4" smd circle
			(at -7.499858 -0.499872 90)
			(size 0.50038 0.50038)
			(layers "F.Cu" "F.Mask" "F.Paste")
			(net "Net_119")
		)
		(pad "L5" smd circle
			(at -6.49986 -0.499872 90)
			(size 0.50038 0.50038)
			(layers "F.Cu" "F.Mask" "F.Paste")
			(net "Net_120")
		)
		(pad "L6" smd circle
			(at -5.499862 -0.499872 90)
			(size 0.50038 0.50038)
			(layers "F.Cu" "F.Mask" "F.Paste")
			(net "Net_89")
		)
		(pad "L7" smd circle
			(at -4.499864 -0.499872 90)
			(size 0.50038 0.50038)
			(layers "F.Cu" "F.Mask" "F.Paste")
			(net "XP1R0V_FPGA_VCCINT")
		)
		(pad "L8" smd circle
			(at -3.499866 -0.499872 90)
			(size 0.50038 0.50038)
			(layers "F.Cu" "F.Mask" "F.Paste")
			(net "SG")
		)
		(pad "L9" smd circle
			(at -2.499868 -0.499872 90)
			(size 0.50038 0.50038)
			(layers "F.Cu" "F.Mask" "F.Paste")
			(net "SG")
		)
		(pad "L10" smd circle
			(at -1.49987 -0.499872 90)
			(size 0.50038 0.50038)
			(layers "F.Cu" "F.Mask" "F.Paste")
			(net "SG")
		)
		(pad "L11" smd circle
			(at -0.499872 -0.499872 90)
			(size 0.50038 0.50038)
			(layers "F.Cu" "F.Mask" "F.Paste")
			(net "XP1R0V_FPGA_VCCINT")
		)
		(pad "L12" smd circle
			(at 0.500126 -0.499872 90)
			(size 0.50038 0.50038)
			(layers "F.Cu" "F.Mask" "F.Paste")
			(net "CCLK_0")
		)
		(pad "L13" smd circle
			(at 1.500124 -0.499872 90)
			(size 0.50038 0.50038)
			(layers "F.Cu" "F.Mask" "F.Paste")
			(net "SMA2_SIG_IN_BF_EN_N")
		)
		(pad "L14" smd circle
			(at 2.500122 -0.499872 90)
			(size 0.50038 0.50038)
			(layers "F.Cu" "F.Mask" "F.Paste")
			(net "FPGA_IN_BNO080_INT_N")
		)
		(pad "L15" smd circle
			(at 3.50012 -0.499872 90)
			(size 0.50038 0.50038)
			(layers "F.Cu" "F.Mask" "F.Paste")
			(net "FPGA_OUT_BNO080_BOOT_N")
		)
		(pad "L16" smd circle
			(at 4.500118 -0.499872 90)
			(size 0.50038 0.50038)
			(layers "F.Cu" "F.Mask" "F.Paste")
			(net "Net_172")
		)
		(pad "L17" smd circle
			(at 5.500116 -0.499872 90)
			(size 0.50038 0.50038)
			(layers "F.Cu" "F.Mask" "F.Paste")
			(net "XP3R3V_FPGA")
		)
		(pad "L18" smd circle
			(at 6.500114 -0.499872 90)
			(size 0.50038 0.50038)
			(layers "F.Cu" "F.Mask" "F.Paste")
			(net "Net_45")
		)
		(pad "L19" smd circle
			(at 7.500112 -0.499872 90)
			(size 0.50038 0.50038)
			(layers "F.Cu" "F.Mask" "F.Paste")
			(net "Net_37")
		)
		(pad "L20" smd circle
			(at 8.50011 -0.499872 90)
			(size 0.50038 0.50038)
			(layers "F.Cu" "F.Mask" "F.Paste")
			(net "Net_36")
		)
		(pad "L21" smd circle
			(at 9.500108 -0.499872 90)
			(size 0.50038 0.50038)
			(layers "F.Cu" "F.Mask" "F.Paste")
			(net "FPGA_IO_7")
		)
		(pad "L22" smd circle
			(at 10.500106 -0.499872 90)
			(size 0.50038 0.50038)
			(layers "F.Cu" "F.Mask" "F.Paste")
			(net "SG")
		)
		(pad "M1" smd circle
			(at -10.500106 0.500126 90)
			(size 0.50038 0.50038)
			(layers "F.Cu" "F.Mask" "F.Paste")
			(net "Net_111")
		)
		(pad "M2" smd circle
			(at -9.500108 0.500126 90)
			(size 0.50038 0.50038)
			(layers "F.Cu" "F.Mask" "F.Paste")
			(net "Net_113")
		)
		(pad "M3" smd circle
			(at -8.50011 0.500126 90)
			(size 0.50038 0.50038)
			(layers "F.Cu" "F.Mask" "F.Paste")
			(net "Net_115")
		)
		(pad "M4" smd circle
			(at -7.499858 0.500126 90)
			(size 0.50038 0.50038)
			(layers "F.Cu" "F.Mask" "F.Paste")
			(net "XP2R5V_FPGA")
		)
		(pad "M5" smd circle
			(at -6.49986 0.500126 90)
			(size 0.50038 0.50038)
			(layers "F.Cu" "F.Mask" "F.Paste")
			(net "IO_L23N_35")
		)
		(pad "M6" smd circle
			(at -5.499862 0.500126 90)
			(size 0.50038 0.50038)
			(layers "F.Cu" "F.Mask" "F.Paste")
			(net "IO_L23P_35")
		)
		(pad "M7" smd circle
			(at -4.499864 0.500126 90)
			(size 0.50038 0.50038)
			(layers "F.Cu" "F.Mask" "F.Paste")
			(net "SG")
		)
		(pad "M8" smd circle
			(at -3.499866 0.500126 90)
			(size 0.50038 0.50038)
			(layers "F.Cu" "F.Mask" "F.Paste")
			(net "XP1R0V_FPGA_VCCINT")
		)
		(pad "M9" smd circle
			(at -2.499868 0.500126 90)
			(size 0.50038 0.50038)
			(layers "F.Cu" "F.Mask" "F.Paste")
			(net "SG")
		)
		(pad "M10" smd circle
			(at -1.49987 0.500126 90)
			(size 0.50038 0.50038)
			(layers "F.Cu" "F.Mask" "F.Paste")
			(net "SG")
		)
		(pad "M11" smd circle
			(at -0.499872 0.500126 90)
			(size 0.50038 0.50038)
			(layers "F.Cu" "F.Mask" "F.Paste")
			(net "SG")
		)
		(pad "M12" smd circle
			(at 0.500126 0.500126 90)
			(size 0.50038 0.50038)
			(layers "F.Cu" "F.Mask" "F.Paste")
			(net "XP1R8V_FPGA_VCCAUX")
		)
		(pad "M13" smd circle
			(at 1.500124 0.500126 90)
			(size 0.50038 0.50038)
			(layers "F.Cu" "F.Mask" "F.Paste")
			(net "SMA2_SIG_OUT_BF_EN_N")
		)
		(pad "M14" smd circle
			(at 2.500122 0.500126 90)
			(size 0.50038 0.50038)
			(layers "F.Cu" "F.Mask" "F.Paste")
			(net "XP3R3V_FPGA")
		)
		(pad "M15" smd circle
			(at 3.50012 0.500126 90)
			(size 0.50038 0.50038)
			(layers "F.Cu" "F.Mask" "F.Paste")
			(net "FPGA_IN_MAC_USB_OC_N")
		)
		(pad "M16" smd circle
			(at 4.500118 0.500126 90)
			(size 0.50038 0.50038)
			(layers "F.Cu" "F.Mask" "F.Paste")
			(net "RSVD_DBG_USB_MUX_SEL")
		)
		(pad "M17" smd circle
			(at 5.500116 0.500126 90)
			(size 0.50038 0.50038)
			(layers "F.Cu" "F.Mask" "F.Paste")
			(net "Net_127")
		)
		(pad "M18" smd circle
			(at 6.500114 0.500126 90)
			(size 0.50038 0.50038)
			(layers "F.Cu" "F.Mask" "F.Paste")
			(net "FPGA_IN_LM75B_INT3_N")
		)
		(pad "M19" smd circle
			(at 7.500112 0.500126 90)
			(size 0.50038 0.50038)
			(layers "F.Cu" "F.Mask" "F.Paste")
			(net "SG")
		)
		(pad "M20" smd circle
			(at 8.50011 0.500126 90)
			(size 0.50038 0.50038)
			(layers "F.Cu" "F.Mask" "F.Paste")
			(net "Net_50")
		)
		(pad "M21" smd circle
			(at 9.500108 0.500126 90)
			(size 0.50038 0.50038)
			(layers "F.Cu" "F.Mask" "F.Paste")
			(net "FPGA_IO_6")
		)
		(pad "M22" smd circle
			(at 10.500106 0.500126 90)
			(size 0.50038 0.50038)
			(layers "F.Cu" "F.Mask" "F.Paste")
			(net "FPGA_IN_LM75B_INT2_N")
		)
		(pad "N1" smd circle
			(at -10.500106 1.500124 90)
			(size 0.50038 0.50038)
			(layers "F.Cu" "F.Mask" "F.Paste")
			(net "XP2R5V_FPGA")
		)
		(pad "N2" smd circle
			(at -9.500108 1.500124 90)
			(size 0.50038 0.50038)
			(layers "F.Cu" "F.Mask" "F.Paste")
			(net "IO_L22N_35")
		)
		(pad "N3" smd circle
			(at -8.50011 1.500124 90)
			(size 0.50038 0.50038)
			(layers "F.Cu" "F.Mask" "F.Paste")
			(net "Net_121")
		)
		(pad "N4" smd circle
			(at -7.499858 1.500124 90)
			(size 0.50038 0.50038)
			(layers "F.Cu" "F.Mask" "F.Paste")
			(net "Net_122")
		)
		(pad "N5" smd circle
			(at -6.49986 1.500124 90)
			(size 0.50038 0.50038)
			(layers "F.Cu" "F.Mask" "F.Paste")
			(net "IO_L24N_35")
		)
		(pad "N6" smd circle
			(at -5.499862 1.500124 90)
			(size 0.50038 0.50038)
			(layers "F.Cu" "F.Mask" "F.Paste")
			(net "SG")
		)
		(pad "N7" smd circle
			(at -4.499864 1.500124 90)
			(size 0.50038 0.50038)
			(layers "F.Cu" "F.Mask" "F.Paste")
			(net "XP1R0V_FPGA_VCCINT")
		)
		(pad "N8" smd circle
			(at -3.499866 1.500124 90)
			(size 0.50038 0.50038)
			(layers "F.Cu" "F.Mask" "F.Paste")
			(net "SG")
		)
		(pad "N9" smd circle
			(at -2.499868 1.500124 90)
			(size 0.50038 0.50038)
			(layers "F.Cu" "F.Mask" "F.Paste")
			(net "SG")
		)
		(pad "N10" smd circle
			(at -1.49987 1.500124 90)
			(size 0.50038 0.50038)
			(layers "F.Cu" "F.Mask" "F.Paste")
			(net "SG")
		)
		(pad "N11" smd circle
			(at -0.499872 1.500124 90)
			(size 0.50038 0.50038)
			(layers "F.Cu" "F.Mask" "F.Paste")
			(net "XP1R0V_FPGA_VCCINT")
		)
		(pad "N12" smd circle
			(at 0.500126 1.500124 90)
			(size 0.50038 0.50038)
			(layers "F.Cu" "F.Mask" "F.Paste")
			(net "FPGA_PROGRAM_N")
		)
		(pad "N13" smd circle
			(at 1.500124 1.500124 90)
			(size 0.50038 0.50038)
			(layers "F.Cu" "F.Mask" "F.Paste")
			(net "Net_66")
		)
		(pad "N14" smd circle
			(at 2.500122 1.500124 90)
			(size 0.50038 0.50038)
			(layers "F.Cu" "F.Mask" "F.Paste")
			(net "Net_65")
		)
		(pad "N15" smd circle
			(at 3.50012 1.500124 90)
			(size 0.50038 0.50038)
			(layers "F.Cu" "F.Mask" "F.Paste")
			(net "UART_GPS_TX_FPGA_RX")
		)
		(pad "N16" smd circle
			(at 4.500118 1.500124 90)
			(size 0.50038 0.50038)
			(layers "F.Cu" "F.Mask" "F.Paste")
			(net "SG")
		)
		(pad "N17" smd circle
			(at 5.500116 1.500124 90)
			(size 0.50038 0.50038)
			(layers "F.Cu" "F.Mask" "F.Paste")
			(net "FPGA_PCA9546_I2C_SCL")
		)
		(pad "N18" smd circle
			(at 6.500114 1.500124 90)
			(size 0.50038 0.50038)
			(layers "F.Cu" "F.Mask" "F.Paste")
			(net "FPGA_BRD_REV2")
		)
		(pad "N19" smd circle
			(at 7.500112 1.500124 90)
			(size 0.50038 0.50038)
			(layers "F.Cu" "F.Mask" "F.Paste")
			(net "FPGA_BRD_REV1")
		)
		(pad "N20" smd circle
			(at 8.50011 1.500124 90)
			(size 0.50038 0.50038)
			(layers "F.Cu" "F.Mask" "F.Paste")
			(net "FPGA_BRD_REV0")
		)
		(pad "N21" smd circle
			(at 9.500108 1.500124 90)
			(size 0.50038 0.50038)
			(layers "F.Cu" "F.Mask" "F.Paste")
			(net "XP3R3V_FPGA")
		)
		(pad "N22" smd circle
			(at 10.500106 1.500124 90)
			(size 0.50038 0.50038)
			(layers "F.Cu" "F.Mask" "F.Paste")
			(net "FPGA_IN_LM75B_INT1_N")
		)
		(pad "P1" smd circle
			(at -10.500106 2.500122 90)
			(size 0.50038 0.50038)
			(layers "F.Cu" "F.Mask" "F.Paste")
			(net "IO_L20N_35")
		)
		(pad "P2" smd circle
			(at -9.500108 2.500122 90)
			(size 0.50038 0.50038)
			(layers "F.Cu" "F.Mask" "F.Paste")
			(net "IO_L22P_35")
		)
		(pad "P3" smd circle
			(at -8.50011 2.500122 90)
			(size 0.50038 0.50038)
			(layers "F.Cu" "F.Mask" "F.Paste")
			(net "SG")
		)
		(pad "P4" smd circle
			(at -7.499858 2.500122 90)
			(size 0.50038 0.50038)
			(layers "F.Cu" "F.Mask" "F.Paste")
			(net "IO_L21N_35")
		)
		(pad "P5" smd circle
			(at -6.49986 2.500122 90)
			(size 0.50038 0.50038)
			(layers "F.Cu" "F.Mask" "F.Paste")
			(net "IO_L21P_35")
		)
		(pad "P6" smd circle
			(at -5.499862 2.500122 90)
			(size 0.50038 0.50038)
			(layers "F.Cu" "F.Mask" "F.Paste")
			(net "IO_L24P_35")
		)
		(pad "P7" smd circle
			(at -4.499864 2.500122 90)
			(size 0.50038 0.50038)
			(layers "F.Cu" "F.Mask" "F.Paste")
			(net "SG")
		)
		(pad "P8" smd circle
			(at -3.499866 2.500122 90)
			(size 0.50038 0.50038)
			(layers "F.Cu" "F.Mask" "F.Paste")
			(net "XP1R0V_FPGA_VCCINT")
		)
		(pad "P9" smd circle
			(at -2.499868 2.500122 90)
			(size 0.50038 0.50038)
			(layers "F.Cu" "F.Mask" "F.Paste")
			(net "SG")
		)
		(pad "P10" smd circle
			(at -1.49987 2.500122 90)
			(size 0.50038 0.50038)
			(layers "F.Cu" "F.Mask" "F.Paste")
			(net "XP1R0V_FPGA_VCCINT")
		)
		(pad "P11" smd circle
			(at -0.499872 2.500122 90)
			(size 0.50038 0.50038)
			(layers "F.Cu" "F.Mask" "F.Paste")
			(net "SG")
		)
		(pad "P12" smd circle
			(at 0.500126 2.500122 90)
			(size 0.50038 0.50038)
			(layers "F.Cu" "F.Mask" "F.Paste")
			(net "XP1R8V_FPGA_VCCAUX")
		)
		(pad "P13" smd circle
			(at 1.500124 2.500122 90)
			(size 0.50038 0.50038)
			(layers "F.Cu" "F.Mask" "F.Paste")
			(net "SG")
		)
		(pad "P14" smd circle
			(at 2.500122 2.500122 90)
			(size 0.50038 0.50038)
			(layers "F.Cu" "F.Mask" "F.Paste")
			(net "MAC_USB_DP")
		)
		(pad "P15" smd circle
			(at 3.50012 2.500122 90)
			(size 0.50038 0.50038)
			(layers "F.Cu" "F.Mask" "F.Paste")
			(net "UART_FT4232_RX_FPGA_TX")
		)
		(pad "P16" smd circle
			(at 4.500118 2.500122 90)
			(size 0.50038 0.50038)
			(layers "F.Cu" "F.Mask" "F.Paste")
			(net "UART_FT4232_TX_FPGA_RX")
		)
		(pad "P17" smd circle
			(at 5.500116 2.500122 90)
			(size 0.50038 0.50038)
			(layers "F.Cu" "F.Mask" "F.Paste")
			(net "Net_63")
		)
		(pad "P18" smd circle
			(at 6.500114 2.500122 90)
			(size 0.50038 0.50038)
			(layers "F.Cu" "F.Mask" "F.Paste")
			(net "XP3R3V_FPGA")
		)
		(pad "P19" smd circle
			(at 7.500112 2.500122 90)
			(size 0.50038 0.50038)
			(layers "F.Cu" "F.Mask" "F.Paste")
			(net "Net_144")
		)
		(pad "P20" smd circle
			(at 8.50011 2.500122 90)
			(size 0.50038 0.50038)
			(layers "F.Cu" "F.Mask" "F.Paste")
			(net "UART_GPS_RX_FPGA_TX")
		)
		(pad "P21" smd circle
			(at 9.500108 2.500122 90)
			(size 0.50038 0.50038)
			(layers "F.Cu" "F.Mask" "F.Paste")
			(net "FPGA_D02")
		)
		(pad "P22" smd circle
			(at 10.500106 2.500122 90)
			(size 0.50038 0.50038)
			(layers "F.Cu" "F.Mask" "F.Paste")
			(net "FPGA_D00_MOSI")
		)
		(pad "R1" smd circle
			(at -10.500106 3.50012 90)
			(size 0.50038 0.50038)
			(layers "F.Cu" "F.Mask" "F.Paste")
			(net "IO_L20P_35")
		)
		(pad "R2" smd circle
			(at -9.500108 3.50012 90)
			(size 0.50038 0.50038)
			(layers "F.Cu" "F.Mask" "F.Paste")
			(net "Net_132")
		)
		(pad "R3" smd circle
			(at -8.50011 3.50012 90)
			(size 0.50038 0.50038)
			(layers "F.Cu" "F.Mask" "F.Paste")
			(net "Net_134")
		)
		(pad "R4" smd circle
			(at -7.499858 3.50012 90)
			(size 0.50038 0.50038)
			(layers "F.Cu" "F.Mask" "F.Paste")
			(net "MHZ200CLKP_CLKIN")
		)
		(pad "R5" smd circle
			(at -6.49986 3.50012 90)
			(size 0.50038 0.50038)
			(layers "F.Cu" "F.Mask" "F.Paste")
			(net "XP2R5V_FPGA")
		)
		(pad "R6" smd circle
			(at -5.499862 3.50012 90)
			(size 0.50038 0.50038)
			(layers "F.Cu" "F.Mask" "F.Paste")
			(net "Net_117")
		)
		(pad "R7" smd circle
			(at -4.499864 3.50012 90)
			(size 0.50038 0.50038)
			(layers "F.Cu" "F.Mask" "F.Paste")
			(net "XP1R0V_FPGA_VCCINT")
		)
		(pad "R8" smd circle
			(at -3.499866 3.50012 90)
			(size 0.50038 0.50038)
			(layers "F.Cu" "F.Mask" "F.Paste")
			(net "SG")
		)
		(pad "R9" smd circle
			(at -2.499868 3.50012 90)
			(size 0.50038 0.50038)
			(layers "F.Cu" "F.Mask" "F.Paste")
			(net "XP1R0V_FPGA_VCCINT")
		)
		(pad "R10" smd circle
			(at -1.49987 3.50012 90)
			(size 0.50038 0.50038)
			(layers "F.Cu" "F.Mask" "F.Paste")
			(net "SG")
		)
		(pad "R11" smd circle
			(at -0.499872 3.50012 90)
			(size 0.50038 0.50038)
			(layers "F.Cu" "F.Mask" "F.Paste")
			(net "XP1R8V_FPGA_VCCAUX")
		)
		(pad "R12" smd circle
			(at 0.500126 3.50012 90)
			(size 0.50038 0.50038)
			(layers "F.Cu" "F.Mask" "F.Paste")
			(net "SG")
		)
		(pad "R13" smd circle
			(at 1.500124 3.50012 90)
			(size 0.50038 0.50038)
			(layers "F.Cu" "F.Mask" "F.Paste")
			(net "FPGA_TDI")
		)
		(pad "R14" smd circle
			(at 2.500122 3.50012 90)
			(size 0.50038 0.50038)
			(layers "F.Cu" "F.Mask" "F.Paste")
			(net "MAC_USB_DM")
		)
		(pad "R15" smd circle
			(at 3.50012 3.50012 90)
			(size 0.50038 0.50038)
			(layers "F.Cu" "F.Mask" "F.Paste")
			(net "XP3R3V_FPGA")
		)
		(pad "R16" smd circle
			(at 4.500118 3.50012 90)
			(size 0.50038 0.50038)
			(layers "F.Cu" "F.Mask" "F.Paste")
			(net "Net_64")
		)
		(pad "R17" smd circle
			(at 5.500116 3.50012 90)
			(size 0.50038 0.50038)
			(layers "F.Cu" "F.Mask" "F.Paste")
			(net "Net_67")
		)
		(pad "R18" smd circle
			(at 6.500114 3.50012 90)
			(size 0.50038 0.50038)
			(layers "F.Cu" "F.Mask" "F.Paste")
			(net "Net_62")
		)
		(pad "R19" smd circle
			(at 7.500112 3.50012 90)
			(size 0.50038 0.50038)
			(layers "F.Cu" "F.Mask" "F.Paste")
			(net "Net_141")
		)
		(pad "R20" smd circle
			(at 8.50011 3.50012 90)
			(size 0.50038 0.50038)
			(layers "F.Cu" "F.Mask" "F.Paste")
			(net "SG")
		)
		(pad "R21" smd circle
			(at 9.500108 3.50012 90)
			(size 0.50038 0.50038)
			(layers "F.Cu" "F.Mask" "F.Paste")
			(net "FPGA_D03")
		)
		(pad "R22" smd circle
			(at 10.500106 3.50012 90)
			(size 0.50038 0.50038)
			(layers "F.Cu" "F.Mask" "F.Paste")
			(net "FPGA_D01")
		)
		(pad "T1" smd circle
			(at -10.500106 4.500118 90)
			(size 0.50038 0.50038)
			(layers "F.Cu" "F.Mask" "F.Paste")
			(net "Net_125")
		)
		(pad "T2" smd circle
			(at -9.500108 4.500118 90)
			(size 0.50038 0.50038)
			(layers "F.Cu" "F.Mask" "F.Paste")
			(net "XP2R5V_FPGA")
		)
		(pad "T3" smd circle
			(at -8.50011 4.500118 90)
			(size 0.50038 0.50038)
			(layers "F.Cu" "F.Mask" "F.Paste")
			(net "Net_29")
		)
		(pad "T4" smd circle
			(at -7.499858 4.500118 90)
			(size 0.50038 0.50038)
			(layers "F.Cu" "F.Mask" "F.Paste")
			(net "MHZ200CLKN_CLKIN")
		)
		(pad "T5" smd circle
			(at -6.49986 4.500118 90)
			(size 0.50038 0.50038)
			(layers "F.Cu" "F.Mask" "F.Paste")
			(net "Net_106")
		)
		(pad "T6" smd circle
			(at -5.499862 4.500118 90)
			(size 0.50038 0.50038)
			(layers "F.Cu" "F.Mask" "F.Paste")
			(net "Net_14")
		)
		(pad "T7" smd circle
			(at -4.499864 4.500118 90)
			(size 0.50038 0.50038)
			(layers "F.Cu" "F.Mask" "F.Paste")
			(net "SG")
		)
		(pad "T8" smd circle
			(at -3.499866 4.500118 90)
			(size 0.50038 0.50038)
			(layers "F.Cu" "F.Mask" "F.Paste")
			(net "XP1R0V_FPGA_VCCINT")
		)
		(pad "T9" smd circle
			(at -2.499868 4.500118 90)
			(size 0.50038 0.50038)
			(layers "F.Cu" "F.Mask" "F.Paste")
			(net "SG")
		)
		(pad "T10" smd circle
			(at -1.49987 4.500118 90)
			(size 0.50038 0.50038)
			(layers "F.Cu" "F.Mask" "F.Paste")
			(net "XP1R0V_FPGA_VCCINT")
		)
		(pad "T11" smd circle
			(at -0.499872 4.500118 90)
			(size 0.50038 0.50038)
			(layers "F.Cu" "F.Mask" "F.Paste")
			(net "SG")
		)
		(pad "T12" smd circle
			(at 0.500126 4.500118 90)
			(size 0.50038 0.50038)
			(layers "F.Cu" "F.Mask" "F.Paste")
			(net "XP3R3V_FPGA")
		)
		(pad "T13" smd circle
			(at 1.500124 4.500118 90)
			(size 0.50038 0.50038)
			(layers "F.Cu" "F.Mask" "F.Paste")
			(net "FPGA_TMS")
		)
		(pad "T14" smd circle
			(at 2.500122 4.500118 90)
			(size 0.50038 0.50038)
			(layers "F.Cu" "F.Mask" "F.Paste")
			(net "Net_41")
		)
		(pad "T15" smd circle
			(at 3.50012 4.500118 90)
			(size 0.50038 0.50038)
			(layers "F.Cu" "F.Mask" "F.Paste")
			(net "Net_38")
		)
		(pad "T16" smd circle
			(at 4.500118 4.500118 90)
			(size 0.50038 0.50038)
			(layers "F.Cu" "F.Mask" "F.Paste")
			(net "FPGA_PCA9546_I2C_SDA")
		)
		(pad "T17" smd circle
			(at 5.500116 4.500118 90)
			(size 0.50038 0.50038)
			(layers "F.Cu" "F.Mask" "F.Paste")
			(net "SG")
		)
		(pad "T18" smd circle
			(at 6.500114 4.500118 90)
			(size 0.50038 0.50038)
			(layers "F.Cu" "F.Mask" "F.Paste")
			(net "Net_61")
		)
		(pad "T19" smd circle
			(at 7.500112 4.500118 90)
			(size 0.50038 0.50038)
			(layers "F.Cu" "F.Mask" "F.Paste")
			(net "FPGA_FCS_B")
		)
		(pad "T20" smd circle
			(at 8.50011 4.500118 90)
			(size 0.50038 0.50038)
			(layers "F.Cu" "F.Mask" "F.Paste")
			(net "Net_77")
		)
		(pad "T21" smd circle
			(at 9.500108 4.500118 90)
			(size 0.50038 0.50038)
			(layers "F.Cu" "F.Mask" "F.Paste")
			(net "Net_74")
		)
		(pad "T22" smd circle
			(at 10.500106 4.500118 90)
			(size 0.50038 0.50038)
			(layers "F.Cu" "F.Mask" "F.Paste")
			(net "XP3R3V_FPGA")
		)
		(pad "U1" smd circle
			(at -10.500106 5.500116 90)
			(size 0.50038 0.50038)
			(layers "F.Cu" "F.Mask" "F.Paste")
			(net "Net_123")
		)
		(pad "U2" smd circle
			(at -9.500108 5.500116 90)
			(size 0.50038 0.50038)
			(layers "F.Cu" "F.Mask" "F.Paste")
			(net "Net_130")
		)
		(pad "U3" smd circle
			(at -8.50011 5.500116 90)
			(size 0.50038 0.50038)
			(layers "F.Cu" "F.Mask" "F.Paste")
			(net "Net_148")
		)
		(pad "U4" smd circle
			(at -7.499858 5.500116 90)
			(size 0.50038 0.50038)
			(layers "F.Cu" "F.Mask" "F.Paste")
			(net "SG")
		)
		(pad "U5" smd circle
			(at -6.49986 5.500116 90)
			(size 0.50038 0.50038)
			(layers "F.Cu" "F.Mask" "F.Paste")
			(net "Net_104")
		)
		(pad "U6" smd circle
			(at -5.499862 5.500116 90)
			(size 0.50038 0.50038)
			(layers "F.Cu" "F.Mask" "F.Paste")
			(net "Net_114")
		)
		(pad "U7" smd circle
			(at -4.499864 5.500116 90)
			(size 0.50038 0.50038)
			(layers "F.Cu" "F.Mask" "F.Paste")
			(net "Net_88")
		)
		(pad "U8" smd circle
			(at -3.499866 5.500116 90)
			(size 0.50038 0.50038)
			(layers "F.Cu" "F.Mask" "F.Paste")
			(net "CFGBVS")
		)
		(pad "U9" smd circle
			(at -2.499868 5.500116 90)
			(size 0.50038 0.50038)
			(layers "F.Cu" "F.Mask" "F.Paste")
			(net "FPGA_M2")
		)
		(pad "U10" smd circle
			(at -1.49987 5.500116 90)
			(size 0.50038 0.50038)
			(layers "F.Cu" "F.Mask" "F.Paste")
			(net "FPGA_M1")
		)
		(pad "U11" smd circle
			(at -0.499872 5.500116 90)
			(size 0.50038 0.50038)
			(layers "F.Cu" "F.Mask" "F.Paste")
			(net "FPGA_M0")
		)
		(pad "U12" smd circle
			(at 0.500126 5.500116 90)
			(size 0.50038 0.50038)
			(layers "F.Cu" "F.Mask" "F.Paste")
			(net "FPGA_CFG_INIT_N")
		)
		(pad "U13" smd circle
			(at 1.500124 5.500116 90)
			(size 0.50038 0.50038)
			(layers "F.Cu" "F.Mask" "F.Paste")
			(net "R_FPGA_TDO")
		)
		(pad "U14" smd circle
			(at 2.500122 5.500116 90)
			(size 0.50038 0.50038)
			(layers "F.Cu" "F.Mask" "F.Paste")
			(net "SG")
		)
		(pad "U15" smd circle
			(at 3.50012 5.500116 90)
			(size 0.50038 0.50038)
			(layers "F.Cu" "F.Mask" "F.Paste")
			(net "Net_169")
		)
		(pad "U16" smd circle
			(at 4.500118 5.500116 90)
			(size 0.50038 0.50038)
			(layers "F.Cu" "F.Mask" "F.Paste")
			(net "FPGA_OUT_PCA9546_RST_N")
		)
		(pad "U17" smd circle
			(at 5.500116 5.500116 90)
			(size 0.50038 0.50038)
			(layers "F.Cu" "F.Mask" "F.Paste")
			(net "Net_53")
		)
		(pad "U18" smd circle
			(at 6.500114 5.500116 90)
			(size 0.50038 0.50038)
			(layers "F.Cu" "F.Mask" "F.Paste")
			(net "Net_49")
		)
		(pad "U19" smd circle
			(at 7.500112 5.500116 90)
			(size 0.50038 0.50038)
			(layers "F.Cu" "F.Mask" "F.Paste")
			(net "XP3R3V_FPGA")
		)
		(pad "U20" smd circle
			(at 8.50011 5.500116 90)
			(size 0.50038 0.50038)
			(layers "F.Cu" "F.Mask" "F.Paste")
			(net "Net_165")
		)
		(pad "U21" smd circle
			(at 9.500108 5.500116 90)
			(size 0.50038 0.50038)
			(layers "F.Cu" "F.Mask" "F.Paste")
			(net "Net_72")
		)
		(pad "U22" smd circle
			(at 10.500106 5.500116 90)
			(size 0.50038 0.50038)
			(layers "F.Cu" "F.Mask" "F.Paste")
			(net "PUDC")
		)
		(pad "V1" smd circle
			(at -10.500106 6.500114 90)
			(size 0.50038 0.50038)
			(layers "F.Cu" "F.Mask" "F.Paste")
			(net "SG")
		)
		(pad "V2" smd circle
			(at -9.500108 6.500114 90)
			(size 0.50038 0.50038)
			(layers "F.Cu" "F.Mask" "F.Paste")
			(net "Net_128")
		)
		(pad "V3" smd circle
			(at -8.50011 6.500114 90)
			(size 0.50038 0.50038)
			(layers "F.Cu" "F.Mask" "F.Paste")
			(net "Net_146")
		)
		(pad "V4" smd circle
			(at -7.499858 6.500114 90)
			(size 0.50038 0.50038)
			(layers "F.Cu" "F.Mask" "F.Paste")
			(net "Net_100")
		)
		(pad "V5" smd circle
			(at -6.49986 6.500114 90)
			(size 0.50038 0.50038)
			(layers "F.Cu" "F.Mask" "F.Paste")
			(net "Net_112")
		)
		(pad "V6" smd circle
			(at -5.499862 6.500114 90)
			(size 0.50038 0.50038)
			(layers "F.Cu" "F.Mask" "F.Paste")
			(net "XP2R5V_FPGA")
		)
		(pad "V7" smd circle
			(at -4.499864 6.500114 90)
			(size 0.50038 0.50038)
			(layers "F.Cu" "F.Mask" "F.Paste")
			(net "Net_59")
		)
		(pad "V8" smd circle
			(at -3.499866 6.500114 90)
			(size 0.50038 0.50038)
			(layers "F.Cu" "F.Mask" "F.Paste")
			(net "IO_L21N_34")
		)
		(pad "V9" smd circle
			(at -2.499868 6.500114 90)
			(size 0.50038 0.50038)
			(layers "F.Cu" "F.Mask" "F.Paste")
			(net "IO_L21P_34")
		)
		(pad "V10" smd circle
			(at -1.49987 6.500114 90)
			(size 0.50038 0.50038)
			(layers "F.Cu" "F.Mask" "F.Paste")
			(net "ANT1_OUT")
		)
		(pad "V11" smd circle
			(at -0.499872 6.500114 90)
			(size 0.50038 0.50038)
			(layers "F.Cu" "F.Mask" "F.Paste")
			(net "SG")
		)
		(pad "V12" smd circle
			(at 0.500126 6.500114 90)
			(size 0.50038 0.50038)
			(layers "F.Cu" "F.Mask" "F.Paste")
			(net "FPGA_TCK")
		)
		(pad "V13" smd circle
			(at 1.500124 6.500114 90)
			(size 0.50038 0.50038)
			(layers "F.Cu" "F.Mask" "F.Paste")
			(net "FPGA_IN_MAC_10MHZ_OUT")
		)
		(pad "V14" smd circle
			(at 2.500122 6.500114 90)
			(size 0.50038 0.50038)
			(layers "F.Cu" "F.Mask" "F.Paste")
			(net "Net_166")
		)
		(pad "V15" smd circle
			(at 3.50012 6.500114 90)
			(size 0.50038 0.50038)
			(layers "F.Cu" "F.Mask" "F.Paste")
			(net "FPGA_OUT_MACUSBPOWER_EN")
		)
		(pad "V16" smd circle
			(at 4.500118 6.500114 90)
			(size 0.50038 0.50038)
			(layers "F.Cu" "F.Mask" "F.Paste")
			(net "XP3R3V_FPGA")
		)
		(pad "V17" smd circle
			(at 5.500116 6.500114 90)
			(size 0.50038 0.50038)
			(layers "F.Cu" "F.Mask" "F.Paste")
			(net "Net_47")
		)
		(pad "V18" smd circle
			(at 6.500114 6.500114 90)
			(size 0.50038 0.50038)
			(layers "F.Cu" "F.Mask" "F.Paste")
			(net "Net_170")
		)
		(pad "V19" smd circle
			(at 7.500112 6.500114 90)
			(size 0.50038 0.50038)
			(layers "F.Cu" "F.Mask" "F.Paste")
			(net "Net_168")
		)
		(pad "V20" smd circle
			(at 8.50011 6.500114 90)
			(size 0.50038 0.50038)
			(layers "F.Cu" "F.Mask" "F.Paste")
			(net "Net_164")
		)
		(pad "V21" smd circle
			(at 9.500108 6.500114 90)
			(size 0.50038 0.50038)
			(layers "F.Cu" "F.Mask" "F.Paste")
			(net "SG")
		)
		(pad "V22" smd circle
			(at 10.500106 6.500114 90)
			(size 0.50038 0.50038)
			(layers "F.Cu" "F.Mask" "F.Paste")
			(net "Net_70")
		)
		(pad "W1" smd circle
			(at -10.500106 7.500112 90)
			(size 0.50038 0.50038)
			(layers "F.Cu" "F.Mask" "F.Paste")
			(net "FPGA_IN_MAC_PPS_OUTP")
		)
		(pad "W2" smd circle
			(at -9.500108 7.500112 90)
			(size 0.50038 0.50038)
			(layers "F.Cu" "F.Mask" "F.Paste")
			(net "Net_138")
		)
		(pad "W3" smd circle
			(at -8.50011 7.500112 90)
			(size 0.50038 0.50038)
			(layers "F.Cu" "F.Mask" "F.Paste")
			(net "XP2R5V_FPGA")
		)
		(pad "W4" smd circle
			(at -7.499858 7.500112 90)
			(size 0.50038 0.50038)
			(layers "F.Cu" "F.Mask" "F.Paste")
			(net "Net_98")
		)
		(pad "W5" smd circle
			(at -6.49986 7.500112 90)
			(size 0.50038 0.50038)
			(layers "F.Cu" "F.Mask" "F.Paste")
			(net "Net_108")
		)
		(pad "W6" smd circle
			(at -5.499862 7.500112 90)
			(size 0.50038 0.50038)
			(layers "F.Cu" "F.Mask" "F.Paste")
			(net "Net_110")
		)
		(pad "W7" smd circle
			(at -4.499864 7.500112 90)
			(size 0.50038 0.50038)
			(layers "F.Cu" "F.Mask" "F.Paste")
			(net "Net_57")
		)
		(pad "W8" smd circle
			(at -3.499866 7.500112 90)
			(size 0.50038 0.50038)
			(layers "F.Cu" "F.Mask" "F.Paste")
			(net "SG")
		)
		(pad "W9" smd circle
			(at -2.499868 7.500112 90)
			(size 0.50038 0.50038)
			(layers "F.Cu" "F.Mask" "F.Paste")
			(net "IO_L24P_34")
		)
		(pad "W10" smd circle
			(at -1.49987 7.500112 90)
			(size 0.50038 0.50038)
			(layers "F.Cu" "F.Mask" "F.Paste")
			(net "ANT2_OUT")
		)
		(pad "W11" smd circle
			(at -0.499872 7.500112 90)
			(size 0.50038 0.50038)
			(layers "F.Cu" "F.Mask" "F.Paste")
			(net "ANT3_OUT")
		)
		(pad "W12" smd circle
			(at 0.500126 7.500112 90)
			(size 0.50038 0.50038)
			(layers "F.Cu" "F.Mask" "F.Paste")
			(net "ANT4_OUT")
		)
		(pad "W13" smd circle
			(at 1.500124 7.500112 90)
			(size 0.50038 0.50038)
			(layers "F.Cu" "F.Mask" "F.Paste")
			(net "XP3R3V_FPGA")
		)
		(pad "W14" smd circle
			(at 2.500122 7.500112 90)
			(size 0.50038 0.50038)
			(layers "F.Cu" "F.Mask" "F.Paste")
			(net "FPGA_IN_GPSTP1_OUT")
		)
		(pad "W15" smd circle
			(at 3.50012 7.500112 90)
			(size 0.50038 0.50038)
			(layers "F.Cu" "F.Mask" "F.Paste")
			(net "Net_46")
		)
		(pad "W16" smd circle
			(at 4.500118 7.500112 90)
			(size 0.50038 0.50038)
			(layers "F.Cu" "F.Mask" "F.Paste")
			(net "Net_43")
		)
		(pad "W17" smd circle
			(at 5.500116 7.500112 90)
			(size 0.50038 0.50038)
			(layers "F.Cu" "F.Mask" "F.Paste")
			(net "Net_44")
		)
		(pad "W18" smd circle
			(at 6.500114 7.500112 90)
			(size 0.50038 0.50038)
			(layers "F.Cu" "F.Mask" "F.Paste")
			(net "SG")
		)
		(pad "W19" smd circle
			(at 7.500112 7.500112 90)
			(size 0.50038 0.50038)
			(layers "F.Cu" "F.Mask" "F.Paste")
			(net "FPGA_M_RGB_LED_I2C_SDA")
		)
		(pad "W20" smd circle
			(at 8.50011 7.500112 90)
			(size 0.50038 0.50038)
			(layers "F.Cu" "F.Mask" "F.Paste")
			(net "FPGA_M_RGB_LED_I2C_SCL")
		)
		(pad "W21" smd circle
			(at 9.500108 7.500112 90)
			(size 0.50038 0.50038)
			(layers "F.Cu" "F.Mask" "F.Paste")
			(net "Net_175")
		)
		(pad "W22" smd circle
			(at 10.500106 7.500112 90)
			(size 0.50038 0.50038)
			(layers "F.Cu" "F.Mask" "F.Paste")
			(net "Net_79")
		)
		(pad "Y1" smd circle
			(at -10.500106 8.50011 90)
			(size 0.50038 0.50038)
			(layers "F.Cu" "F.Mask" "F.Paste")
			(net "FPGA_IN_MAC_PPS_OUTN")
		)
		(pad "Y2" smd circle
			(at -9.500108 8.50011 90)
			(size 0.50038 0.50038)
			(layers "F.Cu" "F.Mask" "F.Paste")
			(net "Net_136")
		)
		(pad "Y3" smd circle
			(at -8.50011 8.50011 90)
			(size 0.50038 0.50038)
			(layers "F.Cu" "F.Mask" "F.Paste")
			(net "Net_160")
		)
		(pad "Y4" smd circle
			(at -7.499858 8.50011 90)
			(size 0.50038 0.50038)
			(layers "F.Cu" "F.Mask" "F.Paste")
			(net "Net_96")
		)
		(pad "Y5" smd circle
			(at -6.49986 8.50011 90)
			(size 0.50038 0.50038)
			(layers "F.Cu" "F.Mask" "F.Paste")
			(net "SG")
		)
		(pad "Y6" smd circle
			(at -5.499862 8.50011 90)
			(size 0.50038 0.50038)
			(layers "F.Cu" "F.Mask" "F.Paste")
			(net "Net_55")
		)
		(pad "Y7" smd circle
			(at -4.499864 8.50011 90)
			(size 0.50038 0.50038)
			(layers "F.Cu" "F.Mask" "F.Paste")
			(net "IO_L23N_34")
		)
		(pad "Y8" smd circle
			(at -3.499866 8.50011 90)
			(size 0.50038 0.50038)
			(layers "F.Cu" "F.Mask" "F.Paste")
			(net "IO_L23P_34")
		)
		(pad "Y9" smd circle
			(at -2.499868 8.50011 90)
			(size 0.50038 0.50038)
			(layers "F.Cu" "F.Mask" "F.Paste")
			(net "IO_L24N_34")
		)
		(pad "Y10" smd circle
			(at -1.49987 8.50011 90)
			(size 0.50038 0.50038)
			(layers "F.Cu" "F.Mask" "F.Paste")
			(net "XP3R3V_FPGA")
		)
		(pad "Y11" smd circle
			(at -0.499872 8.50011 90)
			(size 0.50038 0.50038)
			(layers "F.Cu" "F.Mask" "F.Paste")
			(net "ANT3_IN")
		)
		(pad "Y12" smd circle
			(at 0.500126 8.50011 90)
			(size 0.50038 0.50038)
			(layers "F.Cu" "F.Mask" "F.Paste")
			(net "ANT4_IN")
		)
		(pad "Y13" smd circle
			(at 1.500124 8.50011 90)
			(size 0.50038 0.50038)
			(layers "F.Cu" "F.Mask" "F.Paste")
			(net "Net_143")
		)
		(pad "Y14" smd circle
			(at 2.500122 8.50011 90)
			(size 0.50038 0.50038)
			(layers "F.Cu" "F.Mask" "F.Paste")
			(net "FPGA_IN_GPSTP2_OUT")
		)
		(pad "Y15" smd circle
			(at 3.50012 8.50011 90)
			(size 0.50038 0.50038)
			(layers "F.Cu" "F.Mask" "F.Paste")
			(net "SG")
		)
		(pad "Y16" smd circle
			(at 4.500118 8.50011 90)
			(size 0.50038 0.50038)
			(layers "F.Cu" "F.Mask" "F.Paste")
			(net "FPGA_OUT_GPS_RST_N")
		)
		(pad "Y17" smd circle
			(at 5.500116 8.50011 90)
			(size 0.50038 0.50038)
			(layers "F.Cu" "F.Mask" "F.Paste")
			(net "Net_27")
		)
		(pad "Y18" smd circle
			(at 6.500114 8.50011 90)
			(size 0.50038 0.50038)
			(layers "F.Cu" "F.Mask" "F.Paste")
			(net "FPGA_OUT_RGB_LED_SHUTDOWN_N")
		)
		(pad "Y19" smd circle
			(at 7.500112 8.50011 90)
			(size 0.50038 0.50038)
			(layers "F.Cu" "F.Mask" "F.Paste")
			(net "Net_167")
		)
		(pad "Y20" smd circle
			(at 8.50011 8.50011 90)
			(size 0.50038 0.50038)
			(layers "F.Cu" "F.Mask" "F.Paste")
			(net "XP3R3V_FPGA")
		)
		(pad "Y21" smd circle
			(at 9.500108 8.50011 90)
			(size 0.50038 0.50038)
			(layers "F.Cu" "F.Mask" "F.Paste")
			(net "Net_84")
		)
		(pad "Y22" smd circle
			(at 10.500106 8.50011 90)
			(size 0.50038 0.50038)
			(layers "F.Cu" "F.Mask" "F.Paste")
			(net "Net_82")
		)
	)
	(footprint ""
		(layer "F.Cu")
		(at 124.587 -52.578 180)
		(property "Reference" "R356"
			(at -3.175 -0.16637 0)
			(unlocked yes)
			(layer "F.SilkS")
			(effects
				(font
					(size 0.7874 0.5842)
					(thickness 0.1524)
				)
			)
		)
		(property "Value" "VAL*"
			(at 0.02032 2.13233 180)
			(unlocked yes)
			(layer "F.Fab")
			(hide yes)
			(effects
				(font
					(size 0.7874 0.5842)
					(thickness 0.1524)
				)
			)
		)
		(property "Tolerance" "TOL*"
			(at 0.044704 3.05435 180)
			(unlocked yes)
			(layer "Cmts.User")
			(hide yes)
			(effects
				(font
					(size 0.7874 0.5842)
					(thickness 0.1524)
				)
			)
		)
		(property "User Part Number" "PARTNUM*"
			(at 0.02032 4.024884 180)
			(unlocked yes)
			(layer "Cmts.User")
			(hide yes)
			(effects
				(font
					(size 0.7874 0.5842)
					(thickness 0.1524)
				)
			)
		)
		(property "Device Type" "RESISTOR-G155-100R0-J0,0OHM,-"
			(at 0.008382 1.210564 180)
			(unlocked yes)
			(layer "F.Fab")
			(hide yes)
			(effects
				(font
					(size 0.7874 0.5842)
					(thickness 0.1524)
				)
			)
		)
		(duplicate_pad_numbers_are_jumpers no)
		(fp_line
			(start 1.143 0.5588)
			(end 1.143 -0.5588)
			(stroke
				(width 0.1)
				(type default)
			)
			(layer "F.SilkS")
		)
		(fp_line
			(start 1.143 -0.5588)
			(end -1.143 -0.5588)
			(stroke
				(width 0.1)
				(type default)
			)
			(layer "F.SilkS")
		)
		(fp_line
			(start -1.143 0.5588)
			(end 1.143 0.5588)
			(stroke
				(width 0.1)
				(type default)
			)
			(layer "F.SilkS")
		)
		(fp_line
			(start -1.143 -0.5588)
			(end -1.143 0.5588)
			(stroke
				(width 0.1)
				(type default)
			)
			(layer "F.SilkS")
		)
		(fp_poly
			(pts
				(xy -1.143 0.5588) (xy 1.143 0.5588) (xy 1.143 -0.5588) (xy -1.143 -0.5588)
			)
			(stroke
				(width 0)
				(type default)
			)
			(fill no)
			(layer "F.CrtYd")
		)
		(fp_line
			(start 0.508 0.3048)
			(end 0.508 -0.3048)
			(stroke
				(width 0.1)
				(type default)
			)
			(layer "F.Fab")
		)
		(fp_line
			(start 0.508 -0.3048)
			(end -0.508 -0.3048)
			(stroke
				(width 0.1)
				(type default)
			)
			(layer "F.Fab")
		)
		(fp_line
			(start -0.508 0.3048)
			(end 0.508 0.3048)
			(stroke
				(width 0.1)
				(type default)
			)
			(layer "F.Fab")
		)
		(fp_line
			(start -0.508 -0.3048)
			(end -0.508 0.3048)
			(stroke
				(width 0.1)
				(type default)
			)
			(layer "F.Fab")
		)
		(pad "1" smd rect
			(at -0.5334 0 180)
			(size 0.7112 0.6096)
			(layers "F.Cu" "F.Mask" "F.Paste")
			(net "BF_PCIE_PERST_N")
		)
		(pad "2" smd rect
			(at 0.5334 0 180)
			(size 0.7112 0.6096)
			(layers "F.Cu" "F.Mask" "F.Paste")
			(net "FPGA_PROGRAM_N")
		)
		(zone
			(layer "F.Cu")
			(hatch none 0.5)
			(connect_pads
				(clearance 0)
			)
			(min_thickness 0.25)
			(keepout
				(tracks not_allowed)
				(vias allowed)
				(pads allowed)
				(copperpour not_allowed)
				(footprints allowed)
			)
			(placement
				(enabled no)
				(sheetname "")
			)
			(fill
				(thermal_gap 0.5)
				(thermal_bridge_width 0.5)
				(island_removal_mode 0)
			)
			(polygon
				(pts
					(xy 124.6632 -52.8828) (xy 124.5108 -52.8828) (xy 124.5108 -52.2732) (xy 124.6632 -52.2732)
				)
			)
		)
		(zone
			(layer "F.Cu")
			(hatch none 0.5)
			(connect_pads
				(clearance 0)
			)
			(min_thickness 0.25)
			(keepout
				(tracks allowed)
				(vias not_allowed)
				(pads allowed)
				(copperpour not_allowed)
				(footprints allowed)
			)
			(placement
				(enabled no)
				(sheetname "")
			)
			(fill
				(thermal_gap 0.5)
				(thermal_bridge_width 0.5)
				(island_removal_mode 0)
			)
			(polygon
				(pts
					(xy 124.6632 -52.8828) (xy 124.5108 -52.8828) (xy 124.5108 -52.2732) (xy 124.6632 -52.2732)
				)
			)
		)
	)
	(footprint ""
		(layer "F.Cu")
		(at 19.8882 -100.1014)
		(property "Reference" "CR12"
			(at -0.4572 8.19277 0)
			(unlocked yes)
			(layer "F.SilkS")
			(effects
				(font
					(size 0.7874 0.5842)
					(thickness 0.1524)
				)
			)
		)
		(property "Value" ""
			(at 0 0 0)
			(layer "F.Fab")
			(effects
				(font
					(size 1.27 1.27)
				)
			)
		)
		(property "Device Type" "DIODE_3F-G122-10080-01"
			(at -0.1524 8.061706 0)
			(unlocked yes)
			(layer "F.Fab")
			(hide yes)
			(effects
				(font
					(size 0.7874 0.5842)
					(thickness 0.1524)
				)
			)
		)
		(property "User Part Number" "PARTNUM*"
			(at -0.1524 9.052306 0)
			(unlocked yes)
			(layer "Cmts.User")
			(hide yes)
			(effects
				(font
					(size 0.7874 0.5842)
					(thickness 0.1524)
				)
			)
		)
		(duplicate_pad_numbers_are_jumpers no)
		(fp_line
			(start -3.6195 -5.3086)
			(end -3.6195 6.9596)
			(stroke
				(width 0.1)
				(type default)
			)
			(layer "F.SilkS")
		)
		(fp_line
			(start -3.6195 6.9596)
			(end 3.6195 6.9596)
			(stroke
				(width 0.1)
				(type default)
			)
			(layer "F.SilkS")
		)
		(fp_line
			(start 3.6195 -5.3086)
			(end -3.6195 -5.3086)
			(stroke
				(width 0.1)
				(type default)
			)
			(layer "F.SilkS")
		)
		(fp_line
			(start 3.6195 6.9596)
			(end 3.6195 -5.3086)
			(stroke
				(width 0.1)
				(type default)
			)
			(layer "F.SilkS")
		)
		(fp_poly
			(pts
				(xy -2.8956 -5.0546) (xy -1.89992 -5.0546)
				(arc
					(start -1.89992 -4.058158)
					(mid -1.94894 -4.02319)
					(end -1.988312 -3.97764)
				)
				(xy -2.8956 -3.97764)
			)
			(stroke
				(width 0)
				(type default)
			)
			(fill yes)
			(layer "F.Paste")
		)
		(fp_poly
			(pts
				(xy 1.89992 -5.0546) (xy 2.8956 -5.0546) (xy 2.8956 -3.97764)
				(arc
					(start 2.013712 -3.97764)
					(mid 1.963658 -4.032393)
					(end 1.89992 -4.07035)
				)
			)
			(stroke
				(width 0)
				(type default)
			)
			(fill yes)
			(layer "F.Paste")
		)
		(fp_poly
			(pts
				(xy -2.8956 0.06604)
				(arc
					(start -2.014982 0.06604)
					(mid -1.969113 0.141925)
					(end -1.89992 0.197358)
				)
				(xy -1.89992 1.143) (xy -2.8956 1.143)
			)
			(stroke
				(width 0)
				(type default)
			)
			(fill yes)
			(layer "F.Paste")
		)
		(fp_poly
			(pts
				(arc
					(start 1.89992 0.20955)
					(mid 1.984931 0.152263)
					(end 2.040382 0.06604)
				)
				(xy 2.8956 0.06604) (xy 2.8956 1.143) (xy 1.89992 1.143)
			)
			(stroke
				(width 0)
				(type default)
			)
			(fill yes)
			(layer "F.Paste")
		)
		(fp_poly
			(pts
				(xy 0.70104 -5.0546) (xy 1.69672 -5.0546)
				(arc
					(start 1.69672 -4.066032)
					(mid 1.63886 -4.02892)
					(end 1.593088 -3.97764)
				)
				(arc
					(start 0.819912 -3.97764)
					(mid 0.767727 -4.03411)
					(end 0.70104 -4.072382)
				)
			)
			(stroke
				(width 0)
				(type default)
			)
			(fill yes)
			(layer "F.Paste")
		)
		(fp_poly
			(pts
				(xy -2.8956 -2.49428)
				(arc
					(start -2.02184 -2.49428)
					(mid -1.975997 -2.406299)
					(end -1.89992 -2.342642)
				)
				(arc
					(start -1.89992 -1.518158)
					(mid -1.957563 -1.474963)
					(end -2.000758 -1.41732)
				)
				(xy -2.8956 -1.41732)
			)
			(stroke
				(width 0)
				(type default)
			)
			(fill yes)
			(layer "F.Paste")
		)
		(fp_poly
			(pts
				(xy -2.8956 -1.21412)
				(arc
					(start -2.018538 -1.21412)
					(mid -1.97253 -1.132234)
					(end -1.89992 -1.072642)
				)
				(arc
					(start -1.89992 -0.248158)
					(mid -1.961574 -0.20086)
					(end -2.006092 -0.13716)
				)
				(xy -2.8956 -0.13716)
			)
			(stroke
				(width 0)
				(type default)
			)
			(fill yes)
			(layer "F.Paste")
		)
		(fp_poly
			(pts
				(xy -1.69672 -5.0546) (xy -0.70104 -5.0546)
				(arc
					(start -0.70104 -4.060952)
					(mid -0.752971 -4.025129)
					(end -0.794512 -3.97764)
				)
				(arc
					(start -1.567688 -3.97764)
					(mid -1.624144 -4.037369)
					(end -1.69672 -4.075938)
				)
			)
			(stroke
				(width 0)
				(type default)
			)
			(fill yes)
			(layer "F.Paste")
		)
		(fp_poly
			(pts
				(xy -0.49784 -5.0546) (xy 0.49784 -5.0546)
				(arc
					(start 0.49784 -4.063492)
					(mid 0.442948 -4.027013)
					(end 0.399288 -3.97764)
				)
				(arc
					(start -0.373888 -3.97764)
					(mid -0.428212 -4.035727)
					(end -0.49784 -4.07416)
				)
			)
			(stroke
				(width 0)
				(type default)
			)
			(fill yes)
			(layer "F.Paste")
		)
		(fp_poly
			(pts
				(xy -2.8956 -3.77444)
				(arc
					(start -2.024634 -3.77444)
					(mid -1.979299 -3.680405)
					(end -1.89992 -3.612642)
				)
				(arc
					(start -1.89992 -2.788158)
					(mid -1.953372 -2.749058)
					(end -1.994916 -2.69748)
				)
				(xy -2.8956 -2.69748)
			)
			(stroke
				(width 0)
				(type default)
			)
			(fill yes)
			(layer "F.Paste")
		)
		(fp_poly
			(pts
				(arc
					(start -1.69672 0.215138)
					(mid -1.602311 0.157898)
					(end -1.541018 0.06604)
				)
				(arc
					(start -0.821182 0.06604)
					(mid -0.77339 0.144095)
					(end -0.70104 0.200152)
				)
				(xy -0.70104 1.143) (xy -1.69672 1.143)
			)
			(stroke
				(width 0)
				(type default)
			)
			(fill yes)
			(layer "F.Paste")
		)
		(fp_poly
			(pts
				(arc
					(start -0.49784 0.21336)
					(mid -0.406579 0.156025)
					(end -0.347218 0.06604)
				)
				(arc
					(start 0.372618 0.06604)
					(mid 0.422316 0.1462)
					(end 0.49784 0.202692)
				)
				(xy 0.49784 1.143) (xy -0.49784 1.143)
			)
			(stroke
				(width 0)
				(type default)
			)
			(fill yes)
			(layer "F.Paste")
		)
		(fp_poly
			(pts
				(arc
					(start 0.70104 0.211582)
					(mid 0.789213 0.154213)
					(end 0.846582 0.06604)
				)
				(arc
					(start 1.566418 0.06604)
					(mid 1.618046 0.148282)
					(end 1.69672 0.205232)
				)
				(xy 1.69672 1.143) (xy 0.70104 1.143)
			)
			(stroke
				(width 0)
				(type default)
			)
			(fill yes)
			(layer "F.Paste")
		)
		(fp_poly
			(pts
				(arc
					(start 1.89992 -3.60045)
					(mid 1.995752 -3.669513)
					(end 2.050034 -3.77444)
				)
				(xy 2.8956 -3.77444) (xy 2.8956 -2.69748)
				(arc
					(start 2.020316 -2.69748)
					(mid 1.96833 -2.758521)
					(end 1.89992 -2.80035)
				)
			)
			(stroke
				(width 0)
				(type default)
			)
			(fill yes)
			(layer "F.Paste")
		)
		(fp_poly
			(pts
				(arc
					(start 1.89992 -2.33045)
					(mid 1.99227 -2.395559)
					(end 2.04724 -2.49428)
				)
				(xy 2.8956 -2.49428) (xy 2.8956 -1.41732)
				(arc
					(start 2.026158 -1.41732)
					(mid 1.972726 -1.484646)
					(end 1.89992 -1.53035)
				)
			)
			(stroke
				(width 0)
				(type default)
			)
			(fill yes)
			(layer "F.Paste")
		)
		(fp_poly
			(pts
				(arc
					(start 1.89992 -1.06045)
					(mid 1.988656 -1.121624)
					(end 2.043938 -1.21412)
				)
				(xy 2.8956 -1.21412) (xy 2.8956 -0.13716)
				(arc
					(start 2.031492 -0.13716)
					(mid 1.977 -0.210817)
					(end 1.89992 -0.26035)
				)
			)
			(stroke
				(width 0)
				(type default)
			)
			(fill yes)
			(layer "F.Paste")
		)
		(fp_poly
			(pts
				(arc
					(start -0.49784 -3.59664)
					(mid -0.395448 -3.665482)
					(end -0.337566 -3.77444)
				)
				(arc
					(start 0.362966 -3.77444)
					(mid 0.411854 -3.675897)
					(end 0.49784 -3.607308)
				)
				(xy 0.49784 -2.69748) (xy -0.49784 -2.69748)
			)
			(stroke
				(width 0)
				(type default)
			)
			(fill yes)
			(layer "F.Paste")
		)
		(fp_poly
			(pts
				(arc
					(start -1.69672 -2.324862)
					(mid -1.59473 -2.389682)
					(end -1.53416 -2.49428)
				)
				(arc
					(start -0.82804 -2.49428)
					(mid -0.780368 -2.40405)
					(end -0.70104 -2.339848)
				)
				(arc
					(start -0.70104 -1.520952)
					(mid -0.761756 -1.477056)
					(end -0.806958 -1.41732)
				)
				(arc
					(start -1.555242 -1.41732)
					(mid -1.614808 -1.489961)
					(end -1.69672 -1.535938)
				)
			)
			(stroke
				(width 0)
				(type default)
			)
			(fill yes)
			(layer "F.Paste")
		)
		(fp_poly
			(pts
				(arc
					(start -1.69672 -1.054862)
					(mid -1.598466 -1.115866)
					(end -1.537462 -1.21412)
				)
				(arc
					(start -0.824738 -1.21412)
					(mid -0.776855 -1.130025)
					(end -0.70104 -1.069848)
				)
				(arc
					(start -0.70104 -0.250952)
					(mid -0.765815 -0.202999)
					(end -0.812292 -0.13716)
				)
				(arc
					(start -1.549908 -0.13716)
					(mid -1.610415 -0.21627)
					(end -1.69672 -0.265938)
				)
			)
			(stroke
				(width 0)
				(type default)
			)
			(fill yes)
			(layer "F.Paste")
		)
		(fp_poly
			(pts
				(arc
					(start -0.49784 -2.32664)
					(mid -0.399078 -2.391635)
					(end -0.34036 -2.49428)
				)
				(arc
					(start 0.36576 -2.49428)
					(mid 0.415248 -2.401867)
					(end 0.49784 -2.337308)
				)
				(arc
					(start 0.49784 -1.523492)
					(mid 0.434098 -1.479017)
					(end 0.386842 -1.41732)
				)
				(arc
					(start -0.361442 -1.41732)
					(mid -0.418955 -1.48822)
					(end -0.49784 -1.53416)
				)
			)
			(stroke
				(width 0)
				(type default)
			)
			(fill yes)
			(layer "F.Paste")
		)
		(fp_poly
			(pts
				(arc
					(start -0.49784 -1.05664)
					(mid -0.402774 -1.11778)
					(end -0.343662 -1.21412)
				)
				(arc
					(start 0.369062 -1.21412)
					(mid 0.418806 -1.127881)
					(end 0.49784 -1.067308)
				)
				(arc
					(start 0.49784 -0.253492)
					(mid 0.429995 -0.205005)
					(end 0.381508 -0.13716)
				)
				(arc
					(start -0.356108 -0.13716)
					(mid -0.414601 -0.214483)
					(end -0.49784 -0.26416)
				)
			)
			(stroke
				(width 0)
				(type default)
			)
			(fill yes)
			(layer "F.Paste")
		)
		(fp_poly
			(pts
				(arc
					(start 0.70104 -3.598418)
					(mid 0.80016 -3.667446)
					(end 0.856234 -3.77444)
				)
				(arc
					(start 1.556766 -3.77444)
					(mid 1.607449 -3.673697)
					(end 1.69672 -3.604768)
				)
				(arc
					(start 1.69672 -2.796032)
					(mid 1.634297 -2.754934)
					(end 1.586484 -2.69748)
				)
				(arc
					(start 0.826516 -2.69748)
					(mid 0.77244 -2.760286)
					(end 0.70104 -2.802382)
				)
			)
			(stroke
				(width 0)
				(type default)
			)
			(fill yes)
			(layer "F.Paste")
		)
		(fp_poly
			(pts
				(arc
					(start -1.69672 -3.594862)
					(mid -1.591125 -3.663521)
					(end -1.531366 -3.77444)
				)
				(arc
					(start -0.830834 -3.77444)
					(mid -0.783717 -3.678118)
					(end -0.70104 -3.609848)
				)
				(arc
					(start -0.70104 -2.790952)
					(mid -0.757517 -2.751105)
					(end -0.801116 -2.69748)
				)
				(arc
					(start -1.561084 -2.69748)
					(mid -1.619326 -2.763693)
					(end -1.69672 -2.805938)
				)
			)
			(stroke
				(width 0)
				(type default)
			)
			(fill yes)
			(layer "F.Paste")
		)
		(fp_poly
			(pts
				(arc
					(start 0.70104 -2.328418)
					(mid 0.796635 -2.39353)
					(end 0.85344 -2.49428)
				)
				(arc
					(start 1.55956 -2.49428)
					(mid 1.610887 -2.399705)
					(end 1.69672 -2.334768)
				)
				(arc
					(start 1.69672 -1.526032)
					(mid 1.629976 -1.480977)
					(end 1.580642 -1.41732)
				)
				(arc
					(start 0.832358 -1.41732)
					(mid 0.776878 -1.486459)
					(end 0.70104 -1.532382)
				)
			)
			(stroke
				(width 0)
				(type default)
			)
			(fill yes)
			(layer "F.Paste")
		)
		(fp_poly
			(pts
				(arc
					(start 0.70104 -1.058418)
					(mid 0.792979 -1.119634)
					(end 0.850138 -1.21412)
				)
				(arc
					(start 1.562862 -1.21412)
					(mid 1.614405 -1.125644)
					(end 1.69672 -1.064768)
				)
				(arc
					(start 1.69672 -0.256032)
					(mid 1.625778 -0.207052)
					(end 1.575308 -0.13716)
				)
				(arc
					(start 0.837692 -0.13716)
					(mid 0.781193 -0.212676)
					(end 0.70104 -0.262382)
				)
			)
			(stroke
				(width 0)
				(type default)
			)
			(fill yes)
			(layer "F.Paste")
		)
		(fp_rect
			(start -3.8735 7.2136)
			(end 3.8735 -5.5626)
			(stroke
				(width 0)
				(type default)
			)
			(fill no)
			(layer "F.CrtYd")
		)
		(fp_line
			(start -3.3655 -3.1115)
			(end 3.3655 -3.1115)
			(stroke
				(width 0.1)
				(type default)
			)
			(layer "F.Fab")
		)
		(fp_line
			(start -3.3655 3.1115)
			(end -3.3655 -3.1115)
			(stroke
				(width 0.1)
				(type default)
			)
			(layer "F.Fab")
		)
		(fp_line
			(start -2.8575 4.1275)
			(end -2.8575 5.2705)
			(stroke
				(width 0.1)
				(type default)
			)
			(layer "F.Fab")
		)
		(fp_line
			(start -2.8575 5.2705)
			(end -2.7305 5.2705)
			(stroke
				(width 0.1)
				(type default)
			)
			(layer "F.Fab")
		)
		(fp_line
			(start -2.7305 -3.6195)
			(end -2.7305 0.3175)
			(stroke
				(width 0.1)
				(type default)
			)
			(layer "F.Fab")
		)
		(fp_line
			(start -2.7305 0.3175)
			(end 2.7305 0.3175)
			(stroke
				(width 0.1)
				(type default)
			)
			(layer "F.Fab")
		)
		(fp_line
			(start -2.7305 3.1115)
			(end -2.7305 4.1275)
			(stroke
				(width 0.1)
				(type default)
			)
			(layer "F.Fab")
		)
		(fp_line
			(start -2.7305 4.1275)
			(end -2.8575 4.1275)
			(stroke
				(width 0.1)
				(type default)
			)
			(layer "F.Fab")
		)
		(fp_line
			(start -2.7305 5.2705)
			(end -2.7305 6.0325)
			(stroke
				(width 0.1)
				(type default)
			)
			(layer "F.Fab")
		)
		(fp_line
			(start -2.7305 6.0325)
			(end -1.8415 6.0325)
			(stroke
				(width 0.1)
				(type default)
			)
			(layer "F.Fab")
		)
		(fp_line
			(start -1.9685 -4.3815)
			(end -2.7305 -3.6195)
			(stroke
				(width 0.1)
				(type default)
			)
			(layer "F.Fab")
		)
		(fp_line
			(start -1.8415 4.1275)
			(end -1.8415 3.1115)
			(stroke
				(width 0.1)
				(type default)
			)
			(layer "F.Fab")
		)
		(fp_line
			(start -1.8415 5.2705)
			(end -1.7145 5.2705)
			(stroke
				(width 0.1)
				(type default)
			)
			(layer "F.Fab")
		)
		(fp_line
			(start -1.8415 6.0325)
			(end -1.8415 5.2705)
			(stroke
				(width 0.1)
				(type default)
			)
			(layer "F.Fab")
		)
		(fp_line
			(start -1.7145 4.1275)
			(end -1.8415 4.1275)
			(stroke
				(width 0.1)
				(type default)
			)
			(layer "F.Fab")
		)
		(fp_line
			(start -1.7145 5.2705)
			(end -1.7145 4.1275)
			(stroke
				(width 0.1)
				(type default)
			)
			(layer "F.Fab")
		)
		(fp_line
			(start -0.4445 3.1115)
			(end -0.4445 4.1275)
			(stroke
				(width 0.1)
				(type default)
			)
			(layer "F.Fab")
		)
		(fp_line
			(start -0.4445 4.1275)
			(end 0.4445 4.1275)
			(stroke
				(width 0.1)
				(type default)
			)
			(layer "F.Fab")
		)
		(fp_line
			(start 0.4445 4.1275)
			(end 0.4445 3.1115)
			(stroke
				(width 0.1)
				(type default)
			)
			(layer "F.Fab")
		)
		(fp_line
			(start 1.7145 4.1275)
			(end 1.7145 5.2705)
			(stroke
				(width 0.1)
				(type default)
			)
			(layer "F.Fab")
		)
		(fp_line
			(start 1.7145 5.2705)
			(end 1.8415 5.2705)
			(stroke
				(width 0.1)
				(type default)
			)
			(layer "F.Fab")
		)
		(fp_line
			(start 1.8415 3.1115)
			(end 1.8415 4.1275)
			(stroke
				(width 0.1)
				(type default)
			)
			(layer "F.Fab")
		)
		(fp_line
			(start 1.8415 4.1275)
			(end 1.7145 4.1275)
			(stroke
				(width 0.1)
				(type default)
			)
			(layer "F.Fab")
		)
		(fp_line
			(start 1.8415 5.2705)
			(end 1.8415 6.0325)
			(stroke
				(width 0.1)
				(type default)
			)
			(layer "F.Fab")
		)
		(fp_line
			(start 1.8415 6.0325)
			(end 2.7305 6.0325)
			(stroke
				(width 0.1)
				(type default)
			)
			(layer "F.Fab")
		)
		(fp_line
			(start 1.9685 -4.3815)
			(end -1.9685 -4.3815)
			(stroke
				(width 0.1)
				(type default)
			)
			(layer "F.Fab")
		)
		(fp_line
			(start 2.7305 -3.6195)
			(end 1.9685 -4.3815)
			(stroke
				(width 0.1)
				(type default)
			)
			(layer "F.Fab")
		)
		(fp_line
			(start 2.7305 0.3175)
			(end 2.7305 -3.6195)
			(stroke
				(width 0.1)
				(type default)
			)
			(layer "F.Fab")
		)
		(fp_line
			(start 2.7305 4.1275)
			(end 2.7305 3.1115)
			(stroke
				(width 0.1)
				(type default)
			)
			(layer "F.Fab")
		)
		(fp_line
			(start 2.7305 5.2705)
			(end 2.8575 5.2705)
			(stroke
				(width 0.1)
				(type default)
			)
			(layer "F.Fab")
		)
		(fp_line
			(start 2.7305 6.0325)
			(end 2.7305 5.2705)
			(stroke
				(width 0.1)
				(type default)
			)
			(layer "F.Fab")
		)
		(fp_line
			(start 2.8575 4.1275)
			(end 2.7305 4.1275)
			(stroke
				(width 0.1)
				(type default)
			)
			(layer "F.Fab")
		)
		(fp_line
			(start 2.8575 5.2705)
			(end 2.8575 4.1275)
			(stroke
				(width 0.1)
				(type default)
			)
			(layer "F.Fab")
		)
		(fp_line
			(start 3.3655 -3.1115)
			(end 3.3655 3.1115)
			(stroke
				(width 0.1)
				(type default)
			)
			(layer "F.Fab")
		)
		(fp_line
			(start 3.3655 3.1115)
			(end -3.3655 3.1115)
			(stroke
				(width 0.1)
				(type default)
			)
			(layer "F.Fab")
		)
		(fp_text user "1"
			(at -2.6162 8.19277 0)
			(unlocked yes)
			(layer "F.SilkS")
			(effects
				(font
					(size 0.7874 0.5842)
					(thickness 0.1524)
				)
			)
		)
		(fp_text user "3"
			(at -0.1778 -5.95503 0)
			(unlocked yes)
			(layer "F.SilkS")
			(effects
				(font
					(size 0.7874 0.5842)
					(thickness 0.1524)
				)
			)
		)
		(fp_text user "2"
			(at 3.6068 7.68477 0)
			(unlocked yes)
			(layer "F.SilkS")
			(effects
				(font
					(size 0.7874 0.5842)
					(thickness 0.1524)
				)
			)
		)
		(fp_text user "1"
			(at -2.3114 7.65937 0)
			(unlocked yes)
			(layer "F.Fab")
			(effects
				(font
					(size 0.7874 0.5842)
					(thickness 0.1524)
				)
			)
		)
		(fp_text user "3"
			(at -0.1778 -5.95503 0)
			(unlocked yes)
			(layer "F.Fab")
			(effects
				(font
					(size 0.7874 0.5842)
					(thickness 0.1524)
				)
			)
		)
		(fp_text user "2"
			(at 2.3495 7.67207 0)
			(unlocked yes)
			(layer "F.Fab")
			(effects
				(font
					(size 0.7874 0.5842)
					(thickness 0.1524)
				)
			)
		)
		(pad "1" smd rect
			(at -2.286 5.207)
			(size 1.6002 2.9972)
			(layers "F.Cu" "F.Mask" "F.Paste")
			(net "XP12R0V_PCIE")
		)
		(pad "2" smd rect
			(at 2.286 5.207)
			(size 1.6002 2.9972)
			(layers "F.Cu" "F.Mask" "F.Paste")
			(net "XP12R0V_EXT")
		)
		(pad "3" smd rect
			(at 0 -1.9558)
			(size 5.7912 6.1976)
			(layers "F.Cu" "F.Mask" "F.Paste")
			(net "XP12R0V_IN")
		)
	)
	(footprint ""
		(layer "F.Cu")
		(at 116.205 -61.976 90)
		(property "Reference" "R435"
			(at 3.302 0.92837 90)
			(unlocked yes)
			(layer "F.SilkS")
			(effects
				(font
					(size 0.7874 0.5842)
					(thickness 0.1524)
				)
			)
		)
		(property "Value" "VAL*"
			(at 0.02032 2.13233 90)
			(unlocked yes)
			(layer "F.Fab")
			(hide yes)
			(effects
				(font
					(size 0.7874 0.5842)
					(thickness 0.1524)
				)
			)
		)
		(property "Tolerance" "TOL*"
			(at 0.044704 3.05435 90)
			(unlocked yes)
			(layer "Cmts.User")
			(hide yes)
			(effects
				(font
					(size 0.7874 0.5842)
					(thickness 0.1524)
				)
			)
		)
		(property "User Part Number" "PARTNUM*"
			(at 0.02032 4.024884 90)
			(unlocked yes)
			(layer "Cmts.User")
			(hide yes)
			(effects
				(font
					(size 0.7874 0.5842)
					(thickness 0.1524)
				)
			)
		)
		(property "Device Type" "RESISTOR-G155-11003-01,100KOHMA"
			(at 0.008382 1.210564 90)
			(unlocked yes)
			(layer "F.Fab")
			(hide yes)
			(effects
				(font
					(size 0.7874 0.5842)
					(thickness 0.1524)
				)
			)
		)
		(duplicate_pad_numbers_are_jumpers no)
		(fp_line
			(start 1.143 -0.5588)
			(end -1.143 -0.5588)
			(stroke
				(width 0.1)
				(type default)
			)
			(layer "F.SilkS")
		)
		(fp_line
			(start -1.143 -0.5588)
			(end -1.143 0.5588)
			(stroke
				(width 0.1)
				(type default)
			)
			(layer "F.SilkS")
		)
		(fp_line
			(start 1.143 0.5588)
			(end 1.143 -0.5588)
			(stroke
				(width 0.1)
				(type default)
			)
			(layer "F.SilkS")
		)
		(fp_line
			(start -1.143 0.5588)
			(end 1.143 0.5588)
			(stroke
				(width 0.1)
				(type default)
			)
			(layer "F.SilkS")
		)
		(fp_poly
			(pts
				(xy -1.143 0.5588) (xy 1.143 0.5588) (xy 1.143 -0.5588) (xy -1.143 -0.5588)
			)
			(stroke
				(width 0)
				(type default)
			)
			(fill no)
			(layer "F.CrtYd")
		)
		(fp_line
			(start 0.508 -0.3048)
			(end -0.508 -0.3048)
			(stroke
				(width 0.1)
				(type default)
			)
			(layer "F.Fab")
		)
		(fp_line
			(start -0.508 -0.3048)
			(end -0.508 0.3048)
			(stroke
				(width 0.1)
				(type default)
			)
			(layer "F.Fab")
		)
		(fp_line
			(start 0.508 0.3048)
			(end 0.508 -0.3048)
			(stroke
				(width 0.1)
				(type default)
			)
			(layer "F.Fab")
		)
		(fp_line
			(start -0.508 0.3048)
			(end 0.508 0.3048)
			(stroke
				(width 0.1)
				(type default)
			)
			(layer "F.Fab")
		)
		(pad "1" smd rect
			(at -0.5334 0 90)
			(size 0.7112 0.6096)
			(layers "F.Cu" "F.Mask" "F.Paste")
			(net "FPGA_FLASH_DQ1_MISO")
		)
		(pad "2" smd rect
			(at 0.5334 0 90)
			(size 0.7112 0.6096)
			(layers "F.Cu" "F.Mask" "F.Paste")
			(net "XP3R3V_FPGA")
		)
		(zone
			(layer "F.Cu")
			(hatch none 0.5)
			(connect_pads
				(clearance 0)
			)
			(min_thickness 0.25)
			(keepout
				(tracks not_allowed)
				(vias allowed)
				(pads allowed)
				(copperpour not_allowed)
				(footprints allowed)
			)
			(placement
				(enabled no)
				(sheetname "")
			)
			(fill
				(thermal_gap 0.5)
				(thermal_bridge_width 0.5)
				(island_removal_mode 0)
			)
			(polygon
				(pts
					(xy 116.5098 -61.8998) (xy 116.5098 -62.0522) (xy 115.9002 -62.0522) (xy 115.9002 -61.8998)
				)
			)
		)
		(zone
			(layer "F.Cu")
			(hatch none 0.5)
			(connect_pads
				(clearance 0)
			)
			(min_thickness 0.25)
			(keepout
				(tracks allowed)
				(vias not_allowed)
				(pads allowed)
				(copperpour not_allowed)
				(footprints allowed)
			)
			(placement
				(enabled no)
				(sheetname "")
			)
			(fill
				(thermal_gap 0.5)
				(thermal_bridge_width 0.5)
				(island_removal_mode 0)
			)
			(polygon
				(pts
					(xy 116.5098 -61.8998) (xy 116.5098 -62.0522) (xy 115.9002 -62.0522) (xy 115.9002 -61.8998)
				)
			)
		)
	)
	(footprint ""
		(layer "F.Cu")
		(at 101.1428 -78.486 90)
		(property "Reference" "C190"
			(at 1.524 2.02057 90)
			(unlocked yes)
			(layer "F.SilkS")
			(effects
				(font
					(size 0.7874 0.5842)
					(thickness 0.1524)
				)
			)
		)
		(property "Value" "VAL*"
			(at 0.193548 2.13614 90)
			(unlocked yes)
			(layer "F.Fab")
			(hide yes)
			(effects
				(font
					(size 0.7874 0.5842)
					(thickness 0.1524)
				)
			)
		)
		(property "Tolerance" "TOL*"
			(at 0.216154 3.1496 90)
			(unlocked yes)
			(layer "Cmts.User")
			(hide yes)
			(effects
				(font
					(size 0.7874 0.5842)
					(thickness 0.1524)
				)
			)
		)
		(property "Device Type" "CAPACITOR-G104-0B103-EK,0.01UFA"
			(at 0.184404 1.180592 90)
			(unlocked yes)
			(layer "F.Fab")
			(hide yes)
			(effects
				(font
					(size 0.7874 0.5842)
					(thickness 0.1524)
				)
			)
		)
		(property "User Part Number" "PARTNUM*"
			(at 0.216154 4.185666 90)
			(unlocked yes)
			(layer "Cmts.User")
			(hide yes)
			(effects
				(font
					(size 0.7874 0.5842)
					(thickness 0.1524)
				)
			)
		)
		(duplicate_pad_numbers_are_jumpers no)
		(fp_line
			(start 0.671322 -0.4445)
			(end 0.671322 0.4445)
			(stroke
				(width 0.1)
				(type default)
			)
			(layer "F.SilkS")
		)
		(fp_line
			(start -0.671322 -0.4445)
			(end 0.671322 -0.4445)
			(stroke
				(width 0.1)
				(type default)
			)
			(layer "F.SilkS")
		)
		(fp_line
			(start 0.671322 0.4445)
			(end -0.671322 0.4445)
			(stroke
				(width 0.1)
				(type default)
			)
			(layer "F.SilkS")
		)
		(fp_line
			(start -0.671322 0.4445)
			(end -0.671322 -0.4445)
			(stroke
				(width 0.1)
				(type default)
			)
			(layer "F.SilkS")
		)
		(fp_rect
			(start 0.671322 -0.4445)
			(end -0.671322 0.4445)
			(stroke
				(width 0)
				(type default)
			)
			(fill no)
			(layer "F.CrtYd")
		)
		(fp_line
			(start 0.31496 -0.1651)
			(end -0.31496 -0.1651)
			(stroke
				(width 0.1)
				(type default)
			)
			(layer "F.Fab")
		)
		(fp_line
			(start -0.31496 -0.1651)
			(end -0.31496 0.1651)
			(stroke
				(width 0.1)
				(type default)
			)
			(layer "F.Fab")
		)
		(fp_line
			(start 0.31496 0.1651)
			(end 0.31496 -0.1651)
			(stroke
				(width 0.1)
				(type default)
			)
			(layer "F.Fab")
		)
		(fp_line
			(start -0.31496 0.1651)
			(end 0.31496 0.1651)
			(stroke
				(width 0.1)
				(type default)
			)
			(layer "F.Fab")
		)
		(pad "1" smd rect
			(at -0.264922 0 90)
			(size 0.3048 0.381)
			(layers "F.Cu" "F.Mask" "F.Paste")
			(net "XP1R2V_SS")
		)
		(pad "2" smd rect
			(at 0.264922 0 90)
			(size 0.3048 0.381)
			(layers "F.Cu" "F.Mask" "F.Paste")
			(net "SG")
		)
		(zone
			(layer "F.Cu")
			(hatch none 0.5)
			(connect_pads
				(clearance 0)
			)
			(min_thickness 0.25)
			(keepout
				(tracks allowed)
				(vias not_allowed)
				(pads allowed)
				(copperpour not_allowed)
				(footprints allowed)
			)
			(placement
				(enabled no)
				(sheetname "")
			)
			(fill
				(thermal_gap 0.5)
				(thermal_bridge_width 0.5)
				(island_removal_mode 0)
			)
			(polygon
				(pts
					(xy 100.9523 -78.598522) (xy 100.9523 -78.373478) (xy 101.3333 -78.373478) (xy 101.3333 -78.598522)
				)
			)
		)
	)
	(footprint ""
		(layer "F.Cu")
		(at 128.1938 -64.3636)
		(property "Reference" "C186"
			(at 0.889 5.24637 0)
			(unlocked yes)
			(layer "F.SilkS")
			(effects
				(font
					(size 0.7874 0.5842)
					(thickness 0.1524)
				)
			)
		)
		(property "Value" "VAL*"
			(at 0.0762 3.134106 0)
			(unlocked yes)
			(layer "F.Fab")
			(hide yes)
			(effects
				(font
					(size 0.7874 0.5842)
					(thickness 0.1524)
				)
			)
		)
		(property "Tolerance" "TOL*"
			(at 0.0762 4.048506 0)
			(unlocked yes)
			(layer "Cmts.User")
			(hide yes)
			(effects
				(font
					(size 0.7874 0.5842)
					(thickness 0.1524)
				)
			)
		)
		(property "User Part Number" "PARTNUM*"
			(at 0.1016 5.013706 0)
			(unlocked yes)
			(layer "Cmts.User")
			(hide yes)
			(effects
				(font
					(size 0.7874 0.5842)
					(thickness 0.1524)
				)
			)
		)
		(property "Device Type" "CAPACITOR-G107-0F106-EM,10UF,2A"
			(at 0.0508 2.194306 0)
			(unlocked yes)
			(layer "F.Fab")
			(hide yes)
			(effects
				(font
					(size 0.7874 0.5842)
					(thickness 0.1524)
				)
			)
		)
		(duplicate_pad_numbers_are_jumpers no)
		(fp_line
			(start -1.5748 -0.9398)
			(end -1.5748 0.9398)
			(stroke
				(width 0.1)
				(type default)
			)
			(layer "F.SilkS")
		)
		(fp_line
			(start -1.5748 0.9398)
			(end 1.5748 0.9398)
			(stroke
				(width 0.1)
				(type default)
			)
			(layer "F.SilkS")
		)
		(fp_line
			(start 1.5748 -0.9398)
			(end -1.5748 -0.9398)
			(stroke
				(width 0.1)
				(type default)
			)
			(layer "F.SilkS")
		)
		(fp_line
			(start 1.5748 0.9398)
			(end 1.5748 -0.9398)
			(stroke
				(width 0.1)
				(type default)
			)
			(layer "F.SilkS")
		)
		(fp_rect
			(start 1.5748 -0.9398)
			(end -1.5748 0.9398)
			(stroke
				(width 0)
				(type default)
			)
			(fill no)
			(layer "F.CrtYd")
		)
		(fp_line
			(start -1.016 -0.635)
			(end -1.016 0.635)
			(stroke
				(width 0.1)
				(type default)
			)
			(layer "F.Fab")
		)
		(fp_line
			(start -1.016 0.635)
			(end 1.016 0.635)
			(stroke
				(width 0.1)
				(type default)
			)
			(layer "F.Fab")
		)
		(fp_line
			(start 1.016 -0.635)
			(end -1.016 -0.635)
			(stroke
				(width 0.1)
				(type default)
			)
			(layer "F.Fab")
		)
		(fp_line
			(start 1.016 0.635)
			(end 1.016 -0.635)
			(stroke
				(width 0.1)
				(type default)
			)
			(layer "F.Fab")
		)
		(pad "1" smd rect
			(at -0.8382 0)
			(size 0.9652 1.3716)
			(layers "F.Cu" "F.Mask" "F.Paste")
			(net "XP1R8V_VIN")
		)
		(pad "2" smd rect
			(at 0.8382 0)
			(size 0.9652 1.3716)
			(layers "F.Cu" "F.Mask" "F.Paste")
			(net "SG")
		)
		(zone
			(layer "F.Cu")
			(hatch none 0.5)
			(connect_pads
				(clearance 0)
			)
			(min_thickness 0.25)
			(keepout
				(tracks allowed)
				(vias not_allowed)
				(pads allowed)
				(copperpour not_allowed)
				(footprints allowed)
			)
			(placement
				(enabled no)
				(sheetname "")
			)
			(fill
				(thermal_gap 0.5)
				(thermal_bridge_width 0.5)
				(island_removal_mode 0)
			)
			(polygon
				(pts
					(xy 128.4224 -64.9986) (xy 127.9652 -64.9986) (xy 127.9652 -63.7286) (xy 128.4224 -63.7286)
				)
			)
		)
	)
	(footprint ""
		(layer "F.Cu")
		(at 143.256 -59.436 90)
		(property "Reference" "C264"
			(at 3.175 -1.86563 90)
			(unlocked yes)
			(layer "F.SilkS")
			(effects
				(font
					(size 0.7874 0.5842)
					(thickness 0.1524)
				)
			)
		)
		(property "Value" "VAL*"
			(at 0.193548 2.13614 90)
			(unlocked yes)
			(layer "F.Fab")
			(hide yes)
			(effects
				(font
					(size 0.7874 0.5842)
					(thickness 0.1524)
				)
			)
		)
		(property "Tolerance" "TOL*"
			(at 0.216154 3.1496 90)
			(unlocked yes)
			(layer "Cmts.User")
			(hide yes)
			(effects
				(font
					(size 0.7874 0.5842)
					(thickness 0.1524)
				)
			)
		)
		(property "Device Type" "CAPACITOR-G104-0A180-FJ,18PF,5%"
			(at 0.184404 1.180592 90)
			(unlocked yes)
			(layer "F.Fab")
			(hide yes)
			(effects
				(font
					(size 0.7874 0.5842)
					(thickness 0.1524)
				)
			)
		)
		(property "User Part Number" "PARTNUM*"
			(at 0.216154 4.185666 90)
			(unlocked yes)
			(layer "Cmts.User")
			(hide yes)
			(effects
				(font
					(size 0.7874 0.5842)
					(thickness 0.1524)
				)
			)
		)
		(duplicate_pad_numbers_are_jumpers no)
		(fp_line
			(start 0.671322 -0.4445)
			(end 0.671322 0.4445)
			(stroke
				(width 0.1)
				(type default)
			)
			(layer "F.SilkS")
		)
		(fp_line
			(start -0.671322 -0.4445)
			(end 0.671322 -0.4445)
			(stroke
				(width 0.1)
				(type default)
			)
			(layer "F.SilkS")
		)
		(fp_line
			(start 0.671322 0.4445)
			(end -0.671322 0.4445)
			(stroke
				(width 0.1)
				(type default)
			)
			(layer "F.SilkS")
		)
		(fp_line
			(start -0.671322 0.4445)
			(end -0.671322 -0.4445)
			(stroke
				(width 0.1)
				(type default)
			)
			(layer "F.SilkS")
		)
		(fp_rect
			(start -0.671322 -0.4445)
			(end 0.671322 0.4445)
			(stroke
				(width 0)
				(type default)
			)
			(fill no)
			(layer "F.CrtYd")
		)
		(fp_line
			(start 0.31496 -0.1651)
			(end -0.31496 -0.1651)
			(stroke
				(width 0.1)
				(type default)
			)
			(layer "F.Fab")
		)
		(fp_line
			(start -0.31496 -0.1651)
			(end -0.31496 0.1651)
			(stroke
				(width 0.1)
				(type default)
			)
			(layer "F.Fab")
		)
		(fp_line
			(start 0.31496 0.1651)
			(end 0.31496 -0.1651)
			(stroke
				(width 0.1)
				(type default)
			)
			(layer "F.Fab")
		)
		(fp_line
			(start -0.31496 0.1651)
			(end 0.31496 0.1651)
			(stroke
				(width 0.1)
				(type default)
			)
			(layer "F.Fab")
		)
		(pad "1" smd rect
			(at -0.264922 0 90)
			(size 0.3048 0.381)
			(layers "F.Cu" "F.Mask" "F.Paste")
			(net "XP1R0V_COMP")
		)
		(pad "2" smd rect
			(at 0.264922 0 90)
			(size 0.3048 0.381)
			(layers "F.Cu" "F.Mask" "F.Paste")
			(net "XP1R0V_AGND")
		)
		(zone
			(layer "F.Cu")
			(hatch none 0.5)
			(connect_pads
				(clearance 0)
			)
			(min_thickness 0.25)
			(keepout
				(tracks allowed)
				(vias not_allowed)
				(pads allowed)
				(copperpour not_allowed)
				(footprints allowed)
			)
			(placement
				(enabled no)
				(sheetname "")
			)
			(fill
				(thermal_gap 0.5)
				(thermal_bridge_width 0.5)
				(island_removal_mode 0)
			)
			(polygon
				(pts
					(xy 143.0655 -59.323478) (xy 143.4465 -59.323478) (xy 143.4465 -59.548522) (xy 143.0655 -59.548522)
				)
			)
		)
	)
	(footprint ""
		(layer "F.Cu")
		(at 16.852392 -68.8086 180)
		(property "Reference" "R70"
			(at 1.993392 0.24765 0)
			(unlocked yes)
			(layer "F.SilkS")
			(effects
				(font
					(size 0.635 0.4064)
					(thickness 0.1524)
				)
			)
		)
		(property "Value" "VAL*"
			(at 0.02032 2.13233 180)
			(unlocked yes)
			(layer "F.Fab")
			(hide yes)
			(effects
				(font
					(size 0.7874 0.5842)
					(thickness 0.1524)
				)
			)
		)
		(property "Tolerance" "TOL*"
			(at 0.044704 3.05435 180)
			(unlocked yes)
			(layer "Cmts.User")
			(hide yes)
			(effects
				(font
					(size 0.7874 0.5842)
					(thickness 0.1524)
				)
			)
		)
		(property "User Part Number" "PARTNUM*"
			(at 0.02032 4.024884 180)
			(unlocked yes)
			(layer "Cmts.User")
			(hide yes)
			(effects
				(font
					(size 0.7874 0.5842)
					(thickness 0.1524)
				)
			)
		)
		(property "Device Type" "RESISTOR-G155-14701-01,4.7KOHMA"
			(at 0.008382 1.210564 180)
			(unlocked yes)
			(layer "F.Fab")
			(hide yes)
			(effects
				(font
					(size 0.7874 0.5842)
					(thickness 0.1524)
				)
			)
		)
		(duplicate_pad_numbers_are_jumpers no)
		(fp_line
			(start 1.143 0.5588)
			(end 1.143 -0.5588)
			(stroke
				(width 0.1)
				(type default)
			)
			(layer "F.SilkS")
		)
		(fp_line
			(start 1.143 -0.5588)
			(end -1.143 -0.5588)
			(stroke
				(width 0.1)
				(type default)
			)
			(layer "F.SilkS")
		)
		(fp_line
			(start -1.143 0.5588)
			(end 1.143 0.5588)
			(stroke
				(width 0.1)
				(type default)
			)
			(layer "F.SilkS")
		)
		(fp_line
			(start -1.143 -0.5588)
			(end -1.143 0.5588)
			(stroke
				(width 0.1)
				(type default)
			)
			(layer "F.SilkS")
		)
		(fp_rect
			(start 1.143 0.5588)
			(end -1.143 -0.5588)
			(stroke
				(width 0)
				(type default)
			)
			(fill no)
			(layer "F.CrtYd")
		)
		(fp_line
			(start 0.508 0.3048)
			(end 0.508 -0.3048)
			(stroke
				(width 0.1)
				(type default)
			)
			(layer "F.Fab")
		)
		(fp_line
			(start 0.508 -0.3048)
			(end -0.508 -0.3048)
			(stroke
				(width 0.1)
				(type default)
			)
			(layer "F.Fab")
		)
		(fp_line
			(start -0.508 0.3048)
			(end 0.508 0.3048)
			(stroke
				(width 0.1)
				(type default)
			)
			(layer "F.Fab")
		)
		(fp_line
			(start -0.508 -0.3048)
			(end -0.508 0.3048)
			(stroke
				(width 0.1)
				(type default)
			)
			(layer "F.Fab")
		)
		(pad "1" smd rect
			(at -0.5334 0 180)
			(size 0.7112 0.6096)
			(layers "F.Cu" "F.Mask" "F.Paste")
			(net "XP1R8V_ICP10100")
		)
		(pad "2" smd rect
			(at 0.5334 0 180)
			(size 0.7112 0.6096)
			(layers "F.Cu" "F.Mask" "F.Paste")
			(net "BF_ICP10100_I2C_SDA")
		)
		(zone
			(layer "F.Cu")
			(hatch none 0.5)
			(connect_pads
				(clearance 0)
			)
			(min_thickness 0.25)
			(keepout
				(tracks allowed)
				(vias not_allowed)
				(pads allowed)
				(copperpour not_allowed)
				(footprints allowed)
			)
			(placement
				(enabled no)
				(sheetname "")
			)
			(fill
				(thermal_gap 0.5)
				(thermal_bridge_width 0.5)
				(island_removal_mode 0)
			)
			(polygon
				(pts
					(xy 16.776192 -69.1134) (xy 16.776192 -68.5038) (xy 16.928592 -68.5038) (xy 16.928592 -69.1134)
				)
			)
		)
	)
	(footprint ""
		(layer "F.Cu")
		(at 75.59548 -16.96212)
		(property "Reference" "C37"
			(at 0.35052 -2.81051 0)
			(unlocked yes)
			(layer "F.SilkS")
			(effects
				(font
					(size 0.7874 0.5842)
					(thickness 0.1524)
				)
			)
		)
		(property "Value" "VAL*"
			(at 0.0762 2.067306 0)
			(unlocked yes)
			(layer "F.Fab")
			(hide yes)
			(effects
				(font
					(size 0.7874 0.5842)
					(thickness 0.1524)
				)
			)
		)
		(property "Tolerance" "TOL*"
			(at 0.0762 3.032506 0)
			(unlocked yes)
			(layer "Cmts.User")
			(hide yes)
			(effects
				(font
					(size 0.7874 0.5842)
					(thickness 0.1524)
				)
			)
		)
		(property "User Part Number" "PARTNUM*"
			(at 0.1016 4.023106 0)
			(unlocked yes)
			(layer "Cmts.User")
			(hide yes)
			(effects
				(font
					(size 0.7874 0.5842)
					(thickness 0.1524)
				)
			)
		)
		(property "Device Type" "CAPACITOR-G105-0B104-CK,0.1UF,A"
			(at 0.0508 1.127506 0)
			(unlocked yes)
			(layer "F.Fab")
			(hide yes)
			(effects
				(font
					(size 0.7874 0.5842)
					(thickness 0.1524)
				)
			)
		)
		(duplicate_pad_numbers_are_jumpers no)
		(fp_line
			(start -1.143 -0.5588)
			(end -1.143 0.5588)
			(stroke
				(width 0.1)
				(type default)
			)
			(layer "F.SilkS")
		)
		(fp_line
			(start -1.143 0.5588)
			(end 1.143 0.5588)
			(stroke
				(width 0.1)
				(type default)
			)
			(layer "F.SilkS")
		)
		(fp_line
			(start 1.143 -0.5588)
			(end -1.143 -0.5588)
			(stroke
				(width 0.1)
				(type default)
			)
			(layer "F.SilkS")
		)
		(fp_line
			(start 1.143 0.5588)
			(end 1.143 -0.5588)
			(stroke
				(width 0.1)
				(type default)
			)
			(layer "F.SilkS")
		)
		(fp_rect
			(start -1.143 0.5588)
			(end 1.143 -0.5588)
			(stroke
				(width 0)
				(type default)
			)
			(fill no)
			(layer "F.CrtYd")
		)
		(fp_line
			(start -0.508 -0.3048)
			(end -0.508 0.3048)
			(stroke
				(width 0.1)
				(type default)
			)
			(layer "F.Fab")
		)
		(fp_line
			(start -0.508 0.3048)
			(end 0.508 0.3048)
			(stroke
				(width 0.1)
				(type default)
			)
			(layer "F.Fab")
		)
		(fp_line
			(start 0.508 -0.3048)
			(end -0.508 -0.3048)
			(stroke
				(width 0.1)
				(type default)
			)
			(layer "F.Fab")
		)
		(fp_line
			(start 0.508 0.3048)
			(end 0.508 -0.3048)
			(stroke
				(width 0.1)
				(type default)
			)
			(layer "F.Fab")
		)
		(pad "1" smd rect
			(at -0.5334 0)
			(size 0.7112 0.6096)
			(layers "F.Cu" "F.Mask" "F.Paste")
			(net "XP3R3V_FPGA")
		)
		(pad "2" smd rect
			(at 0.5334 0)
			(size 0.7112 0.6096)
			(layers "F.Cu" "F.Mask" "F.Paste")
			(net "SG")
		)
		(zone
			(layer "F.Cu")
			(hatch none 0.5)
			(connect_pads
				(clearance 0)
			)
			(min_thickness 0.25)
			(keepout
				(tracks allowed)
				(vias not_allowed)
				(pads allowed)
				(copperpour not_allowed)
				(footprints allowed)
			)
			(placement
				(enabled no)
				(sheetname "")
			)
			(fill
				(thermal_gap 0.5)
				(thermal_bridge_width 0.5)
				(island_removal_mode 0)
			)
			(polygon
				(pts
					(xy 75.51928 -16.65732) (xy 75.67168 -16.65732) (xy 75.67168 -17.26692) (xy 75.51928 -17.26692)
				)
			)
		)
	)
	(footprint ""
		(layer "F.Cu")
		(at 143.764 -88.138)
		(property "Reference" "TP43"
			(at -3.8862 -0.08763 0)
			(unlocked yes)
			(layer "F.SilkS")
			(effects
				(font
					(size 0.7874 0.5842)
					(thickness 0.1524)
				)
				(justify left)
			)
		)
		(property "Value" ""
			(at 0 0 0)
			(layer "F.Fab")
			(effects
				(font
					(size 1.27 1.27)
				)
			)
		)
		(property "Device Type" "TP_PIONT-TP010CT020B030_PTH-TPA"
			(at -1.341882 0.996696 0)
			(unlocked yes)
			(layer "F.Fab")
			(hide yes)
			(effects
				(font
					(size 0.7874 0.5842)
					(thickness 0.000001)
				)
				(justify left)
			)
		)
		(duplicate_pad_numbers_are_jumpers no)
		(fp_poly
			(pts
				(arc
					(start 0.889 0)
					(mid -0.889 0)
					(end 0.889 0)
				)
			)
			(stroke
				(width 0)
				(type default)
			)
			(fill no)
			(layer "B.CrtYd")
		)
		(fp_poly
			(pts
				(arc
					(start 0.889 0)
					(mid -0.889 0)
					(end 0.889 0)
				)
			)
			(stroke
				(width 0)
				(type default)
			)
			(fill no)
			(layer "F.CrtYd")
		)
		(pad "1" thru_hole circle
			(at 0 0)
			(size 0.508 0.508)
			(drill 0.254)
			(layers "*.Cu" "*.Mask")
			(remove_unused_layers no)
			(net "XP12R0V_A_EN")
			(clearance 0.1016)
			(padstack
				(mode front_inner_back)
				(layer "Inner"
					(shape circle)
					(size 0.508 0.508)
					(clearance 0.1016)
				)
				(layer "B.Cu"
					(shape circle)
					(size 0.762 0.762)
					(clearance -0.0254)
				)
			)
		)
	)
	(footprint ""
		(layer "F.Cu")
		(at 39.5224 -105.1814 90)
		(property "Reference" "R29"
			(at 1.58623 -1.5494 0)
			(unlocked yes)
			(layer "F.SilkS")
			(effects
				(font
					(size 0.7874 0.5842)
					(thickness 0.1524)
				)
			)
		)
		(property "Value" "VAL*"
			(at 0.02032 2.13233 90)
			(unlocked yes)
			(layer "F.Fab")
			(hide yes)
			(effects
				(font
					(size 0.7874 0.5842)
					(thickness 0.1524)
				)
			)
		)
		(property "Device Type" "RESISTOR-G155-11003-01,100KOHMA"
			(at 0.008382 1.210564 90)
			(unlocked yes)
			(layer "F.Fab")
			(hide yes)
			(effects
				(font
					(size 0.7874 0.5842)
					(thickness 0.1524)
				)
			)
		)
		(property "User Part Number" "PARTNUM*"
			(at 0.02032 4.024884 90)
			(unlocked yes)
			(layer "Cmts.User")
			(hide yes)
			(effects
				(font
					(size 0.7874 0.5842)
					(thickness 0.1524)
				)
			)
		)
		(property "Tolerance" "TOL*"
			(at 0.044704 3.05435 90)
			(unlocked yes)
			(layer "Cmts.User")
			(hide yes)
			(effects
				(font
					(size 0.7874 0.5842)
					(thickness 0.1524)
				)
			)
		)
		(duplicate_pad_numbers_are_jumpers no)
		(fp_line
			(start 1.143 -0.5588)
			(end -1.143 -0.5588)
			(stroke
				(width 0.1)
				(type default)
			)
			(layer "F.SilkS")
		)
		(fp_line
			(start -1.143 -0.5588)
			(end -1.143 0.5588)
			(stroke
				(width 0.1)
				(type default)
			)
			(layer "F.SilkS")
		)
		(fp_line
			(start 1.143 0.5588)
			(end 1.143 -0.5588)
			(stroke
				(width 0.1)
				(type default)
			)
			(layer "F.SilkS")
		)
		(fp_line
			(start -1.143 0.5588)
			(end 1.143 0.5588)
			(stroke
				(width 0.1)
				(type default)
			)
			(layer "F.SilkS")
		)
		(fp_rect
			(start 1.143 0.5588)
			(end -1.143 -0.5588)
			(stroke
				(width 0)
				(type default)
			)
			(fill no)
			(layer "F.CrtYd")
		)
		(fp_line
			(start 0.508 -0.3048)
			(end -0.508 -0.3048)
			(stroke
				(width 0.1)
				(type default)
			)
			(layer "F.Fab")
		)
		(fp_line
			(start -0.508 -0.3048)
			(end -0.508 0.3048)
			(stroke
				(width 0.1)
				(type default)
			)
			(layer "F.Fab")
		)
		(fp_line
			(start 0.508 0.3048)
			(end 0.508 -0.3048)
			(stroke
				(width 0.1)
				(type default)
			)
			(layer "F.Fab")
		)
		(fp_line
			(start -0.508 0.3048)
			(end 0.508 0.3048)
			(stroke
				(width 0.1)
				(type default)
			)
			(layer "F.Fab")
		)
		(pad "1" smd rect
			(at -0.5334 0 90)
			(size 0.7112 0.6096)
			(layers "F.Cu" "F.Mask" "F.Paste")
			(net "XP5R0V_RT")
		)
		(pad "2" smd rect
			(at 0.5334 0 90)
			(size 0.7112 0.6096)
			(layers "F.Cu" "F.Mask" "F.Paste")
			(net "XP5R0V_AGND")
		)
		(zone
			(layer "F.Cu")
			(hatch none 0.5)
			(connect_pads
				(clearance 0)
			)
			(min_thickness 0.25)
			(keepout
				(tracks allowed)
				(vias not_allowed)
				(pads allowed)
				(copperpour not_allowed)
				(footprints allowed)
			)
			(placement
				(enabled no)
				(sheetname "")
			)
			(fill
				(thermal_gap 0.5)
				(thermal_bridge_width 0.5)
				(island_removal_mode 0)
			)
			(polygon
				(pts
					(xy 39.8272 -105.2576) (xy 39.2176 -105.2576) (xy 39.2176 -105.1052) (xy 39.8272 -105.1052)
				)
			)
		)
	)
	(footprint ""
		(layer "F.Cu")
		(at 6.249924 -87.1601 -90)
		(property "Reference" "J13"
			(at -3.60553 1.677924 0)
			(unlocked yes)
			(layer "F.SilkS")
			(effects
				(font
					(size 0.7874 0.5842)
					(thickness 0.1524)
				)
			)
		)
		(property "Value" ""
			(at 0 0 270)
			(layer "F.Fab")
			(effects
				(font
					(size 1.27 1.27)
				)
			)
		)
		(property "Device Type" "CONN_USB_14P_GH4_F_RA_TH-G200-A"
			(at 0.389636 9.511792 270)
			(unlocked yes)
			(layer "F.Fab")
			(hide yes)
			(effects
				(font
					(size 0.7874 0.5842)
					(thickness 0.000001)
				)
			)
		)
		(property "User Part Number" "PARTNUM*"
			(at 0.389636 10.705592 270)
			(unlocked yes)
			(layer "Cmts.User")
			(hide yes)
			(effects
				(font
					(size 0.7874 0.5842)
					(thickness 0.000001)
				)
			)
		)
		(duplicate_pad_numbers_are_jumpers no)
		(fp_line
			(start -2.838704 8.402828)
			(end -2.838704 -6.854952)
			(stroke
				(width 0.1)
				(type default)
			)
			(layer "F.SilkS")
		)
		(fp_line
			(start 3.61823 8.402828)
			(end -2.838704 8.402828)
			(stroke
				(width 0.1)
				(type default)
			)
			(layer "F.SilkS")
		)
		(fp_line
			(start -2.838704 -6.854952)
			(end 3.61823 -6.854952)
			(stroke
				(width 0.1)
				(type default)
			)
			(layer "F.SilkS")
		)
		(fp_line
			(start 3.61823 -6.854952)
			(end 3.61823 8.402828)
			(stroke
				(width 0.1)
				(type default)
			)
			(layer "F.SilkS")
		)
		(fp_poly
			(pts
				(arc
					(start 0.77978 0.145288)
					(mid 0.77978 0.754888)
					(end 0.77978 0.145288)
				)
			)
			(stroke
				(width 0)
				(type default)
			)
			(fill yes)
			(layer "F.Paste")
		)
		(fp_poly
			(pts
				(arc
					(start 0 -0.3048)
					(mid 0 0.3048)
					(end 0 -0.3048)
				)
			)
			(stroke
				(width 0)
				(type default)
			)
			(fill yes)
			(layer "F.Paste")
		)
		(fp_poly
			(pts
				(arc
					(start 0.77978 -0.754888)
					(mid 0.77978 -0.145288)
					(end 0.77978 -0.754888)
				)
			)
			(stroke
				(width 0)
				(type default)
			)
			(fill yes)
			(layer "F.Paste")
		)
		(fp_poly
			(pts
				(arc
					(start 0 -1.204976)
					(mid 0 -0.595376)
					(end 0 -1.204976)
				)
			)
			(stroke
				(width 0)
				(type default)
			)
			(fill yes)
			(layer "F.Paste")
		)
		(fp_poly
			(pts
				(arc
					(start 0.77978 -1.655064)
					(mid 0.77978 -1.045464)
					(end 0.77978 -1.655064)
				)
			)
			(stroke
				(width 0)
				(type default)
			)
			(fill yes)
			(layer "F.Paste")
		)
		(fp_poly
			(pts
				(arc
					(start 0 -2.105152)
					(mid 0 -1.495552)
					(end 0 -2.105152)
				)
			)
			(stroke
				(width 0)
				(type default)
			)
			(fill yes)
			(layer "F.Paste")
		)
		(fp_poly
			(pts
				(arc
					(start 0.77978 -2.55524)
					(mid 0.77978 -1.94564)
					(end 0.77978 -2.55524)
				)
			)
			(stroke
				(width 0)
				(type default)
			)
			(fill yes)
			(layer "F.Paste")
		)
		(fp_poly
			(pts
				(arc
					(start 0 -3.005328)
					(mid 0 -2.395728)
					(end 0 -3.005328)
				)
			)
			(stroke
				(width 0)
				(type default)
			)
			(fill yes)
			(layer "F.Paste")
		)
		(fp_poly
			(pts
				(arc
					(start 0.77978 -3.455416)
					(mid 0.77978 -2.845816)
					(end 0.77978 -3.455416)
				)
			)
			(stroke
				(width 0)
				(type default)
			)
			(fill yes)
			(layer "F.Paste")
		)
		(fp_poly
			(pts
				(arc
					(start 0 -3.905504)
					(mid 0 -3.295904)
					(end 0 -3.905504)
				)
			)
			(stroke
				(width 0)
				(type default)
			)
			(fill yes)
			(layer "F.Paste")
		)
		(fp_poly
			(pts
				(arc
					(start 0.77978 -4.355592)
					(mid 0.77978 -3.745992)
					(end 0.77978 -4.355592)
				)
			)
			(stroke
				(width 0)
				(type default)
			)
			(fill yes)
			(layer "F.Paste")
		)
		(fp_poly
			(pts
				(arc
					(start 0 -4.80568)
					(mid 0 -4.19608)
					(end 0 -4.80568)
				)
			)
			(stroke
				(width 0)
				(type default)
			)
			(fill yes)
			(layer "F.Paste")
		)
		(fp_poly
			(pts
				(arc
					(start 0.77978 -5.255768)
					(mid 0.77978 -4.646168)
					(end 0.77978 -5.255768)
				)
			)
			(stroke
				(width 0)
				(type default)
			)
			(fill yes)
			(layer "F.Paste")
		)
		(fp_poly
			(pts
				(arc
					(start 0 -5.705856)
					(mid 0 -5.096256)
					(end 0 -5.705856)
				)
			)
			(stroke
				(width 0)
				(type default)
			)
			(fill yes)
			(layer "F.Paste")
		)
		(fp_poly
			(pts
				(arc
					(start -0.59563 0.456946)
					(mid -1.04013 0.901446)
					(end -1.48463 0.456946)
				)
				(arc
					(start -1.48463 -0.559054)
					(mid -1.04013 -1.003554)
					(end -0.59563 -0.559054)
				)
			)
			(stroke
				(width 0)
				(type default)
			)
			(fill yes)
			(layer "F.Paste")
		)
		(fp_poly
			(pts
				(arc
					(start 2.26441 0.456946)
					(mid 1.81991 0.901446)
					(end 1.37541 0.456946)
				)
				(arc
					(start 1.37541 -0.559054)
					(mid 1.81991 -1.003554)
					(end 2.26441 -0.559054)
				)
			)
			(stroke
				(width 0)
				(type default)
			)
			(fill yes)
			(layer "F.Paste")
		)
		(fp_poly
			(pts
				(arc
					(start -1.695704 -4.343146)
					(mid -2.140204 -3.898646)
					(end -2.584704 -4.343146)
				)
				(arc
					(start -2.584704 -5.359146)
					(mid -2.140204 -5.803646)
					(end -1.695704 -5.359146)
				)
			)
			(stroke
				(width 0)
				(type default)
			)
			(fill yes)
			(layer "F.Paste")
		)
		(fp_poly
			(pts
				(arc
					(start 3.36423 -4.343146)
					(mid 2.91973 -3.898646)
					(end 2.47523 -4.343146)
				)
				(arc
					(start 2.47523 -5.359146)
					(mid 2.91973 -5.803646)
					(end 3.36423 -5.359146)
				)
			)
			(stroke
				(width 0)
				(type default)
			)
			(fill yes)
			(layer "F.Paste")
		)
		(fp_rect
			(start -7.664704 5.981446)
			(end 8.44423 -10.883646)
			(stroke
				(width 0)
				(type default)
			)
			(fill no)
			(layer "B.CrtYd")
		)
		(fp_rect
			(start -3.092704 8.656828)
			(end 3.87223 -7.108952)
			(stroke
				(width 0)
				(type default)
			)
			(fill no)
			(layer "F.CrtYd")
		)
		(fp_line
			(start -1.59004 8.148828)
			(end -1.59004 -6.600952)
			(stroke
				(width 0.1)
				(type default)
			)
			(layer "F.Fab")
		)
		(fp_line
			(start 2.36982 8.148828)
			(end -1.59004 8.148828)
			(stroke
				(width 0.1)
				(type default)
			)
			(layer "F.Fab")
		)
		(fp_line
			(start -1.59004 -6.600952)
			(end 2.36982 -6.600952)
			(stroke
				(width 0.1)
				(type default)
			)
			(layer "F.Fab")
		)
		(fp_line
			(start 2.36982 -6.600952)
			(end 2.36982 8.148828)
			(stroke
				(width 0.1)
				(type default)
			)
			(layer "F.Fab")
		)
		(fp_text user "B12"
			(at 3.37947 2.503424 0)
			(unlocked yes)
			(layer "F.Fab")
			(effects
				(font
					(size 0.7874 0.5842)
					(thickness 0.1524)
				)
				(justify left)
			)
		)
		(fp_text user "A1"
			(at -3.3147 1.384554 90)
			(unlocked yes)
			(layer "F.Fab")
			(effects
				(font
					(size 0.7874 0.5842)
					(thickness 0.1524)
				)
				(justify right)
			)
		)
		(fp_text user "GH4"
			(at 3.25247 0.217424 0)
			(unlocked yes)
			(layer "F.Fab")
			(effects
				(font
					(size 0.7874 0.5842)
					(thickness 0.1524)
				)
				(justify left)
			)
		)
		(fp_text user "GH3"
			(at -2.33553 -1.433576 0)
			(unlocked yes)
			(layer "F.Fab")
			(effects
				(font
					(size 0.7874 0.5842)
					(thickness 0.1524)
				)
				(justify right)
			)
		)
		(fp_text user "GH2"
			(at 3.37947 -4.227576 0)
			(unlocked yes)
			(layer "F.Fab")
			(effects
				(font
					(size 0.7874 0.5842)
					(thickness 0.1524)
				)
				(justify left)
			)
		)
		(fp_text user "GH1"
			(at -2.58953 -6.005576 0)
			(unlocked yes)
			(layer "F.Fab")
			(effects
				(font
					(size 0.7874 0.5842)
					(thickness 0.1524)
				)
				(justify right)
			)
		)
		(fp_text user "B1"
			(at 2.276602 -7.457186 90)
			(unlocked yes)
			(layer "F.Fab")
			(effects
				(font
					(size 0.7874 0.5842)
					(thickness 0.1524)
				)
				(justify left)
			)
		)
		(fp_text user "A12"
			(at -1.175258 -7.489444 90)
			(unlocked yes)
			(layer "F.Fab")
			(effects
				(font
					(size 0.7874 0.5842)
					(thickness 0.1524)
				)
			)
		)
		(pad "A1" thru_hole circle
			(at 0 0 270)
			(size 0.6096 0.6096)
			(drill 0.4064)
			(layers "*.Cu" "*.Mask")
			(remove_unused_layers no)
			(net "SG")
			(thermal_gap 0.1905)
			(padstack
				(mode front_inner_back)
				(layer "Inner"
					(shape circle)
					(size 0.6096 0.6096)
					(clearance 0.1905)
				)
				(layer "B.Cu"
					(shape circle)
					(size 0.6096 0.6096)
				)
			)
		)
		(pad "A4" thru_hole circle
			(at 0 -0.900176 270)
			(size 0.6096 0.6096)
			(drill 0.4064)
			(layers "*.Cu" "*.Mask")
			(remove_unused_layers no)
			(net "XP5R0V_FT4232")
			(thermal_gap 0.1905)
			(padstack
				(mode front_inner_back)
				(layer "Inner"
					(shape circle)
					(size 0.6096 0.6096)
					(clearance 0.1905)
				)
				(layer "B.Cu"
					(shape circle)
					(size 0.6096 0.6096)
				)
			)
		)
		(pad "A5" thru_hole circle
			(at 0 -1.800352 270)
			(size 0.6096 0.6096)
			(drill 0.4064)
			(layers "*.Cu" "*.Mask")
			(remove_unused_layers no)
			(net "UNNAMED_524_CONNUSB14PGH4FRATH_")
			(thermal_gap 0.1905)
			(padstack
				(mode front_inner_back)
				(layer "Inner"
					(shape circle)
					(size 0.6096 0.6096)
					(clearance 0.1905)
				)
				(layer "B.Cu"
					(shape circle)
					(size 0.6096 0.6096)
				)
			)
		)
		(pad "A9" thru_hole circle
			(at 0 -4.50088 270)
			(size 0.6096 0.6096)
			(drill 0.4064)
			(layers "*.Cu" "*.Mask")
			(remove_unused_layers no)
			(net "XP5R0V_FT4232")
			(thermal_gap 0.1905)
			(padstack
				(mode front_inner_back)
				(layer "Inner"
					(shape circle)
					(size 0.6096 0.6096)
					(clearance 0.1905)
				)
				(layer "B.Cu"
					(shape circle)
					(size 0.6096 0.6096)
				)
			)
		)
		(pad "A12" thru_hole circle
			(at 0 -5.401056 270)
			(size 0.6096 0.6096)
			(drill 0.4064)
			(layers "*.Cu" "*.Mask")
			(remove_unused_layers no)
			(net "SG")
			(thermal_gap 0.1905)
			(padstack
				(mode front_inner_back)
				(layer "Inner"
					(shape circle)
					(size 0.6096 0.6096)
					(clearance 0.1905)
				)
				(layer "B.Cu"
					(shape circle)
					(size 0.6096 0.6096)
				)
			)
		)
		(pad "B1" thru_hole circle
			(at 0.77978 -4.950968 270)
			(size 0.6096 0.6096)
			(drill 0.4064)
			(layers "*.Cu" "*.Mask")
			(remove_unused_layers no)
			(net "SG")
			(thermal_gap 0.1905)
			(padstack
				(mode front_inner_back)
				(layer "Inner"
					(shape circle)
					(size 0.6096 0.6096)
					(clearance 0.1905)
				)
				(layer "B.Cu"
					(shape circle)
					(size 0.6096 0.6096)
				)
			)
		)
		(pad "B4" thru_hole circle
			(at 0.77978 -4.050792 270)
			(size 0.6096 0.6096)
			(drill 0.4064)
			(layers "*.Cu" "*.Mask")
			(remove_unused_layers no)
			(net "XP5R0V_FT4232")
			(thermal_gap 0.1905)
			(padstack
				(mode front_inner_back)
				(layer "Inner"
					(shape circle)
					(size 0.6096 0.6096)
					(clearance 0.1905)
				)
				(layer "B.Cu"
					(shape circle)
					(size 0.6096 0.6096)
				)
			)
		)
		(pad "B5" thru_hole circle
			(at 0.77978 -3.150616 270)
			(size 0.6096 0.6096)
			(drill 0.4064)
			(layers "*.Cu" "*.Mask")
			(remove_unused_layers no)
			(net "UNNAMED_524_CONNUSB14PGH4FRAT_1")
			(thermal_gap 0.1905)
			(padstack
				(mode front_inner_back)
				(layer "Inner"
					(shape circle)
					(size 0.6096 0.6096)
					(clearance 0.1905)
				)
				(layer "B.Cu"
					(shape circle)
					(size 0.6096 0.6096)
				)
			)
		)
		(pad "B9" thru_hole circle
			(at 0.77978 -0.450088 270)
			(size 0.6096 0.6096)
			(drill 0.4064)
			(layers "*.Cu" "*.Mask")
			(remove_unused_layers no)
			(net "XP5R0V_FT4232")
			(thermal_gap 0.1905)
			(padstack
				(mode front_inner_back)
				(layer "Inner"
					(shape circle)
					(size 0.6096 0.6096)
					(clearance 0.1905)
				)
				(layer "B.Cu"
					(shape circle)
					(size 0.6096 0.6096)
				)
			)
		)
		(pad "B12" thru_hole circle
			(at 0.77978 0.450088 270)
			(size 0.6096 0.6096)
			(drill 0.4064)
			(layers "*.Cu" "*.Mask")
			(remove_unused_layers no)
			(net "SG")
			(thermal_gap 0.1905)
			(padstack
				(mode front_inner_back)
				(layer "Inner"
					(shape circle)
					(size 0.6096 0.6096)
					(clearance 0.1905)
				)
				(layer "B.Cu"
					(shape circle)
					(size 0.6096 0.6096)
				)
			)
		)
		(pad "GH1" thru_hole oval
			(at -2.140204 -4.851146 270)
			(size 0.889 1.905)
			(drill oval 0.6096 1.6002)
			(layers "*.Cu" "*.Mask")
			(remove_unused_layers no)
			(net "SG")
			(thermal_gap 0.1524)
			(padstack
				(mode front_inner_back)
				(layer "Inner"
					(shape oval)
					(size 0.889 1.905)
					(clearance 0.1524)
				)
				(layer "B.Cu"
					(shape oval)
					(size 0.889 1.905)
				)
			)
		)
		(pad "GH2" thru_hole oval
			(at 2.91973 -4.851146 270)
			(size 0.889 1.905)
			(drill oval 0.6096 1.6002)
			(layers "*.Cu" "*.Mask")
			(remove_unused_layers no)
			(net "SG")
			(thermal_gap 0.1524)
			(padstack
				(mode front_inner_back)
				(layer "Inner"
					(shape oval)
					(size 0.889 1.905)
					(clearance 0.1524)
				)
				(layer "B.Cu"
					(shape oval)
					(size 0.889 1.905)
				)
			)
		)
		(pad "GH3" thru_hole oval
			(at -1.04013 -0.051054 270)
			(size 0.889 1.905)
			(drill oval 0.6096 1.6002)
			(layers "*.Cu" "*.Mask")
			(remove_unused_layers no)
			(net "SG")
			(thermal_gap 0.1524)
			(padstack
				(mode front_inner_back)
				(layer "Inner"
					(shape oval)
					(size 0.889 1.905)
					(clearance 0.1524)
				)
				(layer "B.Cu"
					(shape oval)
					(size 0.889 1.905)
				)
			)
		)
		(pad "GH4" thru_hole oval
			(at 1.81991 -0.051054 270)
			(size 0.889 1.905)
			(drill oval 0.6096 1.6002)
			(layers "*.Cu" "*.Mask")
			(remove_unused_layers no)
			(net "SG")
			(thermal_gap 0.1524)
			(padstack
				(mode front_inner_back)
				(layer "Inner"
					(shape oval)
					(size 0.889 1.905)
					(clearance 0.1524)
				)
				(layer "B.Cu"
					(shape oval)
					(size 0.889 1.905)
				)
			)
		)
	)
	(footprint ""
		(layer "F.Cu")
		(at 96.52 -53.34)
		(property "Reference" "TP182"
			(at 0 0 0)
			(layer "F.SilkS")
			(hide yes)
			(effects
				(font
					(size 1.27 1.27)
				)
			)
		)
		(property "Value" ""
			(at 0 0 0)
			(layer "F.Fab")
			(effects
				(font
					(size 1.27 1.27)
				)
			)
		)
		(property "Device Type" "TP_PIONT-TP010CT020B030_PTH-TPA"
			(at -1.341882 0.996696 0)
			(unlocked yes)
			(layer "F.Fab")
			(hide yes)
			(effects
				(font
					(size 0.7874 0.5842)
					(thickness 0.1524)
				)
				(justify left)
			)
		)
		(duplicate_pad_numbers_are_jumpers no)
		(fp_poly
			(pts
				(arc
					(start 0.889 0)
					(mid -0.889 0)
					(end 0.889 0)
				)
			)
			(stroke
				(width 0)
				(type default)
			)
			(fill no)
			(layer "B.CrtYd")
		)
		(fp_poly
			(pts
				(arc
					(start 0.889 0)
					(mid -0.889 0)
					(end 0.889 0)
				)
			)
			(stroke
				(width 0)
				(type default)
			)
			(fill no)
			(layer "F.CrtYd")
		)
		(pad "1" thru_hole circle
			(at 0 0)
			(size 0.508 0.508)
			(drill 0.254)
			(layers "*.Cu" "*.Mask")
			(remove_unused_layers no)
			(net "IO_L21N_16")
			(clearance 0.1016)
			(padstack
				(mode front_inner_back)
				(layer "Inner"
					(shape circle)
					(size 0.508 0.508)
					(clearance 0.1016)
				)
				(layer "B.Cu"
					(shape circle)
					(size 0.762 0.762)
					(clearance -0.0254)
				)
			)
		)
	)
	(footprint ""
		(layer "F.Cu")
		(at 139.5984 -99.3648 180)
		(property "Reference" "C8"
			(at 1.5494 -0.09017 0)
			(unlocked yes)
			(layer "F.SilkS")
			(effects
				(font
					(size 0.7874 0.5842)
					(thickness 0.1524)
				)
			)
		)
		(property "Value" "VAL*"
			(at 0.193548 2.13614 180)
			(unlocked yes)
			(layer "F.Fab")
			(hide yes)
			(effects
				(font
					(size 0.7874 0.5842)
					(thickness 0.1524)
				)
			)
		)
		(property "Tolerance" "TOL*"
			(at 0.216154 3.1496 180)
			(unlocked yes)
			(layer "Cmts.User")
			(hide yes)
			(effects
				(font
					(size 0.7874 0.5842)
					(thickness 0.1524)
				)
			)
		)
		(property "Device Type" "CAPACITOR-G104-0B103-EK,0.01UFA"
			(at 0.184404 1.180592 180)
			(unlocked yes)
			(layer "F.Fab")
			(hide yes)
			(effects
				(font
					(size 0.7874 0.5842)
					(thickness 0.1524)
				)
			)
		)
		(property "User Part Number" "PARTNUM*"
			(at 0.216154 4.185666 180)
			(unlocked yes)
			(layer "Cmts.User")
			(hide yes)
			(effects
				(font
					(size 0.7874 0.5842)
					(thickness 0.1524)
				)
			)
		)
		(duplicate_pad_numbers_are_jumpers no)
		(fp_line
			(start 0.671322 0.4445)
			(end -0.671322 0.4445)
			(stroke
				(width 0.1)
				(type default)
			)
			(layer "F.SilkS")
		)
		(fp_line
			(start 0.671322 -0.4445)
			(end 0.671322 0.4445)
			(stroke
				(width 0.1)
				(type default)
			)
			(layer "F.SilkS")
		)
		(fp_line
			(start -0.671322 0.4445)
			(end -0.671322 -0.4445)
			(stroke
				(width 0.1)
				(type default)
			)
			(layer "F.SilkS")
		)
		(fp_line
			(start -0.671322 -0.4445)
			(end 0.671322 -0.4445)
			(stroke
				(width 0.1)
				(type default)
			)
			(layer "F.SilkS")
		)
		(fp_rect
			(start -0.671322 0.4445)
			(end 0.671322 -0.4445)
			(stroke
				(width 0)
				(type default)
			)
			(fill no)
			(layer "F.CrtYd")
		)
		(fp_line
			(start 0.31496 0.1651)
			(end 0.31496 -0.1651)
			(stroke
				(width 0.1)
				(type default)
			)
			(layer "F.Fab")
		)
		(fp_line
			(start 0.31496 -0.1651)
			(end -0.31496 -0.1651)
			(stroke
				(width 0.1)
				(type default)
			)
			(layer "F.Fab")
		)
		(fp_line
			(start -0.31496 0.1651)
			(end 0.31496 0.1651)
			(stroke
				(width 0.1)
				(type default)
			)
			(layer "F.Fab")
		)
		(fp_line
			(start -0.31496 -0.1651)
			(end -0.31496 0.1651)
			(stroke
				(width 0.1)
				(type default)
			)
			(layer "F.Fab")
		)
		(pad "1" smd rect
			(at -0.264922 0 180)
			(size 0.3048 0.381)
			(layers "F.Cu" "F.Mask" "F.Paste")
			(net "XP12R0V_A_OV")
		)
		(pad "2" smd rect
			(at 0.264922 0 180)
			(size 0.3048 0.381)
			(layers "F.Cu" "F.Mask" "F.Paste")
			(net "SG")
		)
		(zone
			(layer "F.Cu")
			(hatch none 0.5)
			(connect_pads
				(clearance 0)
			)
			(min_thickness 0.25)
			(keepout
				(tracks allowed)
				(vias not_allowed)
				(pads allowed)
				(copperpour not_allowed)
				(footprints allowed)
			)
			(placement
				(enabled no)
				(sheetname "")
			)
			(fill
				(thermal_gap 0.5)
				(thermal_bridge_width 0.5)
				(island_removal_mode 0)
			)
			(polygon
				(pts
					(xy 139.710922 -99.5553) (xy 139.485878 -99.5553) (xy 139.485878 -99.1743) (xy 139.710922 -99.1743)
				)
			)
		)
	)
	(footprint ""
		(layer "F.Cu")
		(at 46.609 -75.184 -90)
		(property "Reference" "R487"
			(at 0.381 -2.45237 90)
			(unlocked yes)
			(layer "F.SilkS")
			(effects
				(font
					(size 0.7874 0.5842)
					(thickness 0.1524)
				)
			)
		)
		(property "Value" "VAL*"
			(at 0.02032 2.13233 270)
			(unlocked yes)
			(layer "F.Fab")
			(hide yes)
			(effects
				(font
					(size 0.7874 0.5842)
					(thickness 0.1524)
				)
			)
		)
		(property "Tolerance" "TOL*"
			(at 0.044704 3.05435 270)
			(unlocked yes)
			(layer "Cmts.User")
			(hide yes)
			(effects
				(font
					(size 0.7874 0.5842)
					(thickness 0.1524)
				)
			)
		)
		(property "User Part Number" "PARTNUM*"
			(at 0.02032 4.024884 270)
			(unlocked yes)
			(layer "Cmts.User")
			(hide yes)
			(effects
				(font
					(size 0.7874 0.5842)
					(thickness 0.1524)
				)
			)
		)
		(property "Device Type" "RESISTOR-G155-14701-01,4.7KOHMA"
			(at 0.008382 1.210564 270)
			(unlocked yes)
			(layer "F.Fab")
			(hide yes)
			(effects
				(font
					(size 0.7874 0.5842)
					(thickness 0.1524)
				)
			)
		)
		(duplicate_pad_numbers_are_jumpers no)
		(fp_line
			(start -1.143 0.5588)
			(end 1.143 0.5588)
			(stroke
				(width 0.1)
				(type default)
			)
			(layer "F.SilkS")
		)
		(fp_line
			(start 1.143 0.5588)
			(end 1.143 -0.5588)
			(stroke
				(width 0.1)
				(type default)
			)
			(layer "F.SilkS")
		)
		(fp_line
			(start -1.143 -0.5588)
			(end -1.143 0.5588)
			(stroke
				(width 0.1)
				(type default)
			)
			(layer "F.SilkS")
		)
		(fp_line
			(start 1.143 -0.5588)
			(end -1.143 -0.5588)
			(stroke
				(width 0.1)
				(type default)
			)
			(layer "F.SilkS")
		)
		(fp_poly
			(pts
				(xy -1.143 0.5588) (xy 1.143 0.5588) (xy 1.143 -0.5588) (xy -1.143 -0.5588)
			)
			(stroke
				(width 0)
				(type default)
			)
			(fill no)
			(layer "F.CrtYd")
		)
		(fp_line
			(start -0.508 0.3048)
			(end 0.508 0.3048)
			(stroke
				(width 0.1)
				(type default)
			)
			(layer "F.Fab")
		)
		(fp_line
			(start 0.508 0.3048)
			(end 0.508 -0.3048)
			(stroke
				(width 0.1)
				(type default)
			)
			(layer "F.Fab")
		)
		(fp_line
			(start -0.508 -0.3048)
			(end -0.508 0.3048)
			(stroke
				(width 0.1)
				(type default)
			)
			(layer "F.Fab")
		)
		(fp_line
			(start 0.508 -0.3048)
			(end -0.508 -0.3048)
			(stroke
				(width 0.1)
				(type default)
			)
			(layer "F.Fab")
		)
		(pad "1" smd rect
			(at -0.5334 0 270)
			(size 0.7112 0.6096)
			(layers "F.Cu" "F.Mask" "F.Paste")
			(net "UNNAMED_525_CAPACITOR_I16_1")
		)
		(pad "2" smd rect
			(at 0.5334 0 270)
			(size 0.7112 0.6096)
			(layers "F.Cu" "F.Mask" "F.Paste")
			(net "UNNAMED_525_CAPACITOR_I14_1")
		)
		(zone
			(layer "F.Cu")
			(hatch none 0.5)
			(connect_pads
				(clearance 0)
			)
			(min_thickness 0.25)
			(keepout
				(tracks not_allowed)
				(vias allowed)
				(pads allowed)
				(copperpour not_allowed)
				(footprints allowed)
			)
			(placement
				(enabled no)
				(sheetname "")
			)
			(fill
				(thermal_gap 0.5)
				(thermal_bridge_width 0.5)
				(island_removal_mode 0)
			)
			(polygon
				(pts
					(xy 46.3042 -75.2602) (xy 46.3042 -75.1078) (xy 46.9138 -75.1078) (xy 46.9138 -75.2602)
				)
			)
		)
		(zone
			(layer "F.Cu")
			(hatch none 0.5)
			(connect_pads
				(clearance 0)
			)
			(min_thickness 0.25)
			(keepout
				(tracks allowed)
				(vias not_allowed)
				(pads allowed)
				(copperpour not_allowed)
				(footprints allowed)
			)
			(placement
				(enabled no)
				(sheetname "")
			)
			(fill
				(thermal_gap 0.5)
				(thermal_bridge_width 0.5)
				(island_removal_mode 0)
			)
			(polygon
				(pts
					(xy 46.3042 -75.2602) (xy 46.3042 -75.1078) (xy 46.9138 -75.1078) (xy 46.9138 -75.2602)
				)
			)
		)
	)
	(footprint ""
		(layer "F.Cu")
		(at 29.845 -75.184 -90)
		(property "Reference" "R481"
			(at -0.381 -2.19837 90)
			(unlocked yes)
			(layer "F.SilkS")
			(effects
				(font
					(size 0.7874 0.5842)
					(thickness 0.1524)
				)
			)
		)
		(property "Value" "VAL*"
			(at 0.02032 2.13233 270)
			(unlocked yes)
			(layer "F.Fab")
			(hide yes)
			(effects
				(font
					(size 0.7874 0.5842)
					(thickness 0.1524)
				)
			)
		)
		(property "Tolerance" "TOL*"
			(at 0.044704 3.05435 270)
			(unlocked yes)
			(layer "Cmts.User")
			(hide yes)
			(effects
				(font
					(size 0.7874 0.5842)
					(thickness 0.1524)
				)
			)
		)
		(property "User Part Number" "PARTNUM*"
			(at 0.02032 4.024884 270)
			(unlocked yes)
			(layer "Cmts.User")
			(hide yes)
			(effects
				(font
					(size 0.7874 0.5842)
					(thickness 0.1524)
				)
			)
		)
		(property "Device Type" "RESISTOR-G155-11003-01,100KOHMA"
			(at 0.008382 1.210564 270)
			(unlocked yes)
			(layer "F.Fab")
			(hide yes)
			(effects
				(font
					(size 0.7874 0.5842)
					(thickness 0.1524)
				)
			)
		)
		(duplicate_pad_numbers_are_jumpers no)
		(fp_line
			(start -1.143 0.5588)
			(end 1.143 0.5588)
			(stroke
				(width 0.1)
				(type default)
			)
			(layer "F.SilkS")
		)
		(fp_line
			(start 1.143 0.5588)
			(end 1.143 -0.5588)
			(stroke
				(width 0.1)
				(type default)
			)
			(layer "F.SilkS")
		)
		(fp_line
			(start -1.143 -0.5588)
			(end -1.143 0.5588)
			(stroke
				(width 0.1)
				(type default)
			)
			(layer "F.SilkS")
		)
		(fp_line
			(start 1.143 -0.5588)
			(end -1.143 -0.5588)
			(stroke
				(width 0.1)
				(type default)
			)
			(layer "F.SilkS")
		)
		(fp_poly
			(pts
				(xy -1.143 0.5588) (xy 1.143 0.5588) (xy 1.143 -0.5588) (xy -1.143 -0.5588)
			)
			(stroke
				(width 0)
				(type default)
			)
			(fill no)
			(layer "F.CrtYd")
		)
		(fp_line
			(start -0.508 0.3048)
			(end 0.508 0.3048)
			(stroke
				(width 0.1)
				(type default)
			)
			(layer "F.Fab")
		)
		(fp_line
			(start 0.508 0.3048)
			(end 0.508 -0.3048)
			(stroke
				(width 0.1)
				(type default)
			)
			(layer "F.Fab")
		)
		(fp_line
			(start -0.508 -0.3048)
			(end -0.508 0.3048)
			(stroke
				(width 0.1)
				(type default)
			)
			(layer "F.Fab")
		)
		(fp_line
			(start 0.508 -0.3048)
			(end -0.508 -0.3048)
			(stroke
				(width 0.1)
				(type default)
			)
			(layer "F.Fab")
		)
		(pad "1" smd rect
			(at -0.5334 0 270)
			(size 0.7112 0.6096)
			(layers "F.Cu" "F.Mask" "F.Paste")
			(net "R_FT4232_CHC_RX")
		)
		(pad "2" smd rect
			(at 0.5334 0 270)
			(size 0.7112 0.6096)
			(layers "F.Cu" "F.Mask" "F.Paste")
			(net "XP3R3V_FT4232")
		)
		(zone
			(layer "F.Cu")
			(hatch none 0.5)
			(connect_pads
				(clearance 0)
			)
			(min_thickness 0.25)
			(keepout
				(tracks allowed)
				(vias not_allowed)
				(pads allowed)
				(copperpour not_allowed)
				(footprints allowed)
			)
			(placement
				(enabled no)
				(sheetname "")
			)
			(fill
				(thermal_gap 0.5)
				(thermal_bridge_width 0.5)
				(island_removal_mode 0)
			)
			(polygon
				(pts
					(xy 29.5402 -75.2602) (xy 29.5402 -75.1078) (xy 30.1498 -75.1078) (xy 30.1498 -75.2602)
				)
			)
		)
		(zone
			(layer "F.Cu")
			(hatch none 0.5)
			(connect_pads
				(clearance 0)
			)
			(min_thickness 0.25)
			(keepout
				(tracks not_allowed)
				(vias allowed)
				(pads allowed)
				(copperpour not_allowed)
				(footprints allowed)
			)
			(placement
				(enabled no)
				(sheetname "")
			)
			(fill
				(thermal_gap 0.5)
				(thermal_bridge_width 0.5)
				(island_removal_mode 0)
			)
			(polygon
				(pts
					(xy 29.5402 -75.2602) (xy 29.5402 -75.1078) (xy 30.1498 -75.1078) (xy 30.1498 -75.2602)
				)
			)
		)
	)
	(footprint ""
		(layer "F.Cu")
		(at 36.466018 -26.934922)
		(property "Reference" "ME7"
			(at -0.398018 -4.420108 0)
			(unlocked yes)
			(layer "F.SilkS")
			(effects
				(font
					(size 0.7874 0.5842)
					(thickness 0.1524)
				)
			)
		)
		(property "Value" ""
			(at 0 0 0)
			(layer "F.Fab")
			(effects
				(font
					(size 1.27 1.27)
				)
			)
		)
		(duplicate_pad_numbers_are_jumpers no)
		(fp_poly
			(pts
				(arc
					(start 3.556 0)
					(mid -3.556 0)
					(end 3.556 0)
				)
			)
			(stroke
				(width 0)
				(type default)
			)
			(fill no)
			(layer "B.CrtYd")
		)
		(fp_poly
			(pts
				(arc
					(start 3.556 0)
					(mid -3.556 0)
					(end 3.556 0)
				)
			)
			(stroke
				(width 0)
				(type default)
			)
			(fill no)
			(layer "F.CrtYd")
		)
		(fp_circle
			(center 0 0)
			(end 3.048 0)
			(stroke
				(width 0.1)
				(type default)
			)
			(fill no)
			(layer "B.Fab")
		)
		(fp_circle
			(center 0 0)
			(end 3.048 0)
			(stroke
				(width 0.1)
				(type default)
			)
			(fill no)
			(layer "F.Fab")
		)
		(pad "" np_thru_hole circle
			(at 0 0)
			(size 2.286 2.286)
			(drill 2.54)
			(layers "*.Cu" "*.Mask")
			(padstack
				(mode front_inner_back)
				(layer "Inner"
					(shape circle)
					(size 2.286 2.286)
					(clearance 0.4445)
				)
				(layer "B.Cu"
					(shape circle)
					(size 2.286 2.286)
				)
			)
		)
		(zone
			(layers "F.Cu" "B.Cu" "In1.Cu" "In2.Cu" "In3.Cu" "In4.Cu" "In5.Cu" "In6.Cu"
				"In7.Cu" "In8.Cu"
			)
			(hatch none 0.5)
			(connect_pads
				(clearance 0)
			)
			(min_thickness 0.25)
			(keepout
				(tracks not_allowed)
				(vias allowed)
				(pads allowed)
				(copperpour not_allowed)
				(footprints allowed)
			)
			(placement
				(enabled no)
				(sheetname "")
			)
			(fill
				(thermal_gap 0.5)
				(thermal_bridge_width 0.5)
				(island_removal_mode 0)
			)
			(polygon
				(pts
					(arc
						(start 38.040818 -26.934922)
						(mid 34.891218 -26.934922)
						(end 38.040818 -26.934922)
					)
				)
			)
		)
	)
	(footprint ""
		(layer "F.Cu")
		(at 9.4234 -39.318692 90)
		(property "Reference" "R125"
			(at 2.337308 -0.17145 90)
			(unlocked yes)
			(layer "F.SilkS")
			(effects
				(font
					(size 0.635 0.4064)
					(thickness 0.1524)
				)
			)
		)
		(property "Value" "VAL*"
			(at 0.02032 2.13233 90)
			(unlocked yes)
			(layer "F.Fab")
			(hide yes)
			(effects
				(font
					(size 0.7874 0.5842)
					(thickness 0.1524)
				)
			)
		)
		(property "Device Type" "RESISTOR-G155-11000-01,100OHM,A"
			(at 0.008382 1.210564 90)
			(unlocked yes)
			(layer "F.Fab")
			(hide yes)
			(effects
				(font
					(size 0.7874 0.5842)
					(thickness 0.1524)
				)
			)
		)
		(property "User Part Number" "PARTNUM*"
			(at 0.02032 4.024884 90)
			(unlocked yes)
			(layer "Cmts.User")
			(hide yes)
			(effects
				(font
					(size 0.7874 0.5842)
					(thickness 0.1524)
				)
			)
		)
		(property "Tolerance" "TOL*"
			(at 0.044704 3.05435 90)
			(unlocked yes)
			(layer "Cmts.User")
			(hide yes)
			(effects
				(font
					(size 0.7874 0.5842)
					(thickness 0.1524)
				)
			)
		)
		(duplicate_pad_numbers_are_jumpers no)
		(fp_line
			(start 1.143 -0.5588)
			(end -1.143 -0.5588)
			(stroke
				(width 0.1)
				(type default)
			)
			(layer "F.SilkS")
		)
		(fp_line
			(start -1.143 -0.5588)
			(end -1.143 0.5588)
			(stroke
				(width 0.1)
				(type default)
			)
			(layer "F.SilkS")
		)
		(fp_line
			(start 1.143 0.5588)
			(end 1.143 -0.5588)
			(stroke
				(width 0.1)
				(type default)
			)
			(layer "F.SilkS")
		)
		(fp_line
			(start -1.143 0.5588)
			(end 1.143 0.5588)
			(stroke
				(width 0.1)
				(type default)
			)
			(layer "F.SilkS")
		)
		(fp_poly
			(pts
				(xy -1.143 0.5588) (xy 1.143 0.5588) (xy 1.143 -0.5588) (xy -1.143 -0.5588)
			)
			(stroke
				(width 0)
				(type default)
			)
			(fill no)
			(layer "F.CrtYd")
		)
		(fp_line
			(start 0.508 -0.3048)
			(end -0.508 -0.3048)
			(stroke
				(width 0.1)
				(type default)
			)
			(layer "F.Fab")
		)
		(fp_line
			(start -0.508 -0.3048)
			(end -0.508 0.3048)
			(stroke
				(width 0.1)
				(type default)
			)
			(layer "F.Fab")
		)
		(fp_line
			(start 0.508 0.3048)
			(end 0.508 -0.3048)
			(stroke
				(width 0.1)
				(type default)
			)
			(layer "F.Fab")
		)
		(fp_line
			(start -0.508 0.3048)
			(end 0.508 0.3048)
			(stroke
				(width 0.1)
				(type default)
			)
			(layer "F.Fab")
		)
		(pad "1" smd rect
			(at -0.5334 0 90)
			(size 0.7112 0.6096)
			(layers "F.Cu" "F.Mask" "F.Paste")
			(net "FPGA_OUT_SMA1_LED_GREEN_N")
		)
		(pad "2" smd rect
			(at 0.5334 0 90)
			(size 0.7112 0.6096)
			(layers "F.Cu" "F.Mask" "F.Paste")
			(net "UNNAMED_14_LED4PV14_I265_4")
		)
		(zone
			(layer "F.Cu")
			(hatch none 0.5)
			(connect_pads
				(clearance 0)
			)
			(min_thickness 0.25)
			(keepout
				(tracks not_allowed)
				(vias allowed)
				(pads allowed)
				(copperpour not_allowed)
				(footprints allowed)
			)
			(placement
				(enabled no)
				(sheetname "")
			)
			(fill
				(thermal_gap 0.5)
				(thermal_bridge_width 0.5)
				(island_removal_mode 0)
			)
			(polygon
				(pts
					(xy 9.7282 -39.242492) (xy 9.7282 -39.394892) (xy 9.1186 -39.394892) (xy 9.1186 -39.242492)
				)
			)
		)
		(zone
			(layer "F.Cu")
			(hatch none 0.5)
			(connect_pads
				(clearance 0)
			)
			(min_thickness 0.25)
			(keepout
				(tracks allowed)
				(vias not_allowed)
				(pads allowed)
				(copperpour not_allowed)
				(footprints allowed)
			)
			(placement
				(enabled no)
				(sheetname "")
			)
			(fill
				(thermal_gap 0.5)
				(thermal_bridge_width 0.5)
				(island_removal_mode 0)
			)
			(polygon
				(pts
					(xy 9.7282 -39.242492) (xy 9.7282 -39.394892) (xy 9.1186 -39.394892) (xy 9.1186 -39.242492)
				)
			)
		)
	)
	(footprint ""
		(layer "F.Cu")
		(at 151.257 -60.706)
		(property "Reference" "TP26"
			(at -0.7112 -1.48463 0)
			(unlocked yes)
			(layer "F.SilkS")
			(effects
				(font
					(size 0.7874 0.5842)
					(thickness 0.1524)
				)
				(justify left)
			)
		)
		(property "Value" ""
			(at 0 0 0)
			(layer "F.Fab")
			(effects
				(font
					(size 1.27 1.27)
				)
			)
		)
		(property "Device Type" "TP_PIONT-TP010CT020B030_PTH-TPA"
			(at -1.341882 0.996696 0)
			(unlocked yes)
			(layer "F.Fab")
			(hide yes)
			(effects
				(font
					(size 0.7874 0.5842)
					(thickness 0.000001)
				)
				(justify left)
			)
		)
		(duplicate_pad_numbers_are_jumpers no)
		(fp_poly
			(pts
				(arc
					(start 0.889 0)
					(mid -0.889 0)
					(end 0.889 0)
				)
			)
			(stroke
				(width 0)
				(type default)
			)
			(fill no)
			(layer "B.CrtYd")
		)
		(fp_poly
			(pts
				(arc
					(start 0.889 0)
					(mid -0.889 0)
					(end 0.889 0)
				)
			)
			(stroke
				(width 0)
				(type default)
			)
			(fill no)
			(layer "F.CrtYd")
		)
		(pad "1" thru_hole circle
			(at 0 0)
			(size 0.508 0.508)
			(drill 0.254)
			(layers "*.Cu" "*.Mask")
			(remove_unused_layers no)
			(net "R_SHT3X_RST_N")
			(clearance 0.1016)
			(padstack
				(mode front_inner_back)
				(layer "Inner"
					(shape circle)
					(size 0.508 0.508)
					(clearance 0.1016)
				)
				(layer "B.Cu"
					(shape circle)
					(size 0.762 0.762)
					(clearance -0.0254)
				)
			)
		)
	)
	(footprint ""
		(layer "F.Cu")
		(at 116.459 -29.464 -90)
		(property "Reference" "R438"
			(at 2.794 -0.80137 90)
			(unlocked yes)
			(layer "F.SilkS")
			(effects
				(font
					(size 0.7874 0.5842)
					(thickness 0.1524)
				)
			)
		)
		(property "Value" "VAL*"
			(at 0.02032 2.13233 270)
			(unlocked yes)
			(layer "F.Fab")
			(hide yes)
			(effects
				(font
					(size 0.7874 0.5842)
					(thickness 0.1524)
				)
			)
		)
		(property "Tolerance" "TOL*"
			(at 0.044704 3.05435 270)
			(unlocked yes)
			(layer "Cmts.User")
			(hide yes)
			(effects
				(font
					(size 0.7874 0.5842)
					(thickness 0.1524)
				)
			)
		)
		(property "User Part Number" "PARTNUM*"
			(at 0.02032 4.024884 270)
			(unlocked yes)
			(layer "Cmts.User")
			(hide yes)
			(effects
				(font
					(size 0.7874 0.5842)
					(thickness 0.1524)
				)
			)
		)
		(property "Device Type" "RESISTOR-G155-11002-01,10KOHM,A"
			(at 0.008382 1.210564 270)
			(unlocked yes)
			(layer "F.Fab")
			(hide yes)
			(effects
				(font
					(size 0.7874 0.5842)
					(thickness 0.1524)
				)
			)
		)
		(duplicate_pad_numbers_are_jumpers no)
		(fp_line
			(start -1.143 0.5588)
			(end 1.143 0.5588)
			(stroke
				(width 0.1)
				(type default)
			)
			(layer "F.SilkS")
		)
		(fp_line
			(start 1.143 0.5588)
			(end 1.143 -0.5588)
			(stroke
				(width 0.1)
				(type default)
			)
			(layer "F.SilkS")
		)
		(fp_line
			(start -1.143 -0.5588)
			(end -1.143 0.5588)
			(stroke
				(width 0.1)
				(type default)
			)
			(layer "F.SilkS")
		)
		(fp_line
			(start 1.143 -0.5588)
			(end -1.143 -0.5588)
			(stroke
				(width 0.1)
				(type default)
			)
			(layer "F.SilkS")
		)
		(fp_poly
			(pts
				(xy -1.143 0.5588) (xy 1.143 0.5588) (xy 1.143 -0.5588) (xy -1.143 -0.5588)
			)
			(stroke
				(width 0)
				(type default)
			)
			(fill no)
			(layer "F.CrtYd")
		)
		(fp_line
			(start -0.508 0.3048)
			(end 0.508 0.3048)
			(stroke
				(width 0.1)
				(type default)
			)
			(layer "F.Fab")
		)
		(fp_line
			(start 0.508 0.3048)
			(end 0.508 -0.3048)
			(stroke
				(width 0.1)
				(type default)
			)
			(layer "F.Fab")
		)
		(fp_line
			(start -0.508 -0.3048)
			(end -0.508 0.3048)
			(stroke
				(width 0.1)
				(type default)
			)
			(layer "F.Fab")
		)
		(fp_line
			(start 0.508 -0.3048)
			(end -0.508 -0.3048)
			(stroke
				(width 0.1)
				(type default)
			)
			(layer "F.Fab")
		)
		(pad "1" smd rect
			(at -0.5334 0 270)
			(size 0.7112 0.6096)
			(layers "F.Cu" "F.Mask" "F.Paste")
			(net "FPGA_IN_MAC_PPS_OUTN")
		)
		(pad "2" smd rect
			(at 0.5334 0 270)
			(size 0.7112 0.6096)
			(layers "F.Cu" "F.Mask" "F.Paste")
			(net "XP2R5V_FPGA")
		)
		(zone
			(layer "F.Cu")
			(hatch none 0.5)
			(connect_pads
				(clearance 0)
			)
			(min_thickness 0.25)
			(keepout
				(tracks allowed)
				(vias not_allowed)
				(pads allowed)
				(copperpour not_allowed)
				(footprints allowed)
			)
			(placement
				(enabled no)
				(sheetname "")
			)
			(fill
				(thermal_gap 0.5)
				(thermal_bridge_width 0.5)
				(island_removal_mode 0)
			)
			(polygon
				(pts
					(xy 116.1542 -29.5402) (xy 116.1542 -29.3878) (xy 116.7638 -29.3878) (xy 116.7638 -29.5402)
				)
			)
		)
		(zone
			(layer "F.Cu")
			(hatch none 0.5)
			(connect_pads
				(clearance 0)
			)
			(min_thickness 0.25)
			(keepout
				(tracks not_allowed)
				(vias allowed)
				(pads allowed)
				(copperpour not_allowed)
				(footprints allowed)
			)
			(placement
				(enabled no)
				(sheetname "")
			)
			(fill
				(thermal_gap 0.5)
				(thermal_bridge_width 0.5)
				(island_removal_mode 0)
			)
			(polygon
				(pts
					(xy 116.1542 -29.5402) (xy 116.1542 -29.3878) (xy 116.7638 -29.3878) (xy 116.7638 -29.5402)
				)
			)
		)
	)
	(footprint ""
		(layer "F.Cu")
		(at 93.726 -105.029 180)
		(property "Reference" "TP59"
			(at -0.8128 -0.16637 0)
			(unlocked yes)
			(layer "F.SilkS")
			(effects
				(font
					(size 0.7874 0.5842)
					(thickness 0.1524)
				)
				(justify left)
			)
		)
		(property "Value" ""
			(at 0 0 180)
			(layer "F.Fab")
			(effects
				(font
					(size 1.27 1.27)
				)
			)
		)
		(property "Device Type" "TP_PIONT-TP010CT020B030_PTH-TPA"
			(at -1.341882 0.996696 180)
			(unlocked yes)
			(layer "F.Fab")
			(hide yes)
			(effects
				(font
					(size 0.7874 0.5842)
					(thickness 0.1524)
				)
				(justify left)
			)
		)
		(duplicate_pad_numbers_are_jumpers no)
		(fp_poly
			(pts
				(arc
					(start -0.889 0)
					(mid 0.889 0)
					(end -0.889 0)
				)
			)
			(stroke
				(width 0)
				(type default)
			)
			(fill no)
			(layer "B.CrtYd")
		)
		(fp_poly
			(pts
				(arc
					(start -0.889 0)
					(mid 0.889 0)
					(end -0.889 0)
				)
			)
			(stroke
				(width 0)
				(type default)
			)
			(fill no)
			(layer "F.CrtYd")
		)
		(pad "1" thru_hole circle
			(at 0 0 180)
			(size 0.508 0.508)
			(drill 0.254)
			(layers "*.Cu" "*.Mask")
			(remove_unused_layers no)
			(net "XP3R3V_EN")
			(clearance 0.1016)
			(padstack
				(mode front_inner_back)
				(layer "Inner"
					(shape circle)
					(size 0.508 0.508)
					(clearance 0.1016)
				)
				(layer "B.Cu"
					(shape circle)
					(size 0.762 0.762)
					(clearance -0.0254)
				)
			)
		)
	)
	(footprint ""
		(layer "F.Cu")
		(at 95.631 -26.924)
		(property "Reference" "C291"
			(at -1.397 -1.73863 0)
			(unlocked yes)
			(layer "F.SilkS")
			(effects
				(font
					(size 0.7874 0.5842)
					(thickness 0.1524)
				)
			)
		)
		(property "Value" "VAL*"
			(at 0.0762 3.134106 0)
			(unlocked yes)
			(layer "F.Fab")
			(hide yes)
			(effects
				(font
					(size 0.7874 0.5842)
					(thickness 0.1524)
				)
			)
		)
		(property "Device Type" "CAPACITOR-G107-0F226-CM,22UF,2A"
			(at 0.0508 2.194306 0)
			(unlocked yes)
			(layer "F.Fab")
			(hide yes)
			(effects
				(font
					(size 0.7874 0.5842)
					(thickness 0.1524)
				)
			)
		)
		(property "User Part Number" "PARTNUM*"
			(at 0.1016 5.013706 0)
			(unlocked yes)
			(layer "Cmts.User")
			(hide yes)
			(effects
				(font
					(size 0.7874 0.5842)
					(thickness 0.1524)
				)
			)
		)
		(property "Tolerance" "TOL*"
			(at 0.0762 4.048506 0)
			(unlocked yes)
			(layer "Cmts.User")
			(hide yes)
			(effects
				(font
					(size 0.7874 0.5842)
					(thickness 0.1524)
				)
			)
		)
		(duplicate_pad_numbers_are_jumpers no)
		(fp_line
			(start -1.5748 -0.9398)
			(end -1.5748 0.9398)
			(stroke
				(width 0.1)
				(type default)
			)
			(layer "F.SilkS")
		)
		(fp_line
			(start -1.5748 0.9398)
			(end 1.5748 0.9398)
			(stroke
				(width 0.1)
				(type default)
			)
			(layer "F.SilkS")
		)
		(fp_line
			(start 1.5748 -0.9398)
			(end -1.5748 -0.9398)
			(stroke
				(width 0.1)
				(type default)
			)
			(layer "F.SilkS")
		)
		(fp_line
			(start 1.5748 0.9398)
			(end 1.5748 -0.9398)
			(stroke
				(width 0.1)
				(type default)
			)
			(layer "F.SilkS")
		)
		(fp_rect
			(start 1.5748 -0.9398)
			(end -1.5748 0.9398)
			(stroke
				(width 0)
				(type default)
			)
			(fill no)
			(layer "F.CrtYd")
		)
		(fp_line
			(start -1.016 -0.635)
			(end -1.016 0.635)
			(stroke
				(width 0.1)
				(type default)
			)
			(layer "F.Fab")
		)
		(fp_line
			(start -1.016 0.635)
			(end 1.016 0.635)
			(stroke
				(width 0.1)
				(type default)
			)
			(layer "F.Fab")
		)
		(fp_line
			(start 1.016 -0.635)
			(end -1.016 -0.635)
			(stroke
				(width 0.1)
				(type default)
			)
			(layer "F.Fab")
		)
		(fp_line
			(start 1.016 0.635)
			(end 1.016 -0.635)
			(stroke
				(width 0.1)
				(type default)
			)
			(layer "F.Fab")
		)
		(pad "1" smd rect
			(at -0.8382 0)
			(size 0.9652 1.3716)
			(layers "F.Cu" "F.Mask" "F.Paste")
			(net "XP2R5V_FPGA")
		)
		(pad "2" smd rect
			(at 0.8382 0)
			(size 0.9652 1.3716)
			(layers "F.Cu" "F.Mask" "F.Paste")
			(net "SG")
		)
		(zone
			(layer "F.Cu")
			(hatch none 0.5)
			(connect_pads
				(clearance 0)
			)
			(min_thickness 0.25)
			(keepout
				(tracks not_allowed)
				(vias allowed)
				(pads allowed)
				(copperpour not_allowed)
				(footprints allowed)
			)
			(placement
				(enabled no)
				(sheetname "")
			)
			(fill
				(thermal_gap 0.5)
				(thermal_bridge_width 0.5)
				(island_removal_mode 0)
			)
			(polygon
				(pts
					(xy 95.8596 -27.559) (xy 95.4024 -27.559) (xy 95.4024 -26.289) (xy 95.8596 -26.289)
				)
			)
		)
		(zone
			(layer "F.Cu")
			(hatch none 0.5)
			(connect_pads
				(clearance 0)
			)
			(min_thickness 0.25)
			(keepout
				(tracks allowed)
				(vias not_allowed)
				(pads allowed)
				(copperpour not_allowed)
				(footprints allowed)
			)
			(placement
				(enabled no)
				(sheetname "")
			)
			(fill
				(thermal_gap 0.5)
				(thermal_bridge_width 0.5)
				(island_removal_mode 0)
			)
			(polygon
				(pts
					(xy 95.8596 -27.559) (xy 95.4024 -27.559) (xy 95.4024 -26.289) (xy 95.8596 -26.289)
				)
			)
		)
	)
	(footprint ""
		(layer "F.Cu")
		(at 144.050004 -104.350058 -90)
		(property "Reference" "DS8"
			(at 0.718058 1.397254 90)
			(unlocked yes)
			(layer "F.SilkS")
			(effects
				(font
					(size 0.635 0.4064)
					(thickness 0.1524)
				)
			)
		)
		(property "Value" ""
			(at 0 0 270)
			(layer "F.Fab")
			(effects
				(font
					(size 1.27 1.27)
				)
			)
		)
		(property "Device Type" "OPTICAL-G170-10143-01"
			(at 0.1778 1.483081 270)
			(unlocked yes)
			(layer "F.Fab")
			(hide yes)
			(effects
				(font
					(size 0.786892 0.583946)
					(thickness 0.000001)
				)
			)
		)
		(property "User Part Number" "PARTNUM*"
			(at 0.1778 2.422881 270)
			(unlocked yes)
			(layer "Cmts.User")
			(hide yes)
			(effects
				(font
					(size 0.786892 0.583946)
					(thickness 0.000001)
				)
			)
		)
		(duplicate_pad_numbers_are_jumpers no)
		(fp_line
			(start -1.0668 1.3462)
			(end -2.3368 1.3462)
			(stroke
				(width 0.1)
				(type default)
			)
			(layer "F.SilkS")
		)
		(fp_line
			(start -1.7018 0.7112)
			(end -1.7018 1.9812)
			(stroke
				(width 0.1)
				(type default)
			)
			(layer "F.SilkS")
		)
		(fp_line
			(start -1.397508 0.704088)
			(end -1.397508 -0.704088)
			(stroke
				(width 0.1)
				(type default)
			)
			(layer "F.SilkS")
		)
		(fp_line
			(start 1.397508 0.704088)
			(end -1.397508 0.704088)
			(stroke
				(width 0.1)
				(type default)
			)
			(layer "F.SilkS")
		)
		(fp_line
			(start -1.397508 -0.704088)
			(end 1.397508 -0.704088)
			(stroke
				(width 0.1)
				(type default)
			)
			(layer "F.SilkS")
		)
		(fp_line
			(start 1.397508 -0.704088)
			(end 1.397508 0.704088)
			(stroke
				(width 0.1)
				(type default)
			)
			(layer "F.SilkS")
		)
		(fp_rect
			(start 1.905508 0.704088)
			(end 1.397508 -0.704088)
			(stroke
				(width 0)
				(type default)
			)
			(fill yes)
			(layer "F.SilkS")
		)
		(fp_rect
			(start 1.905508 0.958088)
			(end -1.651508 -0.958088)
			(stroke
				(width 0)
				(type default)
			)
			(fill no)
			(layer "F.CrtYd")
		)
		(fp_line
			(start -0.6858 1.0922)
			(end -1.9558 1.0922)
			(stroke
				(width 0.1)
				(type default)
			)
			(layer "F.Fab")
		)
		(fp_line
			(start -1.3208 0.4572)
			(end -1.3208 1.7272)
			(stroke
				(width 0.1)
				(type default)
			)
			(layer "F.Fab")
		)
		(fp_line
			(start -0.850138 0.450088)
			(end 0.850138 0.450088)
			(stroke
				(width 0.1)
				(type default)
			)
			(layer "F.Fab")
		)
		(fp_line
			(start 0.850138 0.450088)
			(end 0.850138 -0.450088)
			(stroke
				(width 0.1)
				(type default)
			)
			(layer "F.Fab")
		)
		(fp_line
			(start -0.850138 -0.450088)
			(end -0.850138 0.450088)
			(stroke
				(width 0.1)
				(type default)
			)
			(layer "F.Fab")
		)
		(fp_line
			(start 0.850138 -0.450088)
			(end -0.850138 -0.450088)
			(stroke
				(width 0.1)
				(type default)
			)
			(layer "F.Fab")
		)
		(fp_rect
			(start 0.850138 0.450088)
			(end 0.342138 -0.450088)
			(stroke
				(width 0)
				(type default)
			)
			(fill yes)
			(layer "F.Fab")
		)
		(fp_text user "A"
			(at -1.155192 1.683004 0)
			(unlocked yes)
			(layer "F.SilkS")
			(effects
				(font
					(size 0.635 0.4064)
					(thickness 0.1524)
				)
			)
		)
		(fp_text user "C"
			(at 2.400808 -0.983996 0)
			(unlocked yes)
			(layer "F.SilkS")
			(effects
				(font
					(size 0.635 0.4064)
					(thickness 0.1524)
				)
			)
		)
		(fp_text user "A"
			(at -1.49733 -0.7112 0)
			(unlocked yes)
			(layer "F.Fab")
			(effects
				(font
					(size 0.7874 0.5842)
					(thickness 0.1524)
				)
			)
		)
		(fp_text user "C"
			(at 1.773428 -0.856996 0)
			(unlocked yes)
			(layer "F.Fab")
			(effects
				(font
					(size 0.7874 0.5842)
					(thickness 0.1524)
				)
			)
		)
		(pad "A" smd rect
			(at -0.749808 0 270)
			(size 0.7874 0.7874)
			(layers "F.Cu" "F.Mask" "F.Paste")
			(net "UNNAMED_14_OPTICAL_I142_A")
		)
		(pad "C" smd rect
			(at 0.749808 0 270)
			(size 0.7874 0.7874)
			(layers "F.Cu" "F.Mask" "F.Paste")
			(net "SG")
		)
	)
	(footprint ""
		(layer "F.Cu")
		(at 50.74158 -15.5194 -90)
		(property "Reference" "R354"
			(at -3.4036 -0.09779 90)
			(unlocked yes)
			(layer "F.SilkS")
			(effects
				(font
					(size 0.7874 0.5842)
					(thickness 0.1524)
				)
			)
		)
		(property "Value" "VAL*"
			(at 0.02032 2.13233 270)
			(unlocked yes)
			(layer "F.Fab")
			(hide yes)
			(effects
				(font
					(size 0.7874 0.5842)
					(thickness 0.1524)
				)
			)
		)
		(property "Tolerance" "TOL*"
			(at 0.044704 3.05435 270)
			(unlocked yes)
			(layer "Cmts.User")
			(hide yes)
			(effects
				(font
					(size 0.7874 0.5842)
					(thickness 0.1524)
				)
			)
		)
		(property "User Part Number" "PARTNUM*"
			(at 0.02032 4.024884 270)
			(unlocked yes)
			(layer "Cmts.User")
			(hide yes)
			(effects
				(font
					(size 0.7874 0.5842)
					(thickness 0.1524)
				)
			)
		)
		(property "Device Type" "RESISTOR-G155-133R0-01,33OHM,1%"
			(at 0.008382 1.210564 270)
			(unlocked yes)
			(layer "F.Fab")
			(hide yes)
			(effects
				(font
					(size 0.7874 0.5842)
					(thickness 0.1524)
				)
			)
		)
		(duplicate_pad_numbers_are_jumpers no)
		(fp_line
			(start -1.143 0.5588)
			(end 1.143 0.5588)
			(stroke
				(width 0.1)
				(type default)
			)
			(layer "F.SilkS")
		)
		(fp_line
			(start 1.143 0.5588)
			(end 1.143 -0.5588)
			(stroke
				(width 0.1)
				(type default)
			)
			(layer "F.SilkS")
		)
		(fp_line
			(start -1.143 -0.5588)
			(end -1.143 0.5588)
			(stroke
				(width 0.1)
				(type default)
			)
			(layer "F.SilkS")
		)
		(fp_line
			(start 1.143 -0.5588)
			(end -1.143 -0.5588)
			(stroke
				(width 0.1)
				(type default)
			)
			(layer "F.SilkS")
		)
		(fp_rect
			(start 1.143 0.5588)
			(end -1.143 -0.5588)
			(stroke
				(width 0)
				(type default)
			)
			(fill no)
			(layer "F.CrtYd")
		)
		(fp_line
			(start -0.508 0.3048)
			(end 0.508 0.3048)
			(stroke
				(width 0.1)
				(type default)
			)
			(layer "F.Fab")
		)
		(fp_line
			(start 0.508 0.3048)
			(end 0.508 -0.3048)
			(stroke
				(width 0.1)
				(type default)
			)
			(layer "F.Fab")
		)
		(fp_line
			(start -0.508 -0.3048)
			(end -0.508 0.3048)
			(stroke
				(width 0.1)
				(type default)
			)
			(layer "F.Fab")
		)
		(fp_line
			(start 0.508 -0.3048)
			(end -0.508 -0.3048)
			(stroke
				(width 0.1)
				(type default)
			)
			(layer "F.Fab")
		)
		(pad "1" smd rect
			(at -0.5334 0 270)
			(size 0.7112 0.6096)
			(layers "F.Cu" "F.Mask" "F.Paste")
			(net "FPGA_OUT_I2C_BUFFER_EN")
		)
		(pad "2" smd rect
			(at 0.5334 0 270)
			(size 0.7112 0.6096)
			(layers "F.Cu" "F.Mask" "F.Paste")
			(net "UNNAMED_3_G2201019801_I100_EN")
		)
		(zone
			(layer "F.Cu")
			(hatch none 0.5)
			(connect_pads
				(clearance 0)
			)
			(min_thickness 0.25)
			(keepout
				(tracks allowed)
				(vias not_allowed)
				(pads allowed)
				(copperpour not_allowed)
				(footprints allowed)
			)
			(placement
				(enabled no)
				(sheetname "")
			)
			(fill
				(thermal_gap 0.5)
				(thermal_bridge_width 0.5)
				(island_removal_mode 0)
			)
			(polygon
				(pts
					(xy 50.43678 -15.4432) (xy 51.04638 -15.4432) (xy 51.04638 -15.5956) (xy 50.43678 -15.5956)
				)
			)
		)
	)
	(footprint ""
		(layer "F.Cu")
		(at 101.4476 -83.5914)
		(property "Reference" "R461"
			(at -2.5146 -0.69723 0)
			(unlocked yes)
			(layer "F.SilkS")
			(effects
				(font
					(size 0.7874 0.5842)
					(thickness 0.1524)
				)
			)
		)
		(property "Value" "VAL*"
			(at 0.02032 2.13233 0)
			(unlocked yes)
			(layer "F.Fab")
			(hide yes)
			(effects
				(font
					(size 0.7874 0.5842)
					(thickness 0.1524)
				)
			)
		)
		(property "Tolerance" "TOL*"
			(at 0.044704 3.05435 0)
			(unlocked yes)
			(layer "Cmts.User")
			(hide yes)
			(effects
				(font
					(size 0.7874 0.5842)
					(thickness 0.1524)
				)
			)
		)
		(property "User Part Number" "PARTNUM*"
			(at 0.02032 4.024884 0)
			(unlocked yes)
			(layer "Cmts.User")
			(hide yes)
			(effects
				(font
					(size 0.7874 0.5842)
					(thickness 0.1524)
				)
			)
		)
		(property "Device Type" "RESISTOR-G155-133R0-01,33OHM,1%"
			(at 0.008382 1.210564 0)
			(unlocked yes)
			(layer "F.Fab")
			(hide yes)
			(effects
				(font
					(size 0.7874 0.5842)
					(thickness 0.1524)
				)
			)
		)
		(duplicate_pad_numbers_are_jumpers no)
		(fp_line
			(start -1.143 -0.5588)
			(end -1.143 0.5588)
			(stroke
				(width 0.1)
				(type default)
			)
			(layer "F.SilkS")
		)
		(fp_line
			(start -1.143 0.5588)
			(end 1.143 0.5588)
			(stroke
				(width 0.1)
				(type default)
			)
			(layer "F.SilkS")
		)
		(fp_line
			(start 1.143 -0.5588)
			(end -1.143 -0.5588)
			(stroke
				(width 0.1)
				(type default)
			)
			(layer "F.SilkS")
		)
		(fp_line
			(start 1.143 0.5588)
			(end 1.143 -0.5588)
			(stroke
				(width 0.1)
				(type default)
			)
			(layer "F.SilkS")
		)
		(fp_poly
			(pts
				(xy -1.143 0.5588) (xy 1.143 0.5588) (xy 1.143 -0.5588) (xy -1.143 -0.5588)
			)
			(stroke
				(width 0)
				(type default)
			)
			(fill no)
			(layer "F.CrtYd")
		)
		(fp_line
			(start -0.508 -0.3048)
			(end -0.508 0.3048)
			(stroke
				(width 0.1)
				(type default)
			)
			(layer "F.Fab")
		)
		(fp_line
			(start -0.508 0.3048)
			(end 0.508 0.3048)
			(stroke
				(width 0.1)
				(type default)
			)
			(layer "F.Fab")
		)
		(fp_line
			(start 0.508 -0.3048)
			(end -0.508 -0.3048)
			(stroke
				(width 0.1)
				(type default)
			)
			(layer "F.Fab")
		)
		(fp_line
			(start 0.508 0.3048)
			(end 0.508 -0.3048)
			(stroke
				(width 0.1)
				(type default)
			)
			(layer "F.Fab")
		)
		(pad "1" smd rect
			(at -0.5334 0)
			(size 0.7112 0.6096)
			(layers "F.Cu" "F.Mask" "F.Paste")
			(net "FPGA_OUT_MUX2_SEL")
		)
		(pad "2" smd rect
			(at 0.5334 0)
			(size 0.7112 0.6096)
			(layers "F.Cu" "F.Mask" "F.Paste")
			(net "MUX2_SEL")
		)
		(zone
			(layer "F.Cu")
			(hatch none 0.5)
			(connect_pads
				(clearance 0)
			)
			(min_thickness 0.25)
			(keepout
				(tracks allowed)
				(vias not_allowed)
				(pads allowed)
				(copperpour not_allowed)
				(footprints allowed)
			)
			(placement
				(enabled no)
				(sheetname "")
			)
			(fill
				(thermal_gap 0.5)
				(thermal_bridge_width 0.5)
				(island_removal_mode 0)
			)
			(polygon
				(pts
					(xy 101.3714 -83.2866) (xy 101.5238 -83.2866) (xy 101.5238 -83.8962) (xy 101.3714 -83.8962)
				)
			)
		)
		(zone
			(layer "F.Cu")
			(hatch none 0.5)
			(connect_pads
				(clearance 0)
			)
			(min_thickness 0.25)
			(keepout
				(tracks not_allowed)
				(vias allowed)
				(pads allowed)
				(copperpour not_allowed)
				(footprints allowed)
			)
			(placement
				(enabled no)
				(sheetname "")
			)
			(fill
				(thermal_gap 0.5)
				(thermal_bridge_width 0.5)
				(island_removal_mode 0)
			)
			(polygon
				(pts
					(xy 101.3714 -83.2866) (xy 101.5238 -83.2866) (xy 101.5238 -83.8962) (xy 101.3714 -83.8962)
				)
			)
		)
	)
	(footprint ""
		(layer "F.Cu")
		(at 135.3312 -66.8528 90)
		(property "Reference" "R190"
			(at -4.8768 0.34417 90)
			(unlocked yes)
			(layer "F.SilkS")
			(effects
				(font
					(size 0.7874 0.5842)
					(thickness 0.1524)
				)
			)
		)
		(property "Value" "VAL*"
			(at 0.02032 2.13233 90)
			(unlocked yes)
			(layer "F.Fab")
			(hide yes)
			(effects
				(font
					(size 0.7874 0.5842)
					(thickness 0.1524)
				)
			)
		)
		(property "Tolerance" "TOL*"
			(at 0.044704 3.05435 90)
			(unlocked yes)
			(layer "Cmts.User")
			(hide yes)
			(effects
				(font
					(size 0.7874 0.5842)
					(thickness 0.1524)
				)
			)
		)
		(property "User Part Number" "PARTNUM*"
			(at 0.02032 4.024884 90)
			(unlocked yes)
			(layer "Cmts.User")
			(hide yes)
			(effects
				(font
					(size 0.7874 0.5842)
					(thickness 0.1524)
				)
			)
		)
		(property "Device Type" "RESISTOR-G155-03241-01,3.24KOHA"
			(at 0.008382 1.210564 90)
			(unlocked yes)
			(layer "F.Fab")
			(hide yes)
			(effects
				(font
					(size 0.7874 0.5842)
					(thickness 0.1524)
				)
			)
		)
		(duplicate_pad_numbers_are_jumpers no)
		(fp_line
			(start 1.143 -0.5588)
			(end -1.143 -0.5588)
			(stroke
				(width 0.1)
				(type default)
			)
			(layer "F.SilkS")
		)
		(fp_line
			(start -1.143 -0.5588)
			(end -1.143 0.5588)
			(stroke
				(width 0.1)
				(type default)
			)
			(layer "F.SilkS")
		)
		(fp_line
			(start 1.143 0.5588)
			(end 1.143 -0.5588)
			(stroke
				(width 0.1)
				(type default)
			)
			(layer "F.SilkS")
		)
		(fp_line
			(start -1.143 0.5588)
			(end 1.143 0.5588)
			(stroke
				(width 0.1)
				(type default)
			)
			(layer "F.SilkS")
		)
		(fp_rect
			(start 1.143 0.5588)
			(end -1.143 -0.5588)
			(stroke
				(width 0)
				(type default)
			)
			(fill no)
			(layer "F.CrtYd")
		)
		(fp_line
			(start 0.508 -0.3048)
			(end -0.508 -0.3048)
			(stroke
				(width 0.1)
				(type default)
			)
			(layer "F.Fab")
		)
		(fp_line
			(start -0.508 -0.3048)
			(end -0.508 0.3048)
			(stroke
				(width 0.1)
				(type default)
			)
			(layer "F.Fab")
		)
		(fp_line
			(start 0.508 0.3048)
			(end 0.508 -0.3048)
			(stroke
				(width 0.1)
				(type default)
			)
			(layer "F.Fab")
		)
		(fp_line
			(start -0.508 0.3048)
			(end 0.508 0.3048)
			(stroke
				(width 0.1)
				(type default)
			)
			(layer "F.Fab")
		)
		(pad "1" smd rect
			(at -0.5334 0 90)
			(size 0.7112 0.6096)
			(layers "F.Cu" "F.Mask" "F.Paste")
			(net "SG")
		)
		(pad "2" smd rect
			(at 0.5334 0 90)
			(size 0.7112 0.6096)
			(layers "F.Cu" "F.Mask" "F.Paste")
			(net "XP1R8V_FB")
		)
		(zone
			(layer "F.Cu")
			(hatch none 0.5)
			(connect_pads
				(clearance 0)
			)
			(min_thickness 0.25)
			(keepout
				(tracks allowed)
				(vias not_allowed)
				(pads allowed)
				(copperpour not_allowed)
				(footprints allowed)
			)
			(placement
				(enabled no)
				(sheetname "")
			)
			(fill
				(thermal_gap 0.5)
				(thermal_bridge_width 0.5)
				(island_removal_mode 0)
			)
			(polygon
				(pts
					(xy 135.636 -66.929) (xy 135.0264 -66.929) (xy 135.0264 -66.7766) (xy 135.636 -66.7766)
				)
			)
		)
	)
	(footprint ""
		(layer "F.Cu")
		(at 20.32 -31.75 180)
		(property "Reference" "R274"
			(at -2.794 -0.67437 0)
			(unlocked yes)
			(layer "F.SilkS")
			(effects
				(font
					(size 0.7874 0.5842)
					(thickness 0.1524)
				)
			)
		)
		(property "Value" "VAL*"
			(at 0.02032 2.13233 180)
			(unlocked yes)
			(layer "F.Fab")
			(hide yes)
			(effects
				(font
					(size 0.7874 0.5842)
					(thickness 0.1524)
				)
			)
		)
		(property "Device Type" "RESISTOR-G155-11000-01,100OHM,A"
			(at 0.008382 1.210564 180)
			(unlocked yes)
			(layer "F.Fab")
			(hide yes)
			(effects
				(font
					(size 0.7874 0.5842)
					(thickness 0.1524)
				)
			)
		)
		(property "User Part Number" "PARTNUM*"
			(at 0.02032 4.024884 180)
			(unlocked yes)
			(layer "Cmts.User")
			(hide yes)
			(effects
				(font
					(size 0.7874 0.5842)
					(thickness 0.1524)
				)
			)
		)
		(property "Tolerance" "TOL*"
			(at 0.044704 3.05435 180)
			(unlocked yes)
			(layer "Cmts.User")
			(hide yes)
			(effects
				(font
					(size 0.7874 0.5842)
					(thickness 0.1524)
				)
			)
		)
		(duplicate_pad_numbers_are_jumpers no)
		(fp_line
			(start 1.143 0.5588)
			(end 1.143 -0.5588)
			(stroke
				(width 0.1)
				(type default)
			)
			(layer "F.SilkS")
		)
		(fp_line
			(start 1.143 -0.5588)
			(end -1.143 -0.5588)
			(stroke
				(width 0.1)
				(type default)
			)
			(layer "F.SilkS")
		)
		(fp_line
			(start -1.143 0.5588)
			(end 1.143 0.5588)
			(stroke
				(width 0.1)
				(type default)
			)
			(layer "F.SilkS")
		)
		(fp_line
			(start -1.143 -0.5588)
			(end -1.143 0.5588)
			(stroke
				(width 0.1)
				(type default)
			)
			(layer "F.SilkS")
		)
		(fp_poly
			(pts
				(xy -1.143 0.5588) (xy 1.143 0.5588) (xy 1.143 -0.5588) (xy -1.143 -0.5588)
			)
			(stroke
				(width 0)
				(type default)
			)
			(fill no)
			(layer "F.CrtYd")
		)
		(fp_line
			(start 0.508 0.3048)
			(end 0.508 -0.3048)
			(stroke
				(width 0.1)
				(type default)
			)
			(layer "F.Fab")
		)
		(fp_line
			(start 0.508 -0.3048)
			(end -0.508 -0.3048)
			(stroke
				(width 0.1)
				(type default)
			)
			(layer "F.Fab")
		)
		(fp_line
			(start -0.508 0.3048)
			(end 0.508 0.3048)
			(stroke
				(width 0.1)
				(type default)
			)
			(layer "F.Fab")
		)
		(fp_line
			(start -0.508 -0.3048)
			(end -0.508 0.3048)
			(stroke
				(width 0.1)
				(type default)
			)
			(layer "F.Fab")
		)
		(pad "1" smd rect
			(at -0.5334 0 180)
			(size 0.7112 0.6096)
			(layers "F.Cu" "F.Mask" "F.Paste")
			(net "FPGA_OUT_SMA2_LED_GREEN_N")
		)
		(pad "2" smd rect
			(at 0.5334 0 180)
			(size 0.7112 0.6096)
			(layers "F.Cu" "F.Mask" "F.Paste")
			(net "UNNAMED_14_LED4PV14_I266_4")
		)
		(zone
			(layer "F.Cu")
			(hatch none 0.5)
			(connect_pads
				(clearance 0)
			)
			(min_thickness 0.25)
			(keepout
				(tracks not_allowed)
				(vias allowed)
				(pads allowed)
				(copperpour not_allowed)
				(footprints allowed)
			)
			(placement
				(enabled no)
				(sheetname "")
			)
			(fill
				(thermal_gap 0.5)
				(thermal_bridge_width 0.5)
				(island_removal_mode 0)
			)
			(polygon
				(pts
					(xy 20.3962 -32.0548) (xy 20.2438 -32.0548) (xy 20.2438 -31.4452) (xy 20.3962 -31.4452)
				)
			)
		)
		(zone
			(layer "F.Cu")
			(hatch none 0.5)
			(connect_pads
				(clearance 0)
			)
			(min_thickness 0.25)
			(keepout
				(tracks allowed)
				(vias not_allowed)
				(pads allowed)
				(copperpour not_allowed)
				(footprints allowed)
			)
			(placement
				(enabled no)
				(sheetname "")
			)
			(fill
				(thermal_gap 0.5)
				(thermal_bridge_width 0.5)
				(island_removal_mode 0)
			)
			(polygon
				(pts
					(xy 20.3962 -32.0548) (xy 20.2438 -32.0548) (xy 20.2438 -31.4452) (xy 20.3962 -31.4452)
				)
			)
		)
	)
	(footprint ""
		(layer "F.Cu")
		(at 145.8214 -93.1418 180)
		(property "Reference" "R8"
			(at 0.2794 -8.72617 0)
			(unlocked yes)
			(layer "F.SilkS")
			(effects
				(font
					(size 0.7874 0.5842)
					(thickness 0.1524)
				)
			)
		)
		(property "Value" "VAL*"
			(at 0.02032 2.13233 180)
			(unlocked yes)
			(layer "F.Fab")
			(hide yes)
			(effects
				(font
					(size 0.7874 0.5842)
					(thickness 0.1524)
				)
			)
		)
		(property "Device Type" "RESISTOR-G155-100R0-J0,0OHM,-"
			(at 0.008382 1.210564 180)
			(unlocked yes)
			(layer "F.Fab")
			(hide yes)
			(effects
				(font
					(size 0.7874 0.5842)
					(thickness 0.1524)
				)
			)
		)
		(property "User Part Number" "PARTNUM*"
			(at 0.02032 4.024884 180)
			(unlocked yes)
			(layer "Cmts.User")
			(hide yes)
			(effects
				(font
					(size 0.7874 0.5842)
					(thickness 0.1524)
				)
			)
		)
		(property "Tolerance" "TOL*"
			(at 0.044704 3.05435 180)
			(unlocked yes)
			(layer "Cmts.User")
			(hide yes)
			(effects
				(font
					(size 0.7874 0.5842)
					(thickness 0.1524)
				)
			)
		)
		(duplicate_pad_numbers_are_jumpers no)
		(fp_line
			(start 1.143 0.5588)
			(end 1.143 -0.5588)
			(stroke
				(width 0.1)
				(type default)
			)
			(layer "F.SilkS")
		)
		(fp_line
			(start 1.143 -0.5588)
			(end -1.143 -0.5588)
			(stroke
				(width 0.1)
				(type default)
			)
			(layer "F.SilkS")
		)
		(fp_line
			(start -1.143 0.5588)
			(end 1.143 0.5588)
			(stroke
				(width 0.1)
				(type default)
			)
			(layer "F.SilkS")
		)
		(fp_line
			(start -1.143 -0.5588)
			(end -1.143 0.5588)
			(stroke
				(width 0.1)
				(type default)
			)
			(layer "F.SilkS")
		)
		(fp_rect
			(start 1.143 -0.5588)
			(end -1.143 0.5588)
			(stroke
				(width 0)
				(type default)
			)
			(fill no)
			(layer "F.CrtYd")
		)
		(fp_line
			(start 0.508 0.3048)
			(end 0.508 -0.3048)
			(stroke
				(width 0.1)
				(type default)
			)
			(layer "F.Fab")
		)
		(fp_line
			(start 0.508 -0.3048)
			(end -0.508 -0.3048)
			(stroke
				(width 0.1)
				(type default)
			)
			(layer "F.Fab")
		)
		(fp_line
			(start -0.508 0.3048)
			(end 0.508 0.3048)
			(stroke
				(width 0.1)
				(type default)
			)
			(layer "F.Fab")
		)
		(fp_line
			(start -0.508 -0.3048)
			(end -0.508 0.3048)
			(stroke
				(width 0.1)
				(type default)
			)
			(layer "F.Fab")
		)
		(pad "1" smd rect
			(at -0.5334 0 180)
			(size 0.7112 0.6096)
			(layers "F.Cu" "F.Mask" "F.Paste")
			(net "SG")
		)
		(pad "2" smd rect
			(at 0.5334 0 180)
			(size 0.7112 0.6096)
			(layers "F.Cu" "F.Mask" "F.Paste")
			(net "UNNAMED_15_MP5022CGQVZQFN22_I21")
		)
		(zone
			(layer "F.Cu")
			(hatch none 0.5)
			(connect_pads
				(clearance 0)
			)
			(min_thickness 0.25)
			(keepout
				(tracks allowed)
				(vias not_allowed)
				(pads allowed)
				(copperpour not_allowed)
				(footprints allowed)
			)
			(placement
				(enabled no)
				(sheetname "")
			)
			(fill
				(thermal_gap 0.5)
				(thermal_bridge_width 0.5)
				(island_removal_mode 0)
			)
			(polygon
				(pts
					(xy 145.7452 -92.837) (xy 145.8976 -92.837) (xy 145.8976 -93.4466) (xy 145.7452 -93.4466)
				)
			)
		)
	)
	(footprint ""
		(layer "F.Cu")
		(at 24.8412 -99.5172)
		(property "Reference" "TP42"
			(at 0.72517 -1.2446 90)
			(unlocked yes)
			(layer "F.SilkS")
			(effects
				(font
					(size 0.7874 0.5842)
					(thickness 0.1524)
				)
				(justify left)
			)
		)
		(property "Value" ""
			(at 0 0 0)
			(layer "F.Fab")
			(effects
				(font
					(size 1.27 1.27)
				)
			)
		)
		(property "Device Type" "TP_PIONT-TP010CT020B030_PTH-TPA"
			(at -1.341882 0.996696 0)
			(unlocked yes)
			(layer "F.Fab")
			(hide yes)
			(effects
				(font
					(size 0.7874 0.5842)
					(thickness 0.000001)
				)
				(justify left)
			)
		)
		(duplicate_pad_numbers_are_jumpers no)
		(fp_poly
			(pts
				(arc
					(start 0.889 0)
					(mid -0.889 0)
					(end 0.889 0)
				)
			)
			(stroke
				(width 0)
				(type default)
			)
			(fill no)
			(layer "B.CrtYd")
		)
		(fp_poly
			(pts
				(arc
					(start 0.889 0)
					(mid -0.889 0)
					(end 0.889 0)
				)
			)
			(stroke
				(width 0)
				(type default)
			)
			(fill no)
			(layer "F.CrtYd")
		)
		(pad "1" thru_hole circle
			(at 0 0)
			(size 0.508 0.508)
			(drill 0.254)
			(layers "*.Cu" "*.Mask")
			(remove_unused_layers no)
			(net "XP12R0V_IN")
			(clearance 0.1016)
			(padstack
				(mode front_inner_back)
				(layer "Inner"
					(shape circle)
					(size 0.508 0.508)
					(clearance 0.1016)
				)
				(layer "B.Cu"
					(shape circle)
					(size 0.762 0.762)
					(clearance -0.0254)
				)
			)
		)
	)
	(footprint ""
		(layer "F.Cu")
		(at 92.0242 -97.9678 90)
		(property "Reference" "R17"
			(at -0.0508 1.36017 90)
			(unlocked yes)
			(layer "F.SilkS")
			(effects
				(font
					(size 0.7874 0.5842)
					(thickness 0.1524)
				)
			)
		)
		(property "Value" "VAL*"
			(at 0.02032 2.13233 90)
			(unlocked yes)
			(layer "F.Fab")
			(hide yes)
			(effects
				(font
					(size 0.7874 0.5842)
					(thickness 0.1524)
				)
			)
		)
		(property "Tolerance" "TOL*"
			(at 0.044704 3.05435 90)
			(unlocked yes)
			(layer "Cmts.User")
			(hide yes)
			(effects
				(font
					(size 0.7874 0.5842)
					(thickness 0.1524)
				)
			)
		)
		(property "User Part Number" "PARTNUM*"
			(at 0.02032 4.024884 90)
			(unlocked yes)
			(layer "Cmts.User")
			(hide yes)
			(effects
				(font
					(size 0.7874 0.5842)
					(thickness 0.1524)
				)
			)
		)
		(property "Device Type" "RESISTOR-G155-120R0-01,20OHM,1%"
			(at 0.008382 1.210564 90)
			(unlocked yes)
			(layer "F.Fab")
			(hide yes)
			(effects
				(font
					(size 0.7874 0.5842)
					(thickness 0.1524)
				)
			)
		)
		(duplicate_pad_numbers_are_jumpers no)
		(fp_line
			(start 1.143 -0.5588)
			(end -1.143 -0.5588)
			(stroke
				(width 0.1)
				(type default)
			)
			(layer "F.SilkS")
		)
		(fp_line
			(start -1.143 -0.5588)
			(end -1.143 0.5588)
			(stroke
				(width 0.1)
				(type default)
			)
			(layer "F.SilkS")
		)
		(fp_line
			(start 1.143 0.5588)
			(end 1.143 -0.5588)
			(stroke
				(width 0.1)
				(type default)
			)
			(layer "F.SilkS")
		)
		(fp_line
			(start -1.143 0.5588)
			(end 1.143 0.5588)
			(stroke
				(width 0.1)
				(type default)
			)
			(layer "F.SilkS")
		)
		(fp_rect
			(start -1.143 -0.5588)
			(end 1.143 0.5588)
			(stroke
				(width 0)
				(type default)
			)
			(fill no)
			(layer "F.CrtYd")
		)
		(fp_line
			(start 0.508 -0.3048)
			(end -0.508 -0.3048)
			(stroke
				(width 0.1)
				(type default)
			)
			(layer "F.Fab")
		)
		(fp_line
			(start -0.508 -0.3048)
			(end -0.508 0.3048)
			(stroke
				(width 0.1)
				(type default)
			)
			(layer "F.Fab")
		)
		(fp_line
			(start 0.508 0.3048)
			(end 0.508 -0.3048)
			(stroke
				(width 0.1)
				(type default)
			)
			(layer "F.Fab")
		)
		(fp_line
			(start -0.508 0.3048)
			(end 0.508 0.3048)
			(stroke
				(width 0.1)
				(type default)
			)
			(layer "F.Fab")
		)
		(pad "1" smd rect
			(at -0.5334 0 90)
			(size 0.7112 0.6096)
			(layers "F.Cu" "F.Mask" "F.Paste")
			(net "XP3R3V")
		)
		(pad "2" smd rect
			(at 0.5334 0 90)
			(size 0.7112 0.6096)
			(layers "F.Cu" "F.Mask" "F.Paste")
			(net "UNNAMED_517_CAPACITOR_I30_1")
		)
		(zone
			(layer "F.Cu")
			(hatch none 0.5)
			(connect_pads
				(clearance 0)
			)
			(min_thickness 0.25)
			(keepout
				(tracks allowed)
				(vias not_allowed)
				(pads allowed)
				(copperpour not_allowed)
				(footprints allowed)
			)
			(placement
				(enabled no)
				(sheetname "")
			)
			(fill
				(thermal_gap 0.5)
				(thermal_bridge_width 0.5)
				(island_removal_mode 0)
			)
			(polygon
				(pts
					(xy 91.7194 -97.8916) (xy 92.329 -97.8916) (xy 92.329 -98.044) (xy 91.7194 -98.044)
				)
			)
		)
	)
	(footprint ""
		(layer "F.Cu")
		(at 82.7786 -52.959 -90)
		(property "Reference" "R277"
			(at 13.589 0.96393 90)
			(unlocked yes)
			(layer "F.SilkS")
			(effects
				(font
					(size 0.7874 0.5842)
					(thickness 0.1524)
				)
			)
		)
		(property "Value" "VAL*"
			(at 0.02032 2.13233 270)
			(unlocked yes)
			(layer "F.Fab")
			(hide yes)
			(effects
				(font
					(size 0.7874 0.5842)
					(thickness 0.1524)
				)
			)
		)
		(property "Tolerance" "TOL*"
			(at 0.044704 3.05435 270)
			(unlocked yes)
			(layer "Cmts.User")
			(hide yes)
			(effects
				(font
					(size 0.7874 0.5842)
					(thickness 0.1524)
				)
			)
		)
		(property "User Part Number" "PARTNUM*"
			(at 0.02032 4.024884 270)
			(unlocked yes)
			(layer "Cmts.User")
			(hide yes)
			(effects
				(font
					(size 0.7874 0.5842)
					(thickness 0.1524)
				)
			)
		)
		(property "Device Type" "RESISTOR-G155-11000-01,100OHM,A"
			(at 0.008382 1.210564 270)
			(unlocked yes)
			(layer "F.Fab")
			(hide yes)
			(effects
				(font
					(size 0.7874 0.5842)
					(thickness 0.1524)
				)
			)
		)
		(duplicate_pad_numbers_are_jumpers no)
		(fp_line
			(start -1.143 0.5588)
			(end 1.143 0.5588)
			(stroke
				(width 0.1)
				(type default)
			)
			(layer "F.SilkS")
		)
		(fp_line
			(start 1.143 0.5588)
			(end 1.143 -0.5588)
			(stroke
				(width 0.1)
				(type default)
			)
			(layer "F.SilkS")
		)
		(fp_line
			(start -1.143 -0.5588)
			(end -1.143 0.5588)
			(stroke
				(width 0.1)
				(type default)
			)
			(layer "F.SilkS")
		)
		(fp_line
			(start 1.143 -0.5588)
			(end -1.143 -0.5588)
			(stroke
				(width 0.1)
				(type default)
			)
			(layer "F.SilkS")
		)
		(fp_rect
			(start 1.143 0.5588)
			(end -1.143 -0.5588)
			(stroke
				(width 0)
				(type default)
			)
			(fill no)
			(layer "F.CrtYd")
		)
		(fp_line
			(start -0.508 0.3048)
			(end 0.508 0.3048)
			(stroke
				(width 0.1)
				(type default)
			)
			(layer "F.Fab")
		)
		(fp_line
			(start 0.508 0.3048)
			(end 0.508 -0.3048)
			(stroke
				(width 0.1)
				(type default)
			)
			(layer "F.Fab")
		)
		(fp_line
			(start -0.508 -0.3048)
			(end -0.508 0.3048)
			(stroke
				(width 0.1)
				(type default)
			)
			(layer "F.Fab")
		)
		(fp_line
			(start 0.508 -0.3048)
			(end -0.508 -0.3048)
			(stroke
				(width 0.1)
				(type default)
			)
			(layer "F.Fab")
		)
		(pad "1" smd rect
			(at -0.5334 0 270)
			(size 0.7112 0.6096)
			(layers "F.Cu" "F.Mask" "F.Paste")
			(net "FPGA_OUT_MAC_PPS_IN1P")
		)
		(pad "2" smd rect
			(at 0.5334 0 270)
			(size 0.7112 0.6096)
			(layers "F.Cu" "F.Mask" "F.Paste")
			(net "FPGA_OUT_MAC_PPS_IN1N")
		)
		(zone
			(layer "F.Cu")
			(hatch none 0.5)
			(connect_pads
				(clearance 0)
			)
			(min_thickness 0.25)
			(keepout
				(tracks allowed)
				(vias not_allowed)
				(pads allowed)
				(copperpour not_allowed)
				(footprints allowed)
			)
			(placement
				(enabled no)
				(sheetname "")
			)
			(fill
				(thermal_gap 0.5)
				(thermal_bridge_width 0.5)
				(island_removal_mode 0)
			)
			(polygon
				(pts
					(xy 82.4738 -52.8828) (xy 83.0834 -52.8828) (xy 83.0834 -53.0352) (xy 82.4738 -53.0352)
				)
			)
		)
	)
	(footprint ""
		(layer "F.Cu")
		(at 103.632 -87.63 90)
		(property "Reference" "R465"
			(at -1.397 4.61137 90)
			(unlocked yes)
			(layer "F.SilkS")
			(effects
				(font
					(size 0.7874 0.5842)
					(thickness 0.1524)
				)
			)
		)
		(property "Value" "VAL*"
			(at 0.02032 2.13233 90)
			(unlocked yes)
			(layer "F.Fab")
			(hide yes)
			(effects
				(font
					(size 0.7874 0.5842)
					(thickness 0.1524)
				)
			)
		)
		(property "Tolerance" "TOL*"
			(at 0.044704 3.05435 90)
			(unlocked yes)
			(layer "Cmts.User")
			(hide yes)
			(effects
				(font
					(size 0.7874 0.5842)
					(thickness 0.1524)
				)
			)
		)
		(property "User Part Number" "PARTNUM*"
			(at 0.02032 4.024884 90)
			(unlocked yes)
			(layer "Cmts.User")
			(hide yes)
			(effects
				(font
					(size 0.7874 0.5842)
					(thickness 0.1524)
				)
			)
		)
		(property "Device Type" "RESISTOR-G155-100R0-J0,0OHM,-"
			(at 0.008382 1.210564 90)
			(unlocked yes)
			(layer "F.Fab")
			(hide yes)
			(effects
				(font
					(size 0.7874 0.5842)
					(thickness 0.1524)
				)
			)
		)
		(duplicate_pad_numbers_are_jumpers no)
		(fp_line
			(start 1.143 -0.5588)
			(end -1.143 -0.5588)
			(stroke
				(width 0.1)
				(type default)
			)
			(layer "F.SilkS")
		)
		(fp_line
			(start -1.143 -0.5588)
			(end -1.143 0.5588)
			(stroke
				(width 0.1)
				(type default)
			)
			(layer "F.SilkS")
		)
		(fp_line
			(start 1.143 0.5588)
			(end 1.143 -0.5588)
			(stroke
				(width 0.1)
				(type default)
			)
			(layer "F.SilkS")
		)
		(fp_line
			(start -1.143 0.5588)
			(end 1.143 0.5588)
			(stroke
				(width 0.1)
				(type default)
			)
			(layer "F.SilkS")
		)
		(fp_poly
			(pts
				(xy -1.143 0.5588) (xy 1.143 0.5588) (xy 1.143 -0.5588) (xy -1.143 -0.5588)
			)
			(stroke
				(width 0)
				(type default)
			)
			(fill no)
			(layer "F.CrtYd")
		)
		(fp_line
			(start 0.508 -0.3048)
			(end -0.508 -0.3048)
			(stroke
				(width 0.1)
				(type default)
			)
			(layer "F.Fab")
		)
		(fp_line
			(start -0.508 -0.3048)
			(end -0.508 0.3048)
			(stroke
				(width 0.1)
				(type default)
			)
			(layer "F.Fab")
		)
		(fp_line
			(start 0.508 0.3048)
			(end 0.508 -0.3048)
			(stroke
				(width 0.1)
				(type default)
			)
			(layer "F.Fab")
		)
		(fp_line
			(start -0.508 0.3048)
			(end 0.508 0.3048)
			(stroke
				(width 0.1)
				(type default)
			)
			(layer "F.Fab")
		)
		(pad "1" smd rect
			(at -0.5334 0 90)
			(size 0.7112 0.6096)
			(layers "F.Cu" "F.Mask" "F.Paste")
			(net "FPGA_FLASH_DQ3")
		)
		(pad "2" smd rect
			(at 0.5334 0 90)
			(size 0.7112 0.6096)
			(layers "F.Cu" "F.Mask" "F.Paste")
			(net "FLASH_DQ3")
		)
		(zone
			(layer "F.Cu")
			(hatch none 0.5)
			(connect_pads
				(clearance 0)
			)
			(min_thickness 0.25)
			(keepout
				(tracks not_allowed)
				(vias allowed)
				(pads allowed)
				(copperpour not_allowed)
				(footprints allowed)
			)
			(placement
				(enabled no)
				(sheetname "")
			)
			(fill
				(thermal_gap 0.5)
				(thermal_bridge_width 0.5)
				(island_removal_mode 0)
			)
			(polygon
				(pts
					(xy 103.9368 -87.5538) (xy 103.9368 -87.7062) (xy 103.3272 -87.7062) (xy 103.3272 -87.5538)
				)
			)
		)
		(zone
			(layer "F.Cu")
			(hatch none 0.5)
			(connect_pads
				(clearance 0)
			)
			(min_thickness 0.25)
			(keepout
				(tracks allowed)
				(vias not_allowed)
				(pads allowed)
				(copperpour not_allowed)
				(footprints allowed)
			)
			(placement
				(enabled no)
				(sheetname "")
			)
			(fill
				(thermal_gap 0.5)
				(thermal_bridge_width 0.5)
				(island_removal_mode 0)
			)
			(polygon
				(pts
					(xy 103.9368 -87.5538) (xy 103.9368 -87.7062) (xy 103.3272 -87.7062) (xy 103.3272 -87.5538)
				)
			)
		)
	)
	(footprint ""
		(layer "F.Cu")
		(at 152.146 -53.1876 90)
		(property "Reference" "U27"
			(at -0.7366 2.45237 90)
			(unlocked yes)
			(layer "F.SilkS")
			(effects
				(font
					(size 0.7874 0.5842)
					(thickness 0.1524)
				)
			)
		)
		(property "Value" ""
			(at 0 0 90)
			(layer "F.Fab")
			(effects
				(font
					(size 1.27 1.27)
				)
			)
		)
		(property "Device Type" "SHT31A_DIS_B10KS_DFN8-A222-000A"
			(at 0 3.831336 90)
			(unlocked yes)
			(layer "F.Fab")
			(hide yes)
			(effects
				(font
					(size 0.7874 0.5842)
					(thickness 0.1524)
				)
			)
		)
		(property "User Part Number" "PARTNUM*"
			(at 0 5.025136 90)
			(unlocked yes)
			(layer "Cmts.User")
			(hide yes)
			(effects
				(font
					(size 0.7874 0.5842)
					(thickness 0.1524)
				)
			)
		)
		(duplicate_pad_numbers_are_jumpers no)
		(fp_line
			(start 2.040128 -1.553972)
			(end 2.040128 1.553972)
			(stroke
				(width 0.1)
				(type default)
			)
			(layer "F.SilkS")
		)
		(fp_line
			(start -2.040128 -1.553972)
			(end 2.040128 -1.553972)
			(stroke
				(width 0.1)
				(type default)
			)
			(layer "F.SilkS")
		)
		(fp_line
			(start 2.040128 1.553972)
			(end -2.040128 1.553972)
			(stroke
				(width 0.1)
				(type default)
			)
			(layer "F.SilkS")
		)
		(fp_line
			(start -2.040128 1.553972)
			(end -2.040128 -1.553972)
			(stroke
				(width 0.1)
				(type default)
			)
			(layer "F.SilkS")
		)
		(fp_poly
			(pts
				(arc
					(start -2.5146 -2.032)
					(mid -2.5146 -3.048)
					(end -2.5146 -2.032)
				)
			)
			(stroke
				(width 0)
				(type default)
			)
			(fill yes)
			(layer "F.SilkS")
		)
		(fp_poly
			(pts
				(xy 0.4953 0.1016) (xy 0.4953 0.9017) (xy -0.22098 0.9017)
				(arc
					(start -0.221742 0.900938)
					(mid -0.054914 0.820246)
					(end 0.0127 0.6477)
				)
				(arc
					(start 0.0127 0.6477)
					(mid -0.061695 0.468095)
					(end -0.2413 0.3937)
				)
				(arc
					(start -0.2413 0.3937)
					(mid -0.412633 0.460187)
					(end -0.494284 0.62484)
				)
				(xy -0.4953 0.62484) (xy -0.4953 0.1016)
			)
			(stroke
				(width 0)
				(type default)
			)
			(fill yes)
			(layer "F.Paste")
		)
		(fp_poly
			(pts
				(xy 0.4953 -0.63754) (xy 0.4953 -0.1016) (xy -0.4953 -0.1016) (xy -0.4953 -0.9017) (xy 0.22606 -0.9017)
				(arc
					(start 0.22606 -0.901192)
					(mid 0.056421 -0.821798)
					(end -0.0127 -0.6477)
				)
				(arc
					(start -0.0127 -0.6477)
					(mid 0.061695 -0.468095)
					(end 0.2413 -0.3937)
				)
				(arc
					(start 0.2413 -0.3937)
					(mid 0.417276 -0.464537)
					(end 0.495046 -0.63754)
				)
			)
			(stroke
				(width 0)
				(type default)
			)
			(fill yes)
			(layer "F.Paste")
		)
		(fp_rect
			(start -2.294128 1.807972)
			(end 2.294128 -1.807972)
			(stroke
				(width 0)
				(type default)
			)
			(fill no)
			(layer "F.CrtYd")
		)
		(fp_line
			(start 1.299972 -1.299972)
			(end -1.299972 -1.299972)
			(stroke
				(width 0.1)
				(type default)
			)
			(layer "F.Fab")
		)
		(fp_line
			(start -1.299972 -1.299972)
			(end -1.299972 1.299972)
			(stroke
				(width 0.1)
				(type default)
			)
			(layer "F.Fab")
		)
		(fp_line
			(start 1.299972 1.299972)
			(end 1.299972 -1.299972)
			(stroke
				(width 0.1)
				(type default)
			)
			(layer "F.Fab")
		)
		(fp_line
			(start -1.299972 1.299972)
			(end 1.299972 1.299972)
			(stroke
				(width 0.1)
				(type default)
			)
			(layer "F.Fab")
		)
		(fp_poly
			(pts
				(arc
					(start -2.3876 -1.143)
					(mid -2.3876 -2.159)
					(end -2.3876 -1.143)
				)
			)
			(stroke
				(width 0)
				(type default)
			)
			(fill yes)
			(layer "F.Fab")
		)
		(fp_text user "8"
			(at 2.4384 -1.86563 90)
			(unlocked yes)
			(layer "F.SilkS")
			(effects
				(font
					(size 0.7874 0.5842)
					(thickness 0.1524)
				)
			)
		)
		(fp_text user "4"
			(at -2.6416 1.43637 90)
			(unlocked yes)
			(layer "F.SilkS")
			(effects
				(font
					(size 0.7874 0.5842)
					(thickness 0.1524)
				)
			)
		)
		(fp_text user "5"
			(at 2.4384 1.56337 90)
			(unlocked yes)
			(layer "F.SilkS")
			(effects
				(font
					(size 0.7874 0.5842)
					(thickness 0.1524)
				)
			)
		)
		(fp_text user "8"
			(at 2.14503 -1.524 0)
			(unlocked yes)
			(layer "F.Fab")
			(effects
				(font
					(size 0.7874 0.5842)
					(thickness 0.1524)
				)
			)
		)
		(fp_text user "5"
			(at 1.89103 1.397 0)
			(unlocked yes)
			(layer "F.Fab")
			(effects
				(font
					(size 0.7874 0.5842)
					(thickness 0.1524)
				)
			)
		)
		(fp_text user "4"
			(at -2.17297 1.905 0)
			(unlocked yes)
			(layer "F.Fab")
			(effects
				(font
					(size 0.7874 0.5842)
					(thickness 0.1524)
				)
			)
		)
		(pad "1" smd rect
			(at -1.265428 -0.750062 90)
			(size 1.0414 0.3048)
			(layers "F.Cu" "F.Mask" "F.Paste")
			(net "R_SHT3X_I2C_SDA")
		)
		(pad "2" smd rect
			(at -1.265428 -0.249936 90)
			(size 1.0414 0.3048)
			(layers "F.Cu" "F.Mask" "F.Paste")
			(net "SHT3X_ADDR")
		)
		(pad "3" smd rect
			(at -1.265428 0.249936 90)
			(size 1.0414 0.3048)
			(layers "F.Cu" "F.Mask" "F.Paste")
			(net "R_SHT3X_ALERT_N")
		)
		(pad "4" smd rect
			(at -1.265428 0.750062 90)
			(size 1.0414 0.3048)
			(layers "F.Cu" "F.Mask" "F.Paste")
			(net "R_SHT3X_I2C_SCL")
		)
		(pad "5" smd rect
			(at 1.265428 0.750062 90)
			(size 1.0414 0.3048)
			(layers "F.Cu" "F.Mask" "F.Paste")
			(net "VDD3V3_SHT31A")
		)
		(pad "6" smd rect
			(at 1.265428 0.249936 90)
			(size 1.0414 0.3048)
			(layers "F.Cu" "F.Mask" "F.Paste")
			(net "R_SHT3X_RST_N")
		)
		(pad "7" smd rect
			(at 1.265428 -0.249936 90)
			(size 1.0414 0.3048)
			(layers "F.Cu" "F.Mask" "F.Paste")
			(net "SG")
		)
		(pad "8" smd rect
			(at 1.265428 -0.750062 90)
			(size 1.0414 0.3048)
			(layers "F.Cu" "F.Mask" "F.Paste")
			(net "SG")
		)
		(pad "9" smd rect
			(at 0 0 90)
			(size 0.9906 1.8034)
			(layers "F.Cu" "F.Mask" "F.Paste")
			(net "SG")
		)
	)
	(footprint ""
		(layer "F.Cu")
		(at 56.7944 -98.0694 -90)
		(property "Reference" "C13"
			(at -0.127 -3.59537 90)
			(unlocked yes)
			(layer "F.SilkS")
			(effects
				(font
					(size 0.7874 0.5842)
					(thickness 0.1524)
				)
			)
		)
		(property "Value" "VAL*"
			(at 0.0762 3.134106 270)
			(unlocked yes)
			(layer "F.Fab")
			(hide yes)
			(effects
				(font
					(size 0.7874 0.5842)
					(thickness 0.1524)
				)
			)
		)
		(property "Device Type" "CAPACITOR-G107-0F226-CM,22UF,2A"
			(at 0.0508 2.194306 270)
			(unlocked yes)
			(layer "F.Fab")
			(hide yes)
			(effects
				(font
					(size 0.7874 0.5842)
					(thickness 0.1524)
				)
			)
		)
		(property "User Part Number" "PARTNUM*"
			(at 0.1016 5.013706 270)
			(unlocked yes)
			(layer "Cmts.User")
			(hide yes)
			(effects
				(font
					(size 0.7874 0.5842)
					(thickness 0.1524)
				)
			)
		)
		(property "Tolerance" "TOL*"
			(at 0.0762 4.048506 270)
			(unlocked yes)
			(layer "Cmts.User")
			(hide yes)
			(effects
				(font
					(size 0.7874 0.5842)
					(thickness 0.1524)
				)
			)
		)
		(duplicate_pad_numbers_are_jumpers no)
		(fp_line
			(start -1.5748 0.9398)
			(end 1.5748 0.9398)
			(stroke
				(width 0.1)
				(type default)
			)
			(layer "F.SilkS")
		)
		(fp_line
			(start 1.5748 0.9398)
			(end 1.5748 -0.9398)
			(stroke
				(width 0.1)
				(type default)
			)
			(layer "F.SilkS")
		)
		(fp_line
			(start -1.5748 -0.9398)
			(end -1.5748 0.9398)
			(stroke
				(width 0.1)
				(type default)
			)
			(layer "F.SilkS")
		)
		(fp_line
			(start 1.5748 -0.9398)
			(end -1.5748 -0.9398)
			(stroke
				(width 0.1)
				(type default)
			)
			(layer "F.SilkS")
		)
		(fp_rect
			(start -1.5748 -0.9398)
			(end 1.5748 0.9398)
			(stroke
				(width 0)
				(type default)
			)
			(fill no)
			(layer "F.CrtYd")
		)
		(fp_line
			(start -1.016 0.635)
			(end 1.016 0.635)
			(stroke
				(width 0.1)
				(type default)
			)
			(layer "F.Fab")
		)
		(fp_line
			(start 1.016 0.635)
			(end 1.016 -0.635)
			(stroke
				(width 0.1)
				(type default)
			)
			(layer "F.Fab")
		)
		(fp_line
			(start -1.016 -0.635)
			(end -1.016 0.635)
			(stroke
				(width 0.1)
				(type default)
			)
			(layer "F.Fab")
		)
		(fp_line
			(start 1.016 -0.635)
			(end -1.016 -0.635)
			(stroke
				(width 0.1)
				(type default)
			)
			(layer "F.Fab")
		)
		(pad "1" smd rect
			(at -0.8382 0 270)
			(size 0.9652 1.3716)
			(layers "F.Cu" "F.Mask" "F.Paste")
			(net "XP5R0V")
		)
		(pad "2" smd rect
			(at 0.8382 0 270)
			(size 0.9652 1.3716)
			(layers "F.Cu" "F.Mask" "F.Paste")
			(net "SG")
		)
		(zone
			(layer "F.Cu")
			(hatch none 0.5)
			(connect_pads
				(clearance 0)
			)
			(min_thickness 0.25)
			(keepout
				(tracks allowed)
				(vias not_allowed)
				(pads allowed)
				(copperpour not_allowed)
				(footprints allowed)
			)
			(placement
				(enabled no)
				(sheetname "")
			)
			(fill
				(thermal_gap 0.5)
				(thermal_bridge_width 0.5)
				(island_removal_mode 0)
			)
			(polygon
				(pts
					(xy 57.4294 -98.298) (xy 56.1594 -98.298) (xy 56.1594 -97.8408) (xy 57.4294 -97.8408)
				)
			)
		)
	)
	(footprint ""
		(layer "F.Cu")
		(at 20.32 -30.48 180)
		(property "Reference" "R390"
			(at -2.794 -0.80137 0)
			(unlocked yes)
			(layer "F.SilkS")
			(effects
				(font
					(size 0.7874 0.5842)
					(thickness 0.1524)
				)
			)
		)
		(property "Value" "VAL*"
			(at 0.02032 2.13233 180)
			(unlocked yes)
			(layer "F.Fab")
			(hide yes)
			(effects
				(font
					(size 0.7874 0.5842)
					(thickness 0.1524)
				)
			)
		)
		(property "Tolerance" "TOL*"
			(at 0.044704 3.05435 180)
			(unlocked yes)
			(layer "Cmts.User")
			(hide yes)
			(effects
				(font
					(size 0.7874 0.5842)
					(thickness 0.1524)
				)
			)
		)
		(property "User Part Number" "PARTNUM*"
			(at 0.02032 4.024884 180)
			(unlocked yes)
			(layer "Cmts.User")
			(hide yes)
			(effects
				(font
					(size 0.7874 0.5842)
					(thickness 0.1524)
				)
			)
		)
		(property "Device Type" "RESISTOR-G155-133R0-01,33OHM,1%"
			(at 0.008382 1.210564 180)
			(unlocked yes)
			(layer "F.Fab")
			(hide yes)
			(effects
				(font
					(size 0.7874 0.5842)
					(thickness 0.1524)
				)
			)
		)
		(duplicate_pad_numbers_are_jumpers no)
		(fp_line
			(start 1.143 0.5588)
			(end 1.143 -0.5588)
			(stroke
				(width 0.1)
				(type default)
			)
			(layer "F.SilkS")
		)
		(fp_line
			(start 1.143 -0.5588)
			(end -1.143 -0.5588)
			(stroke
				(width 0.1)
				(type default)
			)
			(layer "F.SilkS")
		)
		(fp_line
			(start -1.143 0.5588)
			(end 1.143 0.5588)
			(stroke
				(width 0.1)
				(type default)
			)
			(layer "F.SilkS")
		)
		(fp_line
			(start -1.143 -0.5588)
			(end -1.143 0.5588)
			(stroke
				(width 0.1)
				(type default)
			)
			(layer "F.SilkS")
		)
		(fp_rect
			(start -1.143 -0.5588)
			(end 1.143 0.5588)
			(stroke
				(width 0)
				(type default)
			)
			(fill no)
			(layer "F.CrtYd")
		)
		(fp_line
			(start 0.508 0.3048)
			(end 0.508 -0.3048)
			(stroke
				(width 0.1)
				(type default)
			)
			(layer "F.Fab")
		)
		(fp_line
			(start 0.508 -0.3048)
			(end -0.508 -0.3048)
			(stroke
				(width 0.1)
				(type default)
			)
			(layer "F.Fab")
		)
		(fp_line
			(start -0.508 0.3048)
			(end 0.508 0.3048)
			(stroke
				(width 0.1)
				(type default)
			)
			(layer "F.Fab")
		)
		(fp_line
			(start -0.508 -0.3048)
			(end -0.508 0.3048)
			(stroke
				(width 0.1)
				(type default)
			)
			(layer "F.Fab")
		)
		(pad "1" smd rect
			(at -0.5334 0 180)
			(size 0.7112 0.6096)
			(layers "F.Cu" "F.Mask" "F.Paste")
			(net "SMA2_LED_RED_N")
		)
		(pad "2" smd rect
			(at 0.5334 0 180)
			(size 0.7112 0.6096)
			(layers "F.Cu" "F.Mask" "F.Paste")
			(net "UNNAMED_14_LED4PV14_I266_3")
		)
		(zone
			(layer "F.Cu")
			(hatch none 0.5)
			(connect_pads
				(clearance 0)
			)
			(min_thickness 0.25)
			(keepout
				(tracks not_allowed)
				(vias allowed)
				(pads allowed)
				(copperpour not_allowed)
				(footprints allowed)
			)
			(placement
				(enabled no)
				(sheetname "")
			)
			(fill
				(thermal_gap 0.5)
				(thermal_bridge_width 0.5)
				(island_removal_mode 0)
			)
			(polygon
				(pts
					(xy 20.3962 -30.1752) (xy 20.3962 -30.7848) (xy 20.2438 -30.7848) (xy 20.2438 -30.1752)
				)
			)
		)
		(zone
			(layer "F.Cu")
			(hatch none 0.5)
			(connect_pads
				(clearance 0)
			)
			(min_thickness 0.25)
			(keepout
				(tracks allowed)
				(vias not_allowed)
				(pads allowed)
				(copperpour not_allowed)
				(footprints allowed)
			)
			(placement
				(enabled no)
				(sheetname "")
			)
			(fill
				(thermal_gap 0.5)
				(thermal_bridge_width 0.5)
				(island_removal_mode 0)
			)
			(polygon
				(pts
					(xy 20.3962 -30.1752) (xy 20.3962 -30.7848) (xy 20.2438 -30.7848) (xy 20.2438 -30.1752)
				)
			)
		)
	)
	(footprint ""
		(layer "F.Cu")
		(at 115.1382 -81.788 180)
		(property "Reference" "R459"
			(at -0.4318 -1.18237 0)
			(unlocked yes)
			(layer "F.SilkS")
			(effects
				(font
					(size 0.7874 0.5842)
					(thickness 0.1524)
				)
			)
		)
		(property "Value" "VAL*"
			(at 0.02032 2.13233 180)
			(unlocked yes)
			(layer "F.Fab")
			(hide yes)
			(effects
				(font
					(size 0.7874 0.5842)
					(thickness 0.1524)
				)
			)
		)
		(property "Tolerance" "TOL*"
			(at 0.044704 3.05435 180)
			(unlocked yes)
			(layer "Cmts.User")
			(hide yes)
			(effects
				(font
					(size 0.7874 0.5842)
					(thickness 0.1524)
				)
			)
		)
		(property "User Part Number" "PARTNUM*"
			(at 0.02032 4.024884 180)
			(unlocked yes)
			(layer "Cmts.User")
			(hide yes)
			(effects
				(font
					(size 0.7874 0.5842)
					(thickness 0.1524)
				)
			)
		)
		(property "Device Type" "RESISTOR-G155-11001-01,1KOHM,1%"
			(at 0.008382 1.210564 180)
			(unlocked yes)
			(layer "F.Fab")
			(hide yes)
			(effects
				(font
					(size 0.7874 0.5842)
					(thickness 0.1524)
				)
			)
		)
		(duplicate_pad_numbers_are_jumpers no)
		(fp_line
			(start 1.143 0.5588)
			(end 1.143 -0.5588)
			(stroke
				(width 0.1)
				(type default)
			)
			(layer "F.SilkS")
		)
		(fp_line
			(start 1.143 -0.5588)
			(end -1.143 -0.5588)
			(stroke
				(width 0.1)
				(type default)
			)
			(layer "F.SilkS")
		)
		(fp_line
			(start -1.143 0.5588)
			(end 1.143 0.5588)
			(stroke
				(width 0.1)
				(type default)
			)
			(layer "F.SilkS")
		)
		(fp_line
			(start -1.143 -0.5588)
			(end -1.143 0.5588)
			(stroke
				(width 0.1)
				(type default)
			)
			(layer "F.SilkS")
		)
		(fp_poly
			(pts
				(xy -1.143 0.5588) (xy 1.143 0.5588) (xy 1.143 -0.5588) (xy -1.143 -0.5588)
			)
			(stroke
				(width 0)
				(type default)
			)
			(fill no)
			(layer "F.CrtYd")
		)
		(fp_line
			(start 0.508 0.3048)
			(end 0.508 -0.3048)
			(stroke
				(width 0.1)
				(type default)
			)
			(layer "F.Fab")
		)
		(fp_line
			(start 0.508 -0.3048)
			(end -0.508 -0.3048)
			(stroke
				(width 0.1)
				(type default)
			)
			(layer "F.Fab")
		)
		(fp_line
			(start -0.508 0.3048)
			(end 0.508 0.3048)
			(stroke
				(width 0.1)
				(type default)
			)
			(layer "F.Fab")
		)
		(fp_line
			(start -0.508 -0.3048)
			(end -0.508 0.3048)
			(stroke
				(width 0.1)
				(type default)
			)
			(layer "F.Fab")
		)
		(pad "1" smd rect
			(at -0.5334 0 180)
			(size 0.7112 0.6096)
			(layers "F.Cu" "F.Mask" "F.Paste")
			(net "SG")
		)
		(pad "2" smd rect
			(at 0.5334 0 180)
			(size 0.7112 0.6096)
			(layers "F.Cu" "F.Mask" "F.Paste")
			(net "UNNAMED_524_RESISTOR_I432_2")
		)
		(zone
			(layer "F.Cu")
			(hatch none 0.5)
			(connect_pads
				(clearance 0)
			)
			(min_thickness 0.25)
			(keepout
				(tracks not_allowed)
				(vias allowed)
				(pads allowed)
				(copperpour not_allowed)
				(footprints allowed)
			)
			(placement
				(enabled no)
				(sheetname "")
			)
			(fill
				(thermal_gap 0.5)
				(thermal_bridge_width 0.5)
				(island_removal_mode 0)
			)
			(polygon
				(pts
					(xy 115.2144 -82.0928) (xy 115.062 -82.0928) (xy 115.062 -81.4832) (xy 115.2144 -81.4832)
				)
			)
		)
		(zone
			(layer "F.Cu")
			(hatch none 0.5)
			(connect_pads
				(clearance 0)
			)
			(min_thickness 0.25)
			(keepout
				(tracks allowed)
				(vias not_allowed)
				(pads allowed)
				(copperpour not_allowed)
				(footprints allowed)
			)
			(placement
				(enabled no)
				(sheetname "")
			)
			(fill
				(thermal_gap 0.5)
				(thermal_bridge_width 0.5)
				(island_removal_mode 0)
			)
			(polygon
				(pts
					(xy 115.2144 -82.0928) (xy 115.062 -82.0928) (xy 115.062 -81.4832) (xy 115.2144 -81.4832)
				)
			)
		)
	)
	(footprint ""
		(layer "F.Cu")
		(at 13.462 -52.578 -90)
		(property "Reference" "R121"
			(at 0.508 3.38963 90)
			(unlocked yes)
			(layer "F.SilkS")
			(effects
				(font
					(size 0.7874 0.5842)
					(thickness 0.1524)
				)
			)
		)
		(property "Value" "VAL*"
			(at 0.02032 2.13233 270)
			(unlocked yes)
			(layer "F.Fab")
			(hide yes)
			(effects
				(font
					(size 0.7874 0.5842)
					(thickness 0.1524)
				)
			)
		)
		(property "Tolerance" "TOL*"
			(at 0.044704 3.05435 270)
			(unlocked yes)
			(layer "Cmts.User")
			(hide yes)
			(effects
				(font
					(size 0.7874 0.5842)
					(thickness 0.1524)
				)
			)
		)
		(property "User Part Number" "PARTNUM*"
			(at 0.02032 4.024884 270)
			(unlocked yes)
			(layer "Cmts.User")
			(hide yes)
			(effects
				(font
					(size 0.7874 0.5842)
					(thickness 0.1524)
				)
			)
		)
		(property "Device Type" "RESISTOR-G155-11000-01,100OHM,A"
			(at 0.008382 1.210564 270)
			(unlocked yes)
			(layer "F.Fab")
			(hide yes)
			(effects
				(font
					(size 0.7874 0.5842)
					(thickness 0.1524)
				)
			)
		)
		(duplicate_pad_numbers_are_jumpers no)
		(fp_line
			(start -1.143 0.5588)
			(end 1.143 0.5588)
			(stroke
				(width 0.1)
				(type default)
			)
			(layer "F.SilkS")
		)
		(fp_line
			(start 1.143 0.5588)
			(end 1.143 -0.5588)
			(stroke
				(width 0.1)
				(type default)
			)
			(layer "F.SilkS")
		)
		(fp_line
			(start -1.143 -0.5588)
			(end -1.143 0.5588)
			(stroke
				(width 0.1)
				(type default)
			)
			(layer "F.SilkS")
		)
		(fp_line
			(start 1.143 -0.5588)
			(end -1.143 -0.5588)
			(stroke
				(width 0.1)
				(type default)
			)
			(layer "F.SilkS")
		)
		(fp_poly
			(pts
				(xy -1.143 0.5588) (xy 1.143 0.5588) (xy 1.143 -0.5588) (xy -1.143 -0.5588)
			)
			(stroke
				(width 0)
				(type default)
			)
			(fill no)
			(layer "F.CrtYd")
		)
		(fp_line
			(start -0.508 0.3048)
			(end 0.508 0.3048)
			(stroke
				(width 0.1)
				(type default)
			)
			(layer "F.Fab")
		)
		(fp_line
			(start 0.508 0.3048)
			(end 0.508 -0.3048)
			(stroke
				(width 0.1)
				(type default)
			)
			(layer "F.Fab")
		)
		(fp_line
			(start -0.508 -0.3048)
			(end -0.508 0.3048)
			(stroke
				(width 0.1)
				(type default)
			)
			(layer "F.Fab")
		)
		(fp_line
			(start 0.508 -0.3048)
			(end -0.508 -0.3048)
			(stroke
				(width 0.1)
				(type default)
			)
			(layer "F.Fab")
		)
		(pad "1" smd rect
			(at -0.5334 0 270)
			(size 0.7112 0.6096)
			(layers "F.Cu" "F.Mask" "F.Paste")
			(net "ANT2_OUT")
		)
		(pad "2" smd rect
			(at 0.5334 0 270)
			(size 0.7112 0.6096)
			(layers "F.Cu" "F.Mask" "F.Paste")
			(net "UNNAMED_12_74HCT2G125DPTSSOP8_9")
		)
		(zone
			(layer "F.Cu")
			(hatch none 0.5)
			(connect_pads
				(clearance 0)
			)
			(min_thickness 0.25)
			(keepout
				(tracks allowed)
				(vias not_allowed)
				(pads allowed)
				(copperpour not_allowed)
				(footprints allowed)
			)
			(placement
				(enabled no)
				(sheetname "")
			)
			(fill
				(thermal_gap 0.5)
				(thermal_bridge_width 0.5)
				(island_removal_mode 0)
			)
			(polygon
				(pts
					(xy 13.1572 -52.6542) (xy 13.1572 -52.5018) (xy 13.7668 -52.5018) (xy 13.7668 -52.6542)
				)
			)
		)
		(zone
			(layer "F.Cu")
			(hatch none 0.5)
			(connect_pads
				(clearance 0)
			)
			(min_thickness 0.25)
			(keepout
				(tracks not_allowed)
				(vias allowed)
				(pads allowed)
				(copperpour not_allowed)
				(footprints allowed)
			)
			(placement
				(enabled no)
				(sheetname "")
			)
			(fill
				(thermal_gap 0.5)
				(thermal_bridge_width 0.5)
				(island_removal_mode 0)
			)
			(polygon
				(pts
					(xy 13.1572 -52.6542) (xy 13.1572 -52.5018) (xy 13.7668 -52.5018) (xy 13.7668 -52.6542)
				)
			)
		)
	)
	(footprint ""
		(layer "F.Cu")
		(at 32.021018 -67.066922)
		(property "Reference" "MAC_PIN1"
			(at 0.127762 2.834132 0)
			(unlocked yes)
			(layer "F.SilkS")
			(effects
				(font
					(size 0.7874 0.5842)
					(thickness 0.1524)
				)
			)
		)
		(property "Value" ""
			(at 0 0 0)
			(layer "F.Fab")
			(effects
				(font
					(size 1.27 1.27)
				)
			)
		)
		(property "Device Type" "NUT-A200-00029-FB"
			(at 0 2.632964 0)
			(unlocked yes)
			(layer "F.Fab")
			(hide yes)
			(effects
				(font
					(size 0.7874 0.5842)
					(thickness 0.1524)
				)
			)
		)
		(property "User Part Number" "PARTNUM*"
			(at 0 3.826764 0)
			(unlocked yes)
			(layer "Cmts.User")
			(hide yes)
			(effects
				(font
					(size 0.7874 0.5842)
					(thickness 0.1524)
				)
			)
		)
		(duplicate_pad_numbers_are_jumpers no)
		(fp_circle
			(center 0 0)
			(end 1.524 0)
			(stroke
				(width 0.1)
				(type default)
			)
			(fill no)
			(layer "F.SilkS")
		)
		(fp_poly
			(pts
				(arc
					(start -1.260856 -0.1524)
					(mid -0.898049 -0.898049)
					(end -0.1524 -1.260856)
				)
				(arc
					(start -0.1524 -0.991616)
					(mid -0.709411 -0.709411)
					(end -0.991616 -0.1524)
				)
			)
			(stroke
				(width 0)
				(type default)
			)
			(fill yes)
			(layer "F.Paste")
		)
		(fp_poly
			(pts
				(arc
					(start -0.1524 1.260856)
					(mid -0.898049 0.898049)
					(end -1.260856 0.1524)
				)
				(arc
					(start -0.991616 0.1524)
					(mid -0.709411 0.709411)
					(end -0.1524 0.991616)
				)
			)
			(stroke
				(width 0)
				(type default)
			)
			(fill yes)
			(layer "F.Paste")
		)
		(fp_poly
			(pts
				(arc
					(start 0.1524 -1.260856)
					(mid 0.898049 -0.898049)
					(end 1.260856 -0.1524)
				)
				(arc
					(start 0.991616 -0.1524)
					(mid 0.709411 -0.709411)
					(end 0.1524 -0.991616)
				)
			)
			(stroke
				(width 0)
				(type default)
			)
			(fill yes)
			(layer "F.Paste")
		)
		(fp_poly
			(pts
				(arc
					(start 1.260856 0.1524)
					(mid 0.898049 0.898049)
					(end 0.1524 1.260856)
				)
				(arc
					(start 0.1524 0.991616)
					(mid 0.709411 0.709411)
					(end 0.991616 0.1524)
				)
			)
			(stroke
				(width 0)
				(type default)
			)
			(fill yes)
			(layer "F.Paste")
		)
		(fp_poly
			(pts
				(arc
					(start 6.35 0)
					(mid -6.35 0)
					(end 6.35 0)
				)
			)
			(stroke
				(width 0)
				(type default)
			)
			(fill no)
			(layer "B.CrtYd")
		)
		(fp_poly
			(pts
				(arc
					(start 1.778 0)
					(mid -1.778 0)
					(end 1.778 0)
				)
			)
			(stroke
				(width 0)
				(type default)
			)
			(fill no)
			(layer "F.CrtYd")
		)
		(fp_circle
			(center 0 0)
			(end 1.1684 0)
			(stroke
				(width 0.1)
				(type default)
			)
			(fill no)
			(layer "F.Fab")
		)
		(pad "1" thru_hole circle
			(at 0 0)
			(size 2.54 2.54)
			(drill 2.0066)
			(layers "*.Cu" "*.Mask")
			(remove_unused_layers no)
			(net "ANALOG_TUNING_IN")
			(thermal_gap 0.0254)
			(padstack
				(mode front_inner_back)
				(layer "Inner"
					(shape circle)
					(size 2.54 2.54)
					(clearance 0.0254)
				)
				(layer "B.Cu"
					(shape circle)
					(size 2.54 2.54)
				)
			)
		)
	)
	(footprint ""
		(layer "F.Cu")
		(at 145.8214 -97.9678)
		(property "Reference" "C7"
			(at 2.6416 -0.41783 0)
			(unlocked yes)
			(layer "F.SilkS")
			(effects
				(font
					(size 0.7874 0.5842)
					(thickness 0.1524)
				)
			)
		)
		(property "Value" "VAL*"
			(at 0.0762 2.067306 0)
			(unlocked yes)
			(layer "F.Fab")
			(hide yes)
			(effects
				(font
					(size 0.7874 0.5842)
					(thickness 0.1524)
				)
			)
		)
		(property "Device Type" "CAPACITOR-G105-0B104-EK,0.1UF,A"
			(at 0.0508 1.127506 0)
			(unlocked yes)
			(layer "F.Fab")
			(hide yes)
			(effects
				(font
					(size 0.7874 0.5842)
					(thickness 0.1524)
				)
			)
		)
		(property "User Part Number" "PARTNUM*"
			(at 0.1016 4.023106 0)
			(unlocked yes)
			(layer "Cmts.User")
			(hide yes)
			(effects
				(font
					(size 0.7874 0.5842)
					(thickness 0.1524)
				)
			)
		)
		(property "Tolerance" "TOL*"
			(at 0.0762 3.032506 0)
			(unlocked yes)
			(layer "Cmts.User")
			(hide yes)
			(effects
				(font
					(size 0.7874 0.5842)
					(thickness 0.1524)
				)
			)
		)
		(duplicate_pad_numbers_are_jumpers no)
		(fp_line
			(start -1.143 -0.5588)
			(end -1.143 0.5588)
			(stroke
				(width 0.1)
				(type default)
			)
			(layer "F.SilkS")
		)
		(fp_line
			(start -1.143 0.5588)
			(end 1.143 0.5588)
			(stroke
				(width 0.1)
				(type default)
			)
			(layer "F.SilkS")
		)
		(fp_line
			(start 1.143 -0.5588)
			(end -1.143 -0.5588)
			(stroke
				(width 0.1)
				(type default)
			)
			(layer "F.SilkS")
		)
		(fp_line
			(start 1.143 0.5588)
			(end 1.143 -0.5588)
			(stroke
				(width 0.1)
				(type default)
			)
			(layer "F.SilkS")
		)
		(fp_rect
			(start -1.143 0.5588)
			(end 1.143 -0.5588)
			(stroke
				(width 0)
				(type default)
			)
			(fill no)
			(layer "F.CrtYd")
		)
		(fp_line
			(start -0.508 -0.3048)
			(end -0.508 0.3048)
			(stroke
				(width 0.1)
				(type default)
			)
			(layer "F.Fab")
		)
		(fp_line
			(start -0.508 0.3048)
			(end 0.508 0.3048)
			(stroke
				(width 0.1)
				(type default)
			)
			(layer "F.Fab")
		)
		(fp_line
			(start 0.508 -0.3048)
			(end -0.508 -0.3048)
			(stroke
				(width 0.1)
				(type default)
			)
			(layer "F.Fab")
		)
		(fp_line
			(start 0.508 0.3048)
			(end 0.508 -0.3048)
			(stroke
				(width 0.1)
				(type default)
			)
			(layer "F.Fab")
		)
		(pad "1" smd rect
			(at -0.5334 0)
			(size 0.7112 0.6096)
			(layers "F.Cu" "F.Mask" "F.Paste")
			(net "XP12R0V_A_IMON")
		)
		(pad "2" smd rect
			(at 0.5334 0)
			(size 0.7112 0.6096)
			(layers "F.Cu" "F.Mask" "F.Paste")
			(net "SG")
		)
		(zone
			(layer "F.Cu")
			(hatch none 0.5)
			(connect_pads
				(clearance 0)
			)
			(min_thickness 0.25)
			(keepout
				(tracks allowed)
				(vias not_allowed)
				(pads allowed)
				(copperpour not_allowed)
				(footprints allowed)
			)
			(placement
				(enabled no)
				(sheetname "")
			)
			(fill
				(thermal_gap 0.5)
				(thermal_bridge_width 0.5)
				(island_removal_mode 0)
			)
			(polygon
				(pts
					(xy 145.7452 -97.663) (xy 145.8976 -97.663) (xy 145.8976 -98.2726) (xy 145.7452 -98.2726)
				)
			)
		)
	)
	(footprint ""
		(layer "F.Cu")
		(at 45.02658 -16.891 180)
		(property "Reference" "U2"
			(at -0.66802 3.64363 0)
			(unlocked yes)
			(layer "F.SilkS")
			(effects
				(font
					(size 0.7874 0.5842)
					(thickness 0.1524)
				)
			)
		)
		(property "Value" ""
			(at 0 0 180)
			(layer "F.Fab")
			(effects
				(font
					(size 1.27 1.27)
				)
			)
		)
		(property "Device Type" "G220_10198_01-G223-10197-01"
			(at -0.0254 3.50647 180)
			(unlocked yes)
			(layer "F.Fab")
			(hide yes)
			(effects
				(font
					(size 0.7874 0.5842)
					(thickness 0.1524)
				)
			)
		)
		(property "User Part Number" "PARTNUM*"
			(at -0.0508 4.52247 180)
			(unlocked yes)
			(layer "Cmts.User")
			(hide yes)
			(effects
				(font
					(size 0.7874 0.5842)
					(thickness 0.1524)
				)
			)
		)
		(duplicate_pad_numbers_are_jumpers no)
		(fp_line
			(start 3.8862 2.413)
			(end 2.2098 2.413)
			(stroke
				(width 0.1)
				(type default)
			)
			(layer "F.SilkS")
		)
		(fp_line
			(start 3.8862 -2.413)
			(end 3.8862 2.413)
			(stroke
				(width 0.1)
				(type default)
			)
			(layer "F.SilkS")
		)
		(fp_line
			(start 2.2098 2.7051)
			(end -2.2098 2.7051)
			(stroke
				(width 0.1)
				(type default)
			)
			(layer "F.SilkS")
		)
		(fp_line
			(start 2.2098 2.413)
			(end 2.2098 2.7051)
			(stroke
				(width 0.1)
				(type default)
			)
			(layer "F.SilkS")
		)
		(fp_line
			(start 2.2098 -2.413)
			(end 3.8862 -2.413)
			(stroke
				(width 0.1)
				(type default)
			)
			(layer "F.SilkS")
		)
		(fp_line
			(start 2.2098 -2.7051)
			(end 2.2098 -2.413)
			(stroke
				(width 0.1)
				(type default)
			)
			(layer "F.SilkS")
		)
		(fp_line
			(start -2.2098 2.7051)
			(end -2.2098 2.413)
			(stroke
				(width 0.1)
				(type default)
			)
			(layer "F.SilkS")
		)
		(fp_line
			(start -2.2098 2.413)
			(end -3.8862 2.413)
			(stroke
				(width 0.1)
				(type default)
			)
			(layer "F.SilkS")
		)
		(fp_line
			(start -2.2098 -2.413)
			(end -2.2098 -2.7051)
			(stroke
				(width 0.1)
				(type default)
			)
			(layer "F.SilkS")
		)
		(fp_line
			(start -2.2098 -2.7051)
			(end 2.2098 -2.7051)
			(stroke
				(width 0.1)
				(type default)
			)
			(layer "F.SilkS")
		)
		(fp_line
			(start -3.8862 2.413)
			(end -3.8862 -2.413)
			(stroke
				(width 0.1)
				(type default)
			)
			(layer "F.SilkS")
		)
		(fp_line
			(start -3.8862 -2.413)
			(end -2.2098 -2.413)
			(stroke
				(width 0.1)
				(type default)
			)
			(layer "F.SilkS")
		)
		(fp_poly
			(pts
				(arc
					(start -4.892294 -1.894586)
					(mid -4.130294 -1.894586)
					(end -4.892294 -1.894586)
				)
			)
			(stroke
				(width 0)
				(type default)
			)
			(fill yes)
			(layer "F.SilkS")
		)
		(fp_rect
			(start 4.1402 -2.9591)
			(end -4.1402 2.9591)
			(stroke
				(width 0)
				(type default)
			)
			(fill no)
			(layer "F.CrtYd")
		)
		(fp_line
			(start 2.9972 2.1082)
			(end 1.9558 2.1082)
			(stroke
				(width 0.1)
				(type default)
			)
			(layer "F.Fab")
		)
		(fp_line
			(start 2.9972 1.7018)
			(end 2.9972 2.1082)
			(stroke
				(width 0.1)
				(type default)
			)
			(layer "F.Fab")
		)
		(fp_line
			(start 2.9972 0.8382)
			(end 1.9558 0.8382)
			(stroke
				(width 0.1)
				(type default)
			)
			(layer "F.Fab")
		)
		(fp_line
			(start 2.9972 0.4318)
			(end 2.9972 0.8382)
			(stroke
				(width 0.1)
				(type default)
			)
			(layer "F.Fab")
		)
		(fp_line
			(start 2.9972 -0.4318)
			(end 1.9558 -0.4318)
			(stroke
				(width 0.1)
				(type default)
			)
			(layer "F.Fab")
		)
		(fp_line
			(start 2.9972 -0.8382)
			(end 2.9972 -0.4318)
			(stroke
				(width 0.1)
				(type default)
			)
			(layer "F.Fab")
		)
		(fp_line
			(start 2.9972 -1.7018)
			(end 1.9558 -1.7018)
			(stroke
				(width 0.1)
				(type default)
			)
			(layer "F.Fab")
		)
		(fp_line
			(start 2.9972 -2.1082)
			(end 2.9972 -1.7018)
			(stroke
				(width 0.1)
				(type default)
			)
			(layer "F.Fab")
		)
		(fp_line
			(start 1.9558 2.4511)
			(end -1.9558 2.4511)
			(stroke
				(width 0.1)
				(type default)
			)
			(layer "F.Fab")
		)
		(fp_line
			(start 1.9558 1.7018)
			(end 2.9972 1.7018)
			(stroke
				(width 0.1)
				(type default)
			)
			(layer "F.Fab")
		)
		(fp_line
			(start 1.9558 0.4318)
			(end 2.9972 0.4318)
			(stroke
				(width 0.1)
				(type default)
			)
			(layer "F.Fab")
		)
		(fp_line
			(start 1.9558 -0.8382)
			(end 2.9972 -0.8382)
			(stroke
				(width 0.1)
				(type default)
			)
			(layer "F.Fab")
		)
		(fp_line
			(start 1.9558 -2.1082)
			(end 2.9972 -2.1082)
			(stroke
				(width 0.1)
				(type default)
			)
			(layer "F.Fab")
		)
		(fp_line
			(start 1.9558 -2.4511)
			(end 1.9558 2.4511)
			(stroke
				(width 0.1)
				(type default)
			)
			(layer "F.Fab")
		)
		(fp_line
			(start -1.9558 2.4511)
			(end -1.9558 -2.4511)
			(stroke
				(width 0.1)
				(type default)
			)
			(layer "F.Fab")
		)
		(fp_line
			(start -1.9558 1.7018)
			(end -2.9972 1.7018)
			(stroke
				(width 0.1)
				(type default)
			)
			(layer "F.Fab")
		)
		(fp_line
			(start -1.9558 0.4318)
			(end -2.9972 0.4318)
			(stroke
				(width 0.1)
				(type default)
			)
			(layer "F.Fab")
		)
		(fp_line
			(start -1.9558 -0.8382)
			(end -2.9972 -0.8382)
			(stroke
				(width 0.1)
				(type default)
			)
			(layer "F.Fab")
		)
		(fp_line
			(start -1.9558 -2.1082)
			(end -2.9972 -2.1082)
			(stroke
				(width 0.1)
				(type default)
			)
			(layer "F.Fab")
		)
		(fp_line
			(start -1.9558 -2.4511)
			(end 1.9558 -2.4511)
			(stroke
				(width 0.1)
				(type default)
			)
			(layer "F.Fab")
		)
		(fp_line
			(start -2.9972 2.1082)
			(end -1.9558 2.1082)
			(stroke
				(width 0.1)
				(type default)
			)
			(layer "F.Fab")
		)
		(fp_line
			(start -2.9972 1.7018)
			(end -2.9972 2.1082)
			(stroke
				(width 0.1)
				(type default)
			)
			(layer "F.Fab")
		)
		(fp_line
			(start -2.9972 0.8382)
			(end -1.9558 0.8382)
			(stroke
				(width 0.1)
				(type default)
			)
			(layer "F.Fab")
		)
		(fp_line
			(start -2.9972 0.4318)
			(end -2.9972 0.8382)
			(stroke
				(width 0.1)
				(type default)
			)
			(layer "F.Fab")
		)
		(fp_line
			(start -2.9972 -0.4318)
			(end -1.9558 -0.4318)
			(stroke
				(width 0.1)
				(type default)
			)
			(layer "F.Fab")
		)
		(fp_line
			(start -2.9972 -0.8382)
			(end -2.9972 -0.4318)
			(stroke
				(width 0.1)
				(type default)
			)
			(layer "F.Fab")
		)
		(fp_line
			(start -2.9972 -1.7018)
			(end -1.9558 -1.7018)
			(stroke
				(width 0.1)
				(type default)
			)
			(layer "F.Fab")
		)
		(fp_line
			(start -2.9972 -2.1082)
			(end -2.9972 -1.7018)
			(stroke
				(width 0.1)
				(type default)
			)
			(layer "F.Fab")
		)
		(fp_poly
			(pts
				(arc
					(start -1.284478 -1.899158)
					(mid -0.522478 -1.899158)
					(end -1.284478 -1.899158)
				)
			)
			(stroke
				(width 0)
				(type default)
			)
			(fill yes)
			(layer "F.Fab")
		)
		(fp_text user "8"
			(at 4.3688 -1.95707 0)
			(unlocked yes)
			(layer "F.SilkS")
			(effects
				(font
					(size 0.7874 0.5842)
					(thickness 0.1524)
				)
			)
		)
		(fp_text user "5"
			(at 4.25958 3.00863 0)
			(unlocked yes)
			(layer "F.SilkS")
			(effects
				(font
					(size 0.7874 0.5842)
					(thickness 0.1524)
				)
			)
		)
		(fp_text user "4"
			(at -4.37642 1.99263 0)
			(unlocked yes)
			(layer "F.SilkS")
			(effects
				(font
					(size 0.7874 0.5842)
					(thickness 0.1524)
				)
			)
		)
		(fp_text user "5"
			(at 3.8862 1.62433 0)
			(unlocked yes)
			(layer "F.Fab")
			(effects
				(font
					(size 0.7874 0.5842)
					(thickness 0.1524)
				)
			)
		)
		(fp_text user "8"
			(at 3.8608 -2.18567 0)
			(unlocked yes)
			(layer "F.Fab")
			(effects
				(font
					(size 0.7874 0.5842)
					(thickness 0.1524)
				)
			)
		)
		(fp_text user "4"
			(at -3.74142 2.00533 0)
			(unlocked yes)
			(layer "F.Fab")
			(effects
				(font
					(size 0.7874 0.5842)
					(thickness 0.1524)
				)
			)
		)
		(pad "1" smd rect
			(at -2.8067 -1.905 270)
			(size 0.508 1.651)
			(layers "F.Cu" "F.Mask" "F.Paste")
			(net "UNNAMED_3_G2201019801_I100_EN")
		)
		(pad "2" smd rect
			(at -2.8067 -0.635 270)
			(size 0.508 1.651)
			(layers "F.Cu" "F.Mask" "F.Paste")
			(net "PCIE_SMCLK")
		)
		(pad "3" smd rect
			(at -2.8067 0.635 270)
			(size 0.508 1.651)
			(layers "F.Cu" "F.Mask" "F.Paste")
			(net "PCIE_CONN_SMCLK")
		)
		(pad "4" smd rect
			(at -2.8067 1.905 270)
			(size 0.508 1.651)
			(layers "F.Cu" "F.Mask" "F.Paste")
			(net "SG")
		)
		(pad "5" smd rect
			(at 2.8067 1.905 270)
			(size 0.508 1.651)
			(layers "F.Cu" "F.Mask" "F.Paste")
			(net "Net_628")
		)
		(pad "6" smd rect
			(at 2.8067 0.635 270)
			(size 0.508 1.651)
			(layers "F.Cu" "F.Mask" "F.Paste")
			(net "PCIE_CONN_SMDAT")
		)
		(pad "7" smd rect
			(at 2.8067 -0.635 270)
			(size 0.508 1.651)
			(layers "F.Cu" "F.Mask" "F.Paste")
			(net "PCIE_SMDAT")
		)
		(pad "8" smd rect
			(at 2.8067 -1.905 270)
			(size 0.508 1.651)
			(layers "F.Cu" "F.Mask" "F.Paste")
			(net "XP3R3V_FPGA")
		)
	)
	(footprint ""
		(layer "F.Cu")
		(at 19.544792 -64.6684 -90)
		(property "Reference" "R350"
			(at 1.2954 -4.751578 90)
			(unlocked yes)
			(layer "F.SilkS")
			(effects
				(font
					(size 0.7874 0.5842)
					(thickness 0.1524)
				)
			)
		)
		(property "Value" "VAL*"
			(at 0.02032 2.13233 270)
			(unlocked yes)
			(layer "F.Fab")
			(hide yes)
			(effects
				(font
					(size 0.7874 0.5842)
					(thickness 0.1524)
				)
			)
		)
		(property "Tolerance" "TOL*"
			(at 0.044704 3.05435 270)
			(unlocked yes)
			(layer "Cmts.User")
			(hide yes)
			(effects
				(font
					(size 0.7874 0.5842)
					(thickness 0.1524)
				)
			)
		)
		(property "User Part Number" "PARTNUM*"
			(at 0.02032 4.024884 270)
			(unlocked yes)
			(layer "Cmts.User")
			(hide yes)
			(effects
				(font
					(size 0.7874 0.5842)
					(thickness 0.1524)
				)
			)
		)
		(property "Device Type" "RESISTOR-G155-100R0-J0,0OHM,-"
			(at 0.008382 1.210564 270)
			(unlocked yes)
			(layer "F.Fab")
			(hide yes)
			(effects
				(font
					(size 0.7874 0.5842)
					(thickness 0.1524)
				)
			)
		)
		(duplicate_pad_numbers_are_jumpers no)
		(fp_line
			(start -1.143 0.5588)
			(end 1.143 0.5588)
			(stroke
				(width 0.1)
				(type default)
			)
			(layer "F.SilkS")
		)
		(fp_line
			(start 1.143 0.5588)
			(end 1.143 -0.5588)
			(stroke
				(width 0.1)
				(type default)
			)
			(layer "F.SilkS")
		)
		(fp_line
			(start -1.143 -0.5588)
			(end -1.143 0.5588)
			(stroke
				(width 0.1)
				(type default)
			)
			(layer "F.SilkS")
		)
		(fp_line
			(start 1.143 -0.5588)
			(end -1.143 -0.5588)
			(stroke
				(width 0.1)
				(type default)
			)
			(layer "F.SilkS")
		)
		(fp_poly
			(pts
				(xy -1.143 0.5588) (xy 1.143 0.5588) (xy 1.143 -0.5588) (xy -1.143 -0.5588)
			)
			(stroke
				(width 0)
				(type default)
			)
			(fill no)
			(layer "F.CrtYd")
		)
		(fp_line
			(start -0.508 0.3048)
			(end 0.508 0.3048)
			(stroke
				(width 0.1)
				(type default)
			)
			(layer "F.Fab")
		)
		(fp_line
			(start 0.508 0.3048)
			(end 0.508 -0.3048)
			(stroke
				(width 0.1)
				(type default)
			)
			(layer "F.Fab")
		)
		(fp_line
			(start -0.508 -0.3048)
			(end -0.508 0.3048)
			(stroke
				(width 0.1)
				(type default)
			)
			(layer "F.Fab")
		)
		(fp_line
			(start 0.508 -0.3048)
			(end -0.508 -0.3048)
			(stroke
				(width 0.1)
				(type default)
			)
			(layer "F.Fab")
		)
		(pad "1" smd rect
			(at -0.5334 0 270)
			(size 0.7112 0.6096)
			(layers "F.Cu" "F.Mask" "F.Paste")
			(net "UNNAMED_8_ICP10100LGA10_I24_R_3")
		)
		(pad "2" smd rect
			(at 0.5334 0 270)
			(size 0.7112 0.6096)
			(layers "F.Cu" "F.Mask" "F.Paste")
			(net "XP1R8V_ICP10100")
		)
		(zone
			(layer "F.Cu")
			(hatch none 0.5)
			(connect_pads
				(clearance 0)
			)
			(min_thickness 0.25)
			(keepout
				(tracks not_allowed)
				(vias allowed)
				(pads allowed)
				(copperpour not_allowed)
				(footprints allowed)
			)
			(placement
				(enabled no)
				(sheetname "")
			)
			(fill
				(thermal_gap 0.5)
				(thermal_bridge_width 0.5)
				(island_removal_mode 0)
			)
			(polygon
				(pts
					(xy 19.239992 -64.7446) (xy 19.239992 -64.5922) (xy 19.849592 -64.5922) (xy 19.849592 -64.7446)
				)
			)
		)
		(zone
			(layer "F.Cu")
			(hatch none 0.5)
			(connect_pads
				(clearance 0)
			)
			(min_thickness 0.25)
			(keepout
				(tracks allowed)
				(vias not_allowed)
				(pads allowed)
				(copperpour not_allowed)
				(footprints allowed)
			)
			(placement
				(enabled no)
				(sheetname "")
			)
			(fill
				(thermal_gap 0.5)
				(thermal_bridge_width 0.5)
				(island_removal_mode 0)
			)
			(polygon
				(pts
					(xy 19.239992 -64.7446) (xy 19.239992 -64.5922) (xy 19.849592 -64.5922) (xy 19.849592 -64.7446)
				)
			)
		)
	)
	(footprint ""
		(layer "F.Cu")
		(at 146.304 -62.611)
		(property "Reference" "TP39"
			(at -1.7272 -1.35763 0)
			(unlocked yes)
			(layer "F.SilkS")
			(effects
				(font
					(size 0.7874 0.5842)
					(thickness 0.1524)
				)
				(justify left)
			)
		)
		(property "Value" ""
			(at 0 0 0)
			(layer "F.Fab")
			(effects
				(font
					(size 1.27 1.27)
				)
			)
		)
		(property "Device Type" "TP_PIONT-TP010CT020B030_PTH-TPA"
			(at -1.341882 0.996696 0)
			(unlocked yes)
			(layer "F.Fab")
			(hide yes)
			(effects
				(font
					(size 0.7874 0.5842)
					(thickness 0.000001)
				)
				(justify left)
			)
		)
		(duplicate_pad_numbers_are_jumpers no)
		(fp_poly
			(pts
				(arc
					(start 0.889 0)
					(mid -0.889 0)
					(end 0.889 0)
				)
			)
			(stroke
				(width 0)
				(type default)
			)
			(fill no)
			(layer "B.CrtYd")
		)
		(fp_poly
			(pts
				(arc
					(start 0.889 0)
					(mid -0.889 0)
					(end 0.889 0)
				)
			)
			(stroke
				(width 0)
				(type default)
			)
			(fill no)
			(layer "F.CrtYd")
		)
		(pad "1" thru_hole circle
			(at 0 0)
			(size 0.508 0.508)
			(drill 0.254)
			(layers "*.Cu" "*.Mask")
			(remove_unused_layers no)
			(net "XP1R0V_FPGA_PG")
			(clearance 0.1016)
			(padstack
				(mode front_inner_back)
				(layer "Inner"
					(shape circle)
					(size 0.508 0.508)
					(clearance 0.1016)
				)
				(layer "B.Cu"
					(shape circle)
					(size 0.762 0.762)
					(clearance -0.0254)
				)
			)
		)
	)
	(footprint ""
		(layer "F.Cu")
		(at 126.619 -89.535 90)
		(property "Reference" "R112"
			(at -3.429 0.54737 90)
			(unlocked yes)
			(layer "F.SilkS")
			(effects
				(font
					(size 0.7874 0.5842)
					(thickness 0.1524)
				)
			)
		)
		(property "Value" "VAL*"
			(at 0.02032 2.13233 90)
			(unlocked yes)
			(layer "F.Fab")
			(hide yes)
			(effects
				(font
					(size 0.7874 0.5842)
					(thickness 0.1524)
				)
			)
		)
		(property "Tolerance" "TOL*"
			(at 0.044704 3.05435 90)
			(unlocked yes)
			(layer "Cmts.User")
			(hide yes)
			(effects
				(font
					(size 0.7874 0.5842)
					(thickness 0.1524)
				)
			)
		)
		(property "User Part Number" "PARTNUM*"
			(at 0.02032 4.024884 90)
			(unlocked yes)
			(layer "Cmts.User")
			(hide yes)
			(effects
				(font
					(size 0.7874 0.5842)
					(thickness 0.1524)
				)
			)
		)
		(property "Device Type" "RESISTOR-G155-133R0-01,33OHM,1%"
			(at 0.008382 1.210564 90)
			(unlocked yes)
			(layer "F.Fab")
			(hide yes)
			(effects
				(font
					(size 0.7874 0.5842)
					(thickness 0.1524)
				)
			)
		)
		(duplicate_pad_numbers_are_jumpers no)
		(fp_line
			(start 1.143 -0.5588)
			(end -1.143 -0.5588)
			(stroke
				(width 0.1)
				(type default)
			)
			(layer "F.SilkS")
		)
		(fp_line
			(start -1.143 -0.5588)
			(end -1.143 0.5588)
			(stroke
				(width 0.1)
				(type default)
			)
			(layer "F.SilkS")
		)
		(fp_line
			(start 1.143 0.5588)
			(end 1.143 -0.5588)
			(stroke
				(width 0.1)
				(type default)
			)
			(layer "F.SilkS")
		)
		(fp_line
			(start -1.143 0.5588)
			(end 1.143 0.5588)
			(stroke
				(width 0.1)
				(type default)
			)
			(layer "F.SilkS")
		)
		(fp_rect
			(start -1.143 0.5588)
			(end 1.143 -0.5588)
			(stroke
				(width 0)
				(type default)
			)
			(fill no)
			(layer "F.CrtYd")
		)
		(fp_line
			(start 0.508 -0.3048)
			(end -0.508 -0.3048)
			(stroke
				(width 0.1)
				(type default)
			)
			(layer "F.Fab")
		)
		(fp_line
			(start -0.508 -0.3048)
			(end -0.508 0.3048)
			(stroke
				(width 0.1)
				(type default)
			)
			(layer "F.Fab")
		)
		(fp_line
			(start 0.508 0.3048)
			(end 0.508 -0.3048)
			(stroke
				(width 0.1)
				(type default)
			)
			(layer "F.Fab")
		)
		(fp_line
			(start -0.508 0.3048)
			(end 0.508 0.3048)
			(stroke
				(width 0.1)
				(type default)
			)
			(layer "F.Fab")
		)
		(pad "1" smd rect
			(at -0.5334 0 90)
			(size 0.7112 0.6096)
			(layers "F.Cu" "F.Mask" "F.Paste")
			(net "DBG_UART_GPS_TXD")
		)
		(pad "2" smd rect
			(at 0.5334 0 90)
			(size 0.7112 0.6096)
			(layers "F.Cu" "F.Mask" "F.Paste")
			(net "GPS_UART_TXD")
		)
		(zone
			(layer "F.Cu")
			(hatch none 0.5)
			(connect_pads
				(clearance 0)
			)
			(min_thickness 0.25)
			(keepout
				(tracks allowed)
				(vias not_allowed)
				(pads allowed)
				(copperpour not_allowed)
				(footprints allowed)
			)
			(placement
				(enabled no)
				(sheetname "")
			)
			(fill
				(thermal_gap 0.5)
				(thermal_bridge_width 0.5)
				(island_removal_mode 0)
			)
			(polygon
				(pts
					(xy 126.9238 -89.4588) (xy 126.9238 -89.6112) (xy 126.3142 -89.6112) (xy 126.3142 -89.4588)
				)
			)
		)
	)
	(footprint ""
		(layer "F.Cu")
		(at 138.050016 -104.350058 -90)
		(property "Reference" "DS6"
			(at 0.845058 1.993646 90)
			(unlocked yes)
			(layer "F.SilkS")
			(effects
				(font
					(size 0.7874 0.5842)
					(thickness 0.1524)
				)
			)
		)
		(property "Value" ""
			(at 0 0 270)
			(layer "F.Fab")
			(effects
				(font
					(size 1.27 1.27)
				)
			)
		)
		(property "Device Type" "OPTICAL-G170-10143-01"
			(at 0.1778 1.483081 270)
			(unlocked yes)
			(layer "F.Fab")
			(hide yes)
			(effects
				(font
					(size 0.786892 0.583946)
					(thickness 0.000001)
				)
			)
		)
		(property "User Part Number" "PARTNUM*"
			(at 0.1778 2.422881 270)
			(unlocked yes)
			(layer "Cmts.User")
			(hide yes)
			(effects
				(font
					(size 0.786892 0.583946)
					(thickness 0.000001)
				)
			)
		)
		(duplicate_pad_numbers_are_jumpers no)
		(fp_line
			(start -0.8128 1.8542)
			(end -2.0828 1.8542)
			(stroke
				(width 0.1)
				(type default)
			)
			(layer "F.SilkS")
		)
		(fp_line
			(start -1.4478 1.2192)
			(end -1.4478 2.4892)
			(stroke
				(width 0.1)
				(type default)
			)
			(layer "F.SilkS")
		)
		(fp_line
			(start -1.397508 0.704088)
			(end -1.397508 -0.704088)
			(stroke
				(width 0.1)
				(type default)
			)
			(layer "F.SilkS")
		)
		(fp_line
			(start 1.397508 0.704088)
			(end -1.397508 0.704088)
			(stroke
				(width 0.1)
				(type default)
			)
			(layer "F.SilkS")
		)
		(fp_line
			(start -1.397508 -0.704088)
			(end 1.397508 -0.704088)
			(stroke
				(width 0.1)
				(type default)
			)
			(layer "F.SilkS")
		)
		(fp_line
			(start 1.397508 -0.704088)
			(end 1.397508 0.704088)
			(stroke
				(width 0.1)
				(type default)
			)
			(layer "F.SilkS")
		)
		(fp_rect
			(start 1.905508 0.704088)
			(end 1.397508 -0.704088)
			(stroke
				(width 0)
				(type default)
			)
			(fill yes)
			(layer "F.SilkS")
		)
		(fp_rect
			(start 1.905508 0.958088)
			(end -1.651508 -0.958088)
			(stroke
				(width 0)
				(type default)
			)
			(fill no)
			(layer "F.CrtYd")
		)
		(fp_line
			(start -1.1938 1.4732)
			(end -2.4638 1.4732)
			(stroke
				(width 0.1)
				(type default)
			)
			(layer "F.Fab")
		)
		(fp_line
			(start -1.8288 0.8382)
			(end -1.8288 2.1082)
			(stroke
				(width 0.1)
				(type default)
			)
			(layer "F.Fab")
		)
		(fp_line
			(start -0.850138 0.450088)
			(end 0.850138 0.450088)
			(stroke
				(width 0.1)
				(type default)
			)
			(layer "F.Fab")
		)
		(fp_line
			(start 0.850138 0.450088)
			(end 0.850138 -0.450088)
			(stroke
				(width 0.1)
				(type default)
			)
			(layer "F.Fab")
		)
		(fp_line
			(start -0.850138 -0.450088)
			(end -0.850138 0.450088)
			(stroke
				(width 0.1)
				(type default)
			)
			(layer "F.Fab")
		)
		(fp_line
			(start 0.850138 -0.450088)
			(end -0.850138 -0.450088)
			(stroke
				(width 0.1)
				(type default)
			)
			(layer "F.Fab")
		)
		(fp_rect
			(start 0.850138 0.450088)
			(end 0.342138 -0.450088)
			(stroke
				(width 0)
				(type default)
			)
			(fill yes)
			(layer "F.Fab")
		)
		(fp_text user "A"
			(at -0.774192 1.652016 0)
			(unlocked yes)
			(layer "F.SilkS")
			(effects
				(font
					(size 0.635 0.4064)
					(thickness 0.1524)
				)
			)
		)
		(fp_text user "C"
			(at 1.892808 1.271016 0)
			(unlocked yes)
			(layer "F.SilkS")
			(effects
				(font
					(size 0.635 0.4064)
					(thickness 0.1524)
				)
			)
		)
		(fp_text user "A"
			(at -1.020572 0.890016 0)
			(unlocked yes)
			(layer "F.Fab")
			(effects
				(font
					(size 0.7874 0.5842)
					(thickness 0.1524)
				)
			)
		)
		(fp_text user "C"
			(at 1.773428 0.128016 0)
			(unlocked yes)
			(layer "F.Fab")
			(effects
				(font
					(size 0.7874 0.5842)
					(thickness 0.1524)
				)
			)
		)
		(pad "A" smd rect
			(at -0.749808 0 270)
			(size 0.7874 0.7874)
			(layers "F.Cu" "F.Mask" "F.Paste")
			(net "UNNAMED_14_OPTICAL_I140_A")
		)
		(pad "C" smd rect
			(at 0.749808 0 270)
			(size 0.7874 0.7874)
			(layers "F.Cu" "F.Mask" "F.Paste")
			(net "SG")
		)
	)
	(footprint ""
		(layer "F.Cu")
		(at 42.6974 -105.4354)
		(property "Reference" "C30"
			(at 3.6576 -1.21793 0)
			(unlocked yes)
			(layer "F.SilkS")
			(effects
				(font
					(size 0.7874 0.5842)
					(thickness 0.1524)
				)
			)
		)
		(property "Value" "VAL*"
			(at 0.0762 3.134106 0)
			(unlocked yes)
			(layer "F.Fab")
			(hide yes)
			(effects
				(font
					(size 0.7874 0.5842)
					(thickness 0.1524)
				)
			)
		)
		(property "Device Type" "CAPACITOR-G107-0F106-EM,10UF,2A"
			(at 0.0508 2.194306 0)
			(unlocked yes)
			(layer "F.Fab")
			(hide yes)
			(effects
				(font
					(size 0.7874 0.5842)
					(thickness 0.1524)
				)
			)
		)
		(property "User Part Number" "PARTNUM*"
			(at 0.1016 5.013706 0)
			(unlocked yes)
			(layer "Cmts.User")
			(hide yes)
			(effects
				(font
					(size 0.7874 0.5842)
					(thickness 0.1524)
				)
			)
		)
		(property "Tolerance" "TOL*"
			(at 0.0762 4.048506 0)
			(unlocked yes)
			(layer "Cmts.User")
			(hide yes)
			(effects
				(font
					(size 0.7874 0.5842)
					(thickness 0.1524)
				)
			)
		)
		(duplicate_pad_numbers_are_jumpers no)
		(fp_line
			(start -1.5748 -0.9398)
			(end -1.5748 0.9398)
			(stroke
				(width 0.1)
				(type default)
			)
			(layer "F.SilkS")
		)
		(fp_line
			(start -1.5748 0.9398)
			(end 1.5748 0.9398)
			(stroke
				(width 0.1)
				(type default)
			)
			(layer "F.SilkS")
		)
		(fp_line
			(start 1.5748 -0.9398)
			(end -1.5748 -0.9398)
			(stroke
				(width 0.1)
				(type default)
			)
			(layer "F.SilkS")
		)
		(fp_line
			(start 1.5748 0.9398)
			(end 1.5748 -0.9398)
			(stroke
				(width 0.1)
				(type default)
			)
			(layer "F.SilkS")
		)
		(fp_rect
			(start 1.5748 -0.9398)
			(end -1.5748 0.9398)
			(stroke
				(width 0)
				(type default)
			)
			(fill no)
			(layer "F.CrtYd")
		)
		(fp_line
			(start -1.016 -0.635)
			(end -1.016 0.635)
			(stroke
				(width 0.1)
				(type default)
			)
			(layer "F.Fab")
		)
		(fp_line
			(start -1.016 0.635)
			(end 1.016 0.635)
			(stroke
				(width 0.1)
				(type default)
			)
			(layer "F.Fab")
		)
		(fp_line
			(start 1.016 -0.635)
			(end -1.016 -0.635)
			(stroke
				(width 0.1)
				(type default)
			)
			(layer "F.Fab")
		)
		(fp_line
			(start 1.016 0.635)
			(end 1.016 -0.635)
			(stroke
				(width 0.1)
				(type default)
			)
			(layer "F.Fab")
		)
		(pad "1" smd rect
			(at -0.8382 0)
			(size 0.9652 1.3716)
			(layers "F.Cu" "F.Mask" "F.Paste")
			(net "VIN_XP5R0V")
		)
		(pad "2" smd rect
			(at 0.8382 0)
			(size 0.9652 1.3716)
			(layers "F.Cu" "F.Mask" "F.Paste")
			(net "SG")
		)
		(zone
			(layer "F.Cu")
			(hatch none 0.5)
			(connect_pads
				(clearance 0)
			)
			(min_thickness 0.25)
			(keepout
				(tracks allowed)
				(vias not_allowed)
				(pads allowed)
				(copperpour not_allowed)
				(footprints allowed)
			)
			(placement
				(enabled no)
				(sheetname "")
			)
			(fill
				(thermal_gap 0.5)
				(thermal_bridge_width 0.5)
				(island_removal_mode 0)
			)
			(polygon
				(pts
					(xy 42.926 -106.0704) (xy 42.4688 -106.0704) (xy 42.4688 -104.8004) (xy 42.926 -104.8004)
				)
			)
		)
	)
	(footprint ""
		(layer "F.Cu")
		(at 111.887 -93.98)
		(property "Reference" "R452"
			(at 3.175 -0.08763 0)
			(unlocked yes)
			(layer "F.SilkS")
			(effects
				(font
					(size 0.7874 0.5842)
					(thickness 0.1524)
				)
			)
		)
		(property "Value" "VAL*"
			(at 0.02032 2.13233 0)
			(unlocked yes)
			(layer "F.Fab")
			(hide yes)
			(effects
				(font
					(size 0.7874 0.5842)
					(thickness 0.1524)
				)
			)
		)
		(property "Tolerance" "TOL*"
			(at 0.044704 3.05435 0)
			(unlocked yes)
			(layer "Cmts.User")
			(hide yes)
			(effects
				(font
					(size 0.7874 0.5842)
					(thickness 0.1524)
				)
			)
		)
		(property "User Part Number" "PARTNUM*"
			(at 0.02032 4.024884 0)
			(unlocked yes)
			(layer "Cmts.User")
			(hide yes)
			(effects
				(font
					(size 0.7874 0.5842)
					(thickness 0.1524)
				)
			)
		)
		(property "Device Type" "RESISTOR-G155-14701-01,4.7KOHMA"
			(at 0.008382 1.210564 0)
			(unlocked yes)
			(layer "F.Fab")
			(hide yes)
			(effects
				(font
					(size 0.7874 0.5842)
					(thickness 0.1524)
				)
			)
		)
		(duplicate_pad_numbers_are_jumpers no)
		(fp_line
			(start -1.143 -0.5588)
			(end -1.143 0.5588)
			(stroke
				(width 0.1)
				(type default)
			)
			(layer "F.SilkS")
		)
		(fp_line
			(start -1.143 0.5588)
			(end 1.143 0.5588)
			(stroke
				(width 0.1)
				(type default)
			)
			(layer "F.SilkS")
		)
		(fp_line
			(start 1.143 -0.5588)
			(end -1.143 -0.5588)
			(stroke
				(width 0.1)
				(type default)
			)
			(layer "F.SilkS")
		)
		(fp_line
			(start 1.143 0.5588)
			(end 1.143 -0.5588)
			(stroke
				(width 0.1)
				(type default)
			)
			(layer "F.SilkS")
		)
		(fp_poly
			(pts
				(xy -1.143 0.5588) (xy 1.143 0.5588) (xy 1.143 -0.5588) (xy -1.143 -0.5588)
			)
			(stroke
				(width 0)
				(type default)
			)
			(fill no)
			(layer "F.CrtYd")
		)
		(fp_line
			(start -0.508 -0.3048)
			(end -0.508 0.3048)
			(stroke
				(width 0.1)
				(type default)
			)
			(layer "F.Fab")
		)
		(fp_line
			(start -0.508 0.3048)
			(end 0.508 0.3048)
			(stroke
				(width 0.1)
				(type default)
			)
			(layer "F.Fab")
		)
		(fp_line
			(start 0.508 -0.3048)
			(end -0.508 -0.3048)
			(stroke
				(width 0.1)
				(type default)
			)
			(layer "F.Fab")
		)
		(fp_line
			(start 0.508 0.3048)
			(end 0.508 -0.3048)
			(stroke
				(width 0.1)
				(type default)
			)
			(layer "F.Fab")
		)
		(pad "1" smd rect
			(at -0.5334 0)
			(size 0.7112 0.6096)
			(layers "F.Cu" "F.Mask" "F.Paste")
			(net "UNNAMED_524_POWERMOS3PNCHV1_I44")
		)
		(pad "2" smd rect
			(at 0.5334 0)
			(size 0.7112 0.6096)
			(layers "F.Cu" "F.Mask" "F.Paste")
			(net "XP3R3V_FPGA")
		)
		(zone
			(layer "F.Cu")
			(hatch none 0.5)
			(connect_pads
				(clearance 0)
			)
			(min_thickness 0.25)
			(keepout
				(tracks allowed)
				(vias not_allowed)
				(pads allowed)
				(copperpour not_allowed)
				(footprints allowed)
			)
			(placement
				(enabled no)
				(sheetname "")
			)
			(fill
				(thermal_gap 0.5)
				(thermal_bridge_width 0.5)
				(island_removal_mode 0)
			)
			(polygon
				(pts
					(xy 111.8108 -93.6752) (xy 111.9632 -93.6752) (xy 111.9632 -94.2848) (xy 111.8108 -94.2848)
				)
			)
		)
		(zone
			(layer "F.Cu")
			(hatch none 0.5)
			(connect_pads
				(clearance 0)
			)
			(min_thickness 0.25)
			(keepout
				(tracks not_allowed)
				(vias allowed)
				(pads allowed)
				(copperpour not_allowed)
				(footprints allowed)
			)
			(placement
				(enabled no)
				(sheetname "")
			)
			(fill
				(thermal_gap 0.5)
				(thermal_bridge_width 0.5)
				(island_removal_mode 0)
			)
			(polygon
				(pts
					(xy 111.8108 -93.6752) (xy 111.9632 -93.6752) (xy 111.9632 -94.2848) (xy 111.8108 -94.2848)
				)
			)
		)
	)
	(footprint ""
		(layer "F.Cu")
		(at 106.807 -20.828)
		(property "Reference" "TP49"
			(at 0.03937 4.5212 90)
			(unlocked yes)
			(layer "F.SilkS")
			(effects
				(font
					(size 0.7874 0.5842)
					(thickness 0.1524)
				)
				(justify left)
			)
		)
		(property "Value" ""
			(at 0 0 0)
			(layer "F.Fab")
			(effects
				(font
					(size 1.27 1.27)
				)
			)
		)
		(property "Device Type" "TP_PIONT-TP010CT020B030_PTH-TPA"
			(at -1.341882 0.996696 0)
			(unlocked yes)
			(layer "F.Fab")
			(hide yes)
			(effects
				(font
					(size 0.7874 0.5842)
					(thickness 0.000001)
				)
				(justify left)
			)
		)
		(duplicate_pad_numbers_are_jumpers no)
		(fp_poly
			(pts
				(arc
					(start 0.889 0)
					(mid -0.889 0)
					(end 0.889 0)
				)
			)
			(stroke
				(width 0)
				(type default)
			)
			(fill no)
			(layer "B.CrtYd")
		)
		(fp_poly
			(pts
				(arc
					(start 0.889 0)
					(mid -0.889 0)
					(end 0.889 0)
				)
			)
			(stroke
				(width 0)
				(type default)
			)
			(fill no)
			(layer "F.CrtYd")
		)
		(pad "1" thru_hole circle
			(at 0 0)
			(size 0.508 0.508)
			(drill 0.254)
			(layers "*.Cu" "*.Mask")
			(remove_unused_layers no)
			(net "CLK_200M_OE")
			(clearance 0.1016)
			(padstack
				(mode front_inner_back)
				(layer "Inner"
					(shape circle)
					(size 0.508 0.508)
					(clearance 0.1016)
				)
				(layer "B.Cu"
					(shape circle)
					(size 0.762 0.762)
					(clearance -0.0254)
				)
			)
		)
	)
	(footprint ""
		(layer "F.Cu")
		(at 141.732 -100.584 180)
		(property "Reference" "R13"
			(at -2.032 -0.66675 0)
			(unlocked yes)
			(layer "F.SilkS")
			(effects
				(font
					(size 0.635 0.4064)
					(thickness 0.1524)
				)
			)
		)
		(property "Value" "VAL*"
			(at 0.02032 2.13233 180)
			(unlocked yes)
			(layer "F.Fab")
			(hide yes)
			(effects
				(font
					(size 0.7874 0.5842)
					(thickness 0.1524)
				)
			)
		)
		(property "Device Type" "RESISTOR-G155-11002-01,10KOHM,A"
			(at 0.008382 1.210564 180)
			(unlocked yes)
			(layer "F.Fab")
			(hide yes)
			(effects
				(font
					(size 0.7874 0.5842)
					(thickness 0.1524)
				)
			)
		)
		(property "User Part Number" "PARTNUM*"
			(at 0.02032 4.024884 180)
			(unlocked yes)
			(layer "Cmts.User")
			(hide yes)
			(effects
				(font
					(size 0.7874 0.5842)
					(thickness 0.1524)
				)
			)
		)
		(property "Tolerance" "TOL*"
			(at 0.044704 3.05435 180)
			(unlocked yes)
			(layer "Cmts.User")
			(hide yes)
			(effects
				(font
					(size 0.7874 0.5842)
					(thickness 0.1524)
				)
			)
		)
		(duplicate_pad_numbers_are_jumpers no)
		(fp_line
			(start 1.143 0.5588)
			(end 1.143 -0.5588)
			(stroke
				(width 0.1)
				(type default)
			)
			(layer "F.SilkS")
		)
		(fp_line
			(start 1.143 -0.5588)
			(end -1.143 -0.5588)
			(stroke
				(width 0.1)
				(type default)
			)
			(layer "F.SilkS")
		)
		(fp_line
			(start -1.143 0.5588)
			(end 1.143 0.5588)
			(stroke
				(width 0.1)
				(type default)
			)
			(layer "F.SilkS")
		)
		(fp_line
			(start -1.143 -0.5588)
			(end -1.143 0.5588)
			(stroke
				(width 0.1)
				(type default)
			)
			(layer "F.SilkS")
		)
		(fp_rect
			(start -1.143 0.5588)
			(end 1.143 -0.5588)
			(stroke
				(width 0)
				(type default)
			)
			(fill no)
			(layer "F.CrtYd")
		)
		(fp_line
			(start 0.508 0.3048)
			(end 0.508 -0.3048)
			(stroke
				(width 0.1)
				(type default)
			)
			(layer "F.Fab")
		)
		(fp_line
			(start 0.508 -0.3048)
			(end -0.508 -0.3048)
			(stroke
				(width 0.1)
				(type default)
			)
			(layer "F.Fab")
		)
		(fp_line
			(start -0.508 0.3048)
			(end 0.508 0.3048)
			(stroke
				(width 0.1)
				(type default)
			)
			(layer "F.Fab")
		)
		(fp_line
			(start -0.508 -0.3048)
			(end -0.508 0.3048)
			(stroke
				(width 0.1)
				(type default)
			)
			(layer "F.Fab")
		)
		(pad "1" smd rect
			(at -0.5334 0 180)
			(size 0.7112 0.6096)
			(layers "F.Cu" "F.Mask" "F.Paste")
			(net "XP12R0V")
		)
		(pad "2" smd rect
			(at 0.5334 0 180)
			(size 0.7112 0.6096)
			(layers "F.Cu" "F.Mask" "F.Paste")
			(net "XP12R0V_A_PG")
		)
		(zone
			(layer "F.Cu")
			(hatch none 0.5)
			(connect_pads
				(clearance 0)
			)
			(min_thickness 0.25)
			(keepout
				(tracks allowed)
				(vias not_allowed)
				(pads allowed)
				(copperpour not_allowed)
				(footprints allowed)
			)
			(placement
				(enabled no)
				(sheetname "")
			)
			(fill
				(thermal_gap 0.5)
				(thermal_bridge_width 0.5)
				(island_removal_mode 0)
			)
			(polygon
				(pts
					(xy 141.8082 -100.8888) (xy 141.6558 -100.8888) (xy 141.6558 -100.2792) (xy 141.8082 -100.2792)
				)
			)
		)
	)
	(footprint ""
		(layer "F.Cu")
		(at 37.101018 -68.082922)
		(property "Reference" "ME5"
			(at -1.795018 -4.140708 0)
			(unlocked yes)
			(layer "F.SilkS")
			(effects
				(font
					(size 0.7874 0.5842)
					(thickness 0.1524)
				)
			)
		)
		(property "Value" ""
			(at 0 0 0)
			(layer "F.Fab")
			(effects
				(font
					(size 1.27 1.27)
				)
			)
		)
		(duplicate_pad_numbers_are_jumpers no)
		(fp_poly
			(pts
				(arc
					(start 3.556 0)
					(mid -3.556 0)
					(end 3.556 0)
				)
			)
			(stroke
				(width 0)
				(type default)
			)
			(fill no)
			(layer "B.CrtYd")
		)
		(fp_poly
			(pts
				(arc
					(start 3.556 0)
					(mid -3.556 0)
					(end 3.556 0)
				)
			)
			(stroke
				(width 0)
				(type default)
			)
			(fill no)
			(layer "F.CrtYd")
		)
		(fp_circle
			(center 0 0)
			(end 3.048 0)
			(stroke
				(width 0.1)
				(type default)
			)
			(fill no)
			(layer "B.Fab")
		)
		(fp_circle
			(center 0 0)
			(end 3.048 0)
			(stroke
				(width 0.1)
				(type default)
			)
			(fill no)
			(layer "F.Fab")
		)
		(pad "" np_thru_hole circle
			(at 0 0)
			(size 2.286 2.286)
			(drill 2.54)
			(layers "*.Cu" "*.Mask")
			(padstack
				(mode front_inner_back)
				(layer "Inner"
					(shape circle)
					(size 2.286 2.286)
					(clearance 0.4445)
				)
				(layer "B.Cu"
					(shape circle)
					(size 2.286 2.286)
				)
			)
		)
		(zone
			(layers "F.Cu" "B.Cu" "In1.Cu" "In2.Cu" "In3.Cu" "In4.Cu" "In5.Cu" "In6.Cu"
				"In7.Cu" "In8.Cu"
			)
			(hatch none 0.5)
			(connect_pads
				(clearance 0)
			)
			(min_thickness 0.25)
			(keepout
				(tracks not_allowed)
				(vias allowed)
				(pads allowed)
				(copperpour not_allowed)
				(footprints allowed)
			)
			(placement
				(enabled no)
				(sheetname "")
			)
			(fill
				(thermal_gap 0.5)
				(thermal_bridge_width 0.5)
				(island_removal_mode 0)
			)
			(polygon
				(pts
					(arc
						(start 38.675818 -68.082922)
						(mid 35.526218 -68.082922)
						(end 38.675818 -68.082922)
					)
				)
			)
		)
	)
	(footprint ""
		(layer "F.Cu")
		(at 131.953 -64.0334 180)
		(property "Reference" "C195"
			(at -0.381 -3.36677 0)
			(unlocked yes)
			(layer "F.SilkS")
			(effects
				(font
					(size 0.7874 0.5842)
					(thickness 0.1524)
				)
			)
		)
		(property "Value" "VAL*"
			(at 0.0762 3.134106 180)
			(unlocked yes)
			(layer "F.Fab")
			(hide yes)
			(effects
				(font
					(size 0.7874 0.5842)
					(thickness 0.1524)
				)
			)
		)
		(property "Tolerance" "TOL*"
			(at 0.0762 4.048506 180)
			(unlocked yes)
			(layer "Cmts.User")
			(hide yes)
			(effects
				(font
					(size 0.7874 0.5842)
					(thickness 0.1524)
				)
			)
		)
		(property "User Part Number" "PARTNUM*"
			(at 0.1016 5.013706 180)
			(unlocked yes)
			(layer "Cmts.User")
			(hide yes)
			(effects
				(font
					(size 0.7874 0.5842)
					(thickness 0.1524)
				)
			)
		)
		(property "Device Type" "CAPACITOR-G107-0F106-EM,10UF,2A"
			(at 0.0508 2.194306 180)
			(unlocked yes)
			(layer "F.Fab")
			(hide yes)
			(effects
				(font
					(size 0.7874 0.5842)
					(thickness 0.1524)
				)
			)
		)
		(duplicate_pad_numbers_are_jumpers no)
		(fp_line
			(start 1.5748 0.9398)
			(end 1.5748 -0.9398)
			(stroke
				(width 0.1)
				(type default)
			)
			(layer "F.SilkS")
		)
		(fp_line
			(start 1.5748 -0.9398)
			(end -1.5748 -0.9398)
			(stroke
				(width 0.1)
				(type default)
			)
			(layer "F.SilkS")
		)
		(fp_line
			(start -1.5748 0.9398)
			(end 1.5748 0.9398)
			(stroke
				(width 0.1)
				(type default)
			)
			(layer "F.SilkS")
		)
		(fp_line
			(start -1.5748 -0.9398)
			(end -1.5748 0.9398)
			(stroke
				(width 0.1)
				(type default)
			)
			(layer "F.SilkS")
		)
		(fp_rect
			(start -1.5748 0.9398)
			(end 1.5748 -0.9398)
			(stroke
				(width 0)
				(type default)
			)
			(fill no)
			(layer "F.CrtYd")
		)
		(fp_line
			(start 1.016 0.635)
			(end 1.016 -0.635)
			(stroke
				(width 0.1)
				(type default)
			)
			(layer "F.Fab")
		)
		(fp_line
			(start 1.016 -0.635)
			(end -1.016 -0.635)
			(stroke
				(width 0.1)
				(type default)
			)
			(layer "F.Fab")
		)
		(fp_line
			(start -1.016 0.635)
			(end 1.016 0.635)
			(stroke
				(width 0.1)
				(type default)
			)
			(layer "F.Fab")
		)
		(fp_line
			(start -1.016 -0.635)
			(end -1.016 0.635)
			(stroke
				(width 0.1)
				(type default)
			)
			(layer "F.Fab")
		)
		(pad "1" smd rect
			(at -0.8382 0 180)
			(size 0.9652 1.3716)
			(layers "F.Cu" "F.Mask" "F.Paste")
			(net "XP1R8V_FPGA")
		)
		(pad "2" smd rect
			(at 0.8382 0 180)
			(size 0.9652 1.3716)
			(layers "F.Cu" "F.Mask" "F.Paste")
			(net "SG")
		)
		(zone
			(layer "F.Cu")
			(hatch none 0.5)
			(connect_pads
				(clearance 0)
			)
			(min_thickness 0.25)
			(keepout
				(tracks allowed)
				(vias not_allowed)
				(pads allowed)
				(copperpour not_allowed)
				(footprints allowed)
			)
			(placement
				(enabled no)
				(sheetname "")
			)
			(fill
				(thermal_gap 0.5)
				(thermal_bridge_width 0.5)
				(island_removal_mode 0)
			)
			(polygon
				(pts
					(xy 132.1816 -64.6684) (xy 131.7244 -64.6684) (xy 131.7244 -63.3984) (xy 132.1816 -63.3984)
				)
			)
		)
	)
	(footprint ""
		(layer "F.Cu")
		(at 142.875 -17.2466)
		(property "Reference" "U25"
			(at -0.254 2.68097 0)
			(unlocked yes)
			(layer "F.SilkS")
			(effects
				(font
					(size 0.7874 0.5842)
					(thickness 0.1524)
				)
			)
		)
		(property "Value" ""
			(at 0 0 0)
			(layer "F.Fab")
			(effects
				(font
					(size 1.27 1.27)
				)
			)
		)
		(property "Device Type" "ISL80101IRAJZ_DFN10-G222-10136A"
			(at 0.276606 2.583688 0)
			(unlocked yes)
			(layer "F.Fab")
			(hide yes)
			(effects
				(font
					(size 0.7874 0.5842)
					(thickness 0.1524)
				)
			)
		)
		(property "User Part Number" "PARTNUM*"
			(at 0.276606 3.517646 0)
			(unlocked yes)
			(layer "Cmts.User")
			(hide yes)
			(effects
				(font
					(size 0.7874 0.5842)
					(thickness 0.1524)
				)
			)
		)
		(duplicate_pad_numbers_are_jumpers no)
		(fp_line
			(start -2.290318 -1.779016)
			(end 2.290318 -1.779016)
			(stroke
				(width 0.1)
				(type default)
			)
			(layer "F.SilkS")
		)
		(fp_line
			(start -2.290318 1.779016)
			(end -2.290318 -1.779016)
			(stroke
				(width 0.1)
				(type default)
			)
			(layer "F.SilkS")
		)
		(fp_line
			(start 2.290318 -1.779016)
			(end 2.290318 1.779016)
			(stroke
				(width 0.1)
				(type default)
			)
			(layer "F.SilkS")
		)
		(fp_line
			(start 2.290318 1.779016)
			(end -2.290318 1.779016)
			(stroke
				(width 0.1)
				(type default)
			)
			(layer "F.SilkS")
		)
		(fp_poly
			(pts
				(arc
					(start -2.553462 -1.023112)
					(mid -3.315462 -1.023112)
					(end -2.553462 -1.023112)
				)
			)
			(stroke
				(width 0)
				(type default)
			)
			(fill yes)
			(layer "F.SilkS")
		)
		(fp_poly
			(pts
				(xy -0.7239 -0.1016)
				(arc
					(start -0.7239 -0.6477)
					(mid -0.290295 -0.468095)
					(end -0.4699 -0.9017)
				)
				(xy 0.7239 -0.9017) (xy 0.7239 -0.1016)
			)
			(stroke
				(width 0)
				(type default)
			)
			(fill yes)
			(layer "F.Paste")
		)
		(fp_poly
			(pts
				(xy -0.7239 0.1016) (xy 0.7239 0.1016) (xy 0.7239 0.62992)
				(arc
					(start 0.723392 0.630428)
					(mid 0.643347 0.462032)
					(end 0.4699 0.3937)
				)
				(arc
					(start 0.4699 0.3937)
					(mid 0.290295 0.468095)
					(end 0.2159 0.6477)
				)
				(arc
					(start 0.2159 0.6477)
					(mid 0.284984 0.821833)
					(end 0.45466 0.901192)
				)
				(xy 0.45466 0.9017) (xy -0.7239 0.9017)
			)
			(stroke
				(width 0)
				(type default)
			)
			(fill yes)
			(layer "F.Paste")
		)
		(fp_poly
			(pts
				(xy -2.544318 2.033016) (xy 2.544318 2.033016) (xy 2.544318 -2.033016) (xy -2.544318 -2.033016)
			)
			(stroke
				(width 0)
				(type default)
			)
			(fill no)
			(layer "F.CrtYd")
		)
		(fp_line
			(start -1.525016 -1.525016)
			(end 1.525016 -1.525016)
			(stroke
				(width 0.1)
				(type default)
			)
			(layer "F.Fab")
		)
		(fp_line
			(start -1.525016 1.525016)
			(end -1.525016 -1.525016)
			(stroke
				(width 0.1)
				(type default)
			)
			(layer "F.Fab")
		)
		(fp_line
			(start 1.525016 -1.525016)
			(end 1.525016 1.525016)
			(stroke
				(width 0.1)
				(type default)
			)
			(layer "F.Fab")
		)
		(fp_line
			(start 1.525016 1.525016)
			(end -1.525016 1.525016)
			(stroke
				(width 0.1)
				(type default)
			)
			(layer "F.Fab")
		)
		(fp_poly
			(pts
				(arc
					(start -1.664462 -1.277112)
					(mid -2.426462 -1.277112)
					(end -1.664462 -1.277112)
				)
			)
			(stroke
				(width 0)
				(type default)
			)
			(fill yes)
			(layer "F.Fab")
		)
		(fp_text user "5"
			(at -2.921 1.41097 0)
			(unlocked yes)
			(layer "F.SilkS")
			(effects
				(font
					(size 0.7874 0.5842)
					(thickness 0.1524)
				)
			)
		)
		(fp_text user "6"
			(at 2.7559 1.202182 0)
			(unlocked yes)
			(layer "F.SilkS")
			(effects
				(font
					(size 0.7874 0.5842)
					(thickness 0.1524)
				)
			)
		)
		(fp_text user "5"
			(at -2.032 1.14427 0)
			(unlocked yes)
			(layer "F.Fab")
			(effects
				(font
					(size 0.7874 0.5842)
					(thickness 0.1524)
				)
			)
		)
		(fp_text user "6"
			(at 2.032 1.14427 0)
			(unlocked yes)
			(layer "F.Fab")
			(effects
				(font
					(size 0.7874 0.5842)
					(thickness 0.1524)
				)
			)
		)
		(fp_text user "10"
			(at 2.286 -1.39573 0)
			(unlocked yes)
			(layer "F.Fab")
			(effects
				(font
					(size 0.7874 0.5842)
					(thickness 0.1524)
				)
			)
		)
		(pad "1" smd circle
			(at -1.515618 -1.000252 180)
			(size 0 0)
			(layers "F.Cu" "F.Mask" "F.Paste")
			(net "XP2R5V_FPGA")
		)
		(pad "2" smd rect
			(at -1.515618 -0.500126)
			(size 1.0414 0.3048)
			(layers "F.Cu" "F.Mask" "F.Paste")
			(net "XP2R5V_FPGA")
		)
		(pad "3" smd rect
			(at -1.515618 0)
			(size 1.0414 0.3048)
			(layers "F.Cu" "F.Mask" "F.Paste")
			(net "UNNAMED_515_ISL80101IRAJZDFN10_")
		)
		(pad "4" smd rect
			(at -1.515618 0.500126)
			(size 1.0414 0.3048)
			(layers "F.Cu" "F.Mask" "F.Paste")
			(net "UNNAMED_515_CAPACITOR_I138_1")
		)
		(pad "5" smd circle
			(at -1.515618 1.000252)
			(size 0 0)
			(layers "F.Cu" "F.Mask" "F.Paste")
			(net "SG")
		)
		(pad "6" smd circle
			(at 1.515618 1.000252)
			(size 0 0)
			(layers "F.Cu" "F.Mask" "F.Paste")
			(net "UNNAMED_515_CAPACITOR_I132_1")
		)
		(pad "7" smd rect
			(at 1.515618 0.500126)
			(size 1.0414 0.3048)
			(layers "F.Cu" "F.Mask" "F.Paste")
			(net "UNNAMED_515_CAPACITOR_I128_1")
		)
		(pad "8" smd rect
			(at 1.515618 0)
			(size 1.0414 0.3048)
			(layers "F.Cu" "F.Mask" "F.Paste")
			(net "Net_764")
		)
		(pad "9" smd rect
			(at 1.515618 -0.500126)
			(size 1.0414 0.3048)
			(layers "F.Cu" "F.Mask" "F.Paste")
			(net "UNNAMED_515_CAPACITOR_I130_1")
		)
		(pad "10" smd circle
			(at 1.515618 -1.000252 180)
			(size 0 0)
			(layers "F.Cu" "F.Mask" "F.Paste")
			(net "UNNAMED_515_CAPACITOR_I130_1")
		)
		(pad "11" smd rect
			(at 0 0)
			(size 1.4478 1.8034)
			(layers "F.Cu" "F.Mask" "F.Paste")
			(net "SG")
		)
	)
	(footprint ""
		(layer "F.Cu")
		(at 153.049986 -107.849924 -90)
		(property "Reference" "DS10"
			(at 0.026924 -1.421384 90)
			(unlocked yes)
			(layer "F.SilkS")
			(effects
				(font
					(size 0.7874 0.5842)
					(thickness 0.1524)
				)
			)
		)
		(property "Value" ""
			(at 0 0 270)
			(layer "F.Fab")
			(effects
				(font
					(size 1.27 1.27)
				)
			)
		)
		(property "Device Type" "OPTICAL-G170-10143-01"
			(at 0.1778 1.483081 270)
			(unlocked yes)
			(layer "F.Fab")
			(hide yes)
			(effects
				(font
					(size 0.786892 0.583946)
					(thickness 0.000001)
				)
			)
		)
		(property "User Part Number" "PARTNUM*"
			(at 0.1778 2.422881 270)
			(unlocked yes)
			(layer "Cmts.User")
			(hide yes)
			(effects
				(font
					(size 0.786892 0.583946)
					(thickness 0.000001)
				)
			)
		)
		(duplicate_pad_numbers_are_jumpers no)
		(fp_line
			(start -1.1938 1.0922)
			(end -2.4638 1.0922)
			(stroke
				(width 0.1)
				(type default)
			)
			(layer "F.SilkS")
		)
		(fp_line
			(start -1.397508 0.704088)
			(end -1.397508 -0.704088)
			(stroke
				(width 0.1)
				(type default)
			)
			(layer "F.SilkS")
		)
		(fp_line
			(start 1.397508 0.704088)
			(end -1.397508 0.704088)
			(stroke
				(width 0.1)
				(type default)
			)
			(layer "F.SilkS")
		)
		(fp_line
			(start -1.8288 0.4572)
			(end -1.8288 1.7272)
			(stroke
				(width 0.1)
				(type default)
			)
			(layer "F.SilkS")
		)
		(fp_line
			(start -1.397508 -0.704088)
			(end 1.397508 -0.704088)
			(stroke
				(width 0.1)
				(type default)
			)
			(layer "F.SilkS")
		)
		(fp_line
			(start 1.397508 -0.704088)
			(end 1.397508 0.704088)
			(stroke
				(width 0.1)
				(type default)
			)
			(layer "F.SilkS")
		)
		(fp_rect
			(start 1.905508 0.704088)
			(end 1.397508 -0.704088)
			(stroke
				(width 0)
				(type default)
			)
			(fill yes)
			(layer "F.SilkS")
		)
		(fp_rect
			(start 1.905508 0.958088)
			(end -1.651508 -0.958088)
			(stroke
				(width 0)
				(type default)
			)
			(fill no)
			(layer "F.CrtYd")
		)
		(fp_line
			(start -1.0668 1.2192)
			(end -2.3368 1.2192)
			(stroke
				(width 0.1)
				(type default)
			)
			(layer "F.Fab")
		)
		(fp_line
			(start -1.7018 0.5842)
			(end -1.7018 1.8542)
			(stroke
				(width 0.1)
				(type default)
			)
			(layer "F.Fab")
		)
		(fp_line
			(start -0.850138 0.450088)
			(end 0.850138 0.450088)
			(stroke
				(width 0.1)
				(type default)
			)
			(layer "F.Fab")
		)
		(fp_line
			(start 0.850138 0.450088)
			(end 0.850138 -0.450088)
			(stroke
				(width 0.1)
				(type default)
			)
			(layer "F.Fab")
		)
		(fp_line
			(start -0.850138 -0.450088)
			(end -0.850138 0.450088)
			(stroke
				(width 0.1)
				(type default)
			)
			(layer "F.Fab")
		)
		(fp_line
			(start 0.850138 -0.450088)
			(end -0.850138 -0.450088)
			(stroke
				(width 0.1)
				(type default)
			)
			(layer "F.Fab")
		)
		(fp_rect
			(start 0.850138 0.450088)
			(end 0.342138 -0.450088)
			(stroke
				(width 0)
				(type default)
			)
			(fill yes)
			(layer "F.Fab")
		)
		(fp_text user "C"
			(at 1.404874 1.284986 0)
			(unlocked yes)
			(layer "F.SilkS")
			(effects
				(font
					(size 0.635 0.4064)
					(thickness 0.1524)
				)
			)
		)
		(fp_text user "A"
			(at -1.846326 0.014986 0)
			(unlocked yes)
			(layer "F.SilkS")
			(effects
				(font
					(size 0.635 0.4064)
					(thickness 0.1524)
				)
			)
		)
		(fp_text user "A"
			(at -2.346706 0.141986 0)
			(unlocked yes)
			(layer "F.Fab")
			(effects
				(font
					(size 0.7874 0.5842)
					(thickness 0.1524)
				)
			)
		)
		(fp_text user "C"
			(at 0.828294 -1.001014 0)
			(unlocked yes)
			(layer "F.Fab")
			(effects
				(font
					(size 0.7874 0.5842)
					(thickness 0.1524)
				)
			)
		)
		(pad "A" smd rect
			(at -0.749808 0 270)
			(size 0.7874 0.7874)
			(layers "F.Cu" "F.Mask" "F.Paste")
			(net "UNNAMED_14_OPTICAL_I138_A")
		)
		(pad "C" smd rect
			(at 0.749808 0 270)
			(size 0.7874 0.7874)
			(layers "F.Cu" "F.Mask" "F.Paste")
			(net "FPGA_USR_LED1")
		)
	)
	(footprint ""
		(layer "F.Cu")
		(at 113.157 -68.707 -90)
		(property "Reference" "C232"
			(at -0.381 -2.96037 90)
			(unlocked yes)
			(layer "F.SilkS")
			(effects
				(font
					(size 0.7874 0.5842)
					(thickness 0.1524)
				)
			)
		)
		(property "Value" "VAL*"
			(at 0.0762 3.134106 270)
			(unlocked yes)
			(layer "F.Fab")
			(hide yes)
			(effects
				(font
					(size 0.7874 0.5842)
					(thickness 0.1524)
				)
			)
		)
		(property "Tolerance" "TOL*"
			(at 0.0762 4.048506 270)
			(unlocked yes)
			(layer "Cmts.User")
			(hide yes)
			(effects
				(font
					(size 0.7874 0.5842)
					(thickness 0.1524)
				)
			)
		)
		(property "User Part Number" "PARTNUM*"
			(at 0.1016 5.013706 270)
			(unlocked yes)
			(layer "Cmts.User")
			(hide yes)
			(effects
				(font
					(size 0.7874 0.5842)
					(thickness 0.1524)
				)
			)
		)
		(property "Device Type" "CAPACITOR-G107-0F226-CM,22UF,2A"
			(at 0.0508 2.194306 270)
			(unlocked yes)
			(layer "F.Fab")
			(hide yes)
			(effects
				(font
					(size 0.7874 0.5842)
					(thickness 0.1524)
				)
			)
		)
		(duplicate_pad_numbers_are_jumpers no)
		(fp_line
			(start -1.5748 0.9398)
			(end 1.5748 0.9398)
			(stroke
				(width 0.1)
				(type default)
			)
			(layer "F.SilkS")
		)
		(fp_line
			(start 1.5748 0.9398)
			(end 1.5748 -0.9398)
			(stroke
				(width 0.1)
				(type default)
			)
			(layer "F.SilkS")
		)
		(fp_line
			(start -1.5748 -0.9398)
			(end -1.5748 0.9398)
			(stroke
				(width 0.1)
				(type default)
			)
			(layer "F.SilkS")
		)
		(fp_line
			(start 1.5748 -0.9398)
			(end -1.5748 -0.9398)
			(stroke
				(width 0.1)
				(type default)
			)
			(layer "F.SilkS")
		)
		(fp_rect
			(start 1.5748 -0.9398)
			(end -1.5748 0.9398)
			(stroke
				(width 0)
				(type default)
			)
			(fill no)
			(layer "F.CrtYd")
		)
		(fp_line
			(start -1.016 0.635)
			(end 1.016 0.635)
			(stroke
				(width 0.1)
				(type default)
			)
			(layer "F.Fab")
		)
		(fp_line
			(start 1.016 0.635)
			(end 1.016 -0.635)
			(stroke
				(width 0.1)
				(type default)
			)
			(layer "F.Fab")
		)
		(fp_line
			(start -1.016 -0.635)
			(end -1.016 0.635)
			(stroke
				(width 0.1)
				(type default)
			)
			(layer "F.Fab")
		)
		(fp_line
			(start 1.016 -0.635)
			(end -1.016 -0.635)
			(stroke
				(width 0.1)
				(type default)
			)
			(layer "F.Fab")
		)
		(pad "1" smd rect
			(at -0.8382 0 270)
			(size 0.9652 1.3716)
			(layers "F.Cu" "F.Mask" "F.Paste")
			(net "XP3R3V")
		)
		(pad "2" smd rect
			(at 0.8382 0 270)
			(size 0.9652 1.3716)
			(layers "F.Cu" "F.Mask" "F.Paste")
			(net "SG")
		)
		(zone
			(layer "F.Cu")
			(hatch none 0.5)
			(connect_pads
				(clearance 0)
			)
			(min_thickness 0.25)
			(keepout
				(tracks allowed)
				(vias not_allowed)
				(pads allowed)
				(copperpour not_allowed)
				(footprints allowed)
			)
			(placement
				(enabled no)
				(sheetname "")
			)
			(fill
				(thermal_gap 0.5)
				(thermal_bridge_width 0.5)
				(island_removal_mode 0)
			)
			(polygon
				(pts
					(xy 113.792 -68.4784) (xy 113.792 -68.9356) (xy 112.522 -68.9356) (xy 112.522 -68.4784)
				)
			)
		)
	)
	(footprint ""
		(layer "F.Cu")
		(at 133.858 -22.098 180)
		(property "Reference" "R484"
			(at 0.127 5.04063 0)
			(unlocked yes)
			(layer "F.SilkS")
			(effects
				(font
					(size 0.7874 0.5842)
					(thickness 0.1524)
				)
			)
		)
		(property "Value" "VAL*"
			(at 0.02032 2.13233 180)
			(unlocked yes)
			(layer "F.Fab")
			(hide yes)
			(effects
				(font
					(size 0.7874 0.5842)
					(thickness 0.1524)
				)
			)
		)
		(property "Tolerance" "TOL*"
			(at 0.044704 3.05435 180)
			(unlocked yes)
			(layer "Cmts.User")
			(hide yes)
			(effects
				(font
					(size 0.7874 0.5842)
					(thickness 0.1524)
				)
			)
		)
		(property "User Part Number" "PARTNUM*"
			(at 0.02032 4.024884 180)
			(unlocked yes)
			(layer "Cmts.User")
			(hide yes)
			(effects
				(font
					(size 0.7874 0.5842)
					(thickness 0.1524)
				)
			)
		)
		(property "Device Type" "RESISTOR-G155-11001-01,1KOHM,1%"
			(at 0.008382 1.210564 180)
			(unlocked yes)
			(layer "F.Fab")
			(hide yes)
			(effects
				(font
					(size 0.7874 0.5842)
					(thickness 0.1524)
				)
			)
		)
		(duplicate_pad_numbers_are_jumpers no)
		(fp_line
			(start 1.143 0.5588)
			(end 1.143 -0.5588)
			(stroke
				(width 0.1)
				(type default)
			)
			(layer "F.SilkS")
		)
		(fp_line
			(start 1.143 -0.5588)
			(end -1.143 -0.5588)
			(stroke
				(width 0.1)
				(type default)
			)
			(layer "F.SilkS")
		)
		(fp_line
			(start -1.143 0.5588)
			(end 1.143 0.5588)
			(stroke
				(width 0.1)
				(type default)
			)
			(layer "F.SilkS")
		)
		(fp_line
			(start -1.143 -0.5588)
			(end -1.143 0.5588)
			(stroke
				(width 0.1)
				(type default)
			)
			(layer "F.SilkS")
		)
		(fp_poly
			(pts
				(xy -1.143 0.5588) (xy 1.143 0.5588) (xy 1.143 -0.5588) (xy -1.143 -0.5588)
			)
			(stroke
				(width 0)
				(type default)
			)
			(fill no)
			(layer "F.CrtYd")
		)
		(fp_line
			(start 0.508 0.3048)
			(end 0.508 -0.3048)
			(stroke
				(width 0.1)
				(type default)
			)
			(layer "F.Fab")
		)
		(fp_line
			(start 0.508 -0.3048)
			(end -0.508 -0.3048)
			(stroke
				(width 0.1)
				(type default)
			)
			(layer "F.Fab")
		)
		(fp_line
			(start -0.508 0.3048)
			(end 0.508 0.3048)
			(stroke
				(width 0.1)
				(type default)
			)
			(layer "F.Fab")
		)
		(fp_line
			(start -0.508 -0.3048)
			(end -0.508 0.3048)
			(stroke
				(width 0.1)
				(type default)
			)
			(layer "F.Fab")
		)
		(pad "1" smd rect
			(at -0.5334 0 180)
			(size 0.7112 0.6096)
			(layers "F.Cu" "F.Mask" "F.Paste")
			(net "SG")
		)
		(pad "2" smd rect
			(at 0.5334 0 180)
			(size 0.7112 0.6096)
			(layers "F.Cu" "F.Mask" "F.Paste")
			(net "UNNAMED_524_RESISTOR_I463_2")
		)
		(zone
			(layer "F.Cu")
			(hatch none 0.5)
			(connect_pads
				(clearance 0)
			)
			(min_thickness 0.25)
			(keepout
				(tracks allowed)
				(vias not_allowed)
				(pads allowed)
				(copperpour not_allowed)
				(footprints allowed)
			)
			(placement
				(enabled no)
				(sheetname "")
			)
			(fill
				(thermal_gap 0.5)
				(thermal_bridge_width 0.5)
				(island_removal_mode 0)
			)
			(polygon
				(pts
					(xy 133.9342 -22.4028) (xy 133.7818 -22.4028) (xy 133.7818 -21.7932) (xy 133.9342 -21.7932)
				)
			)
		)
		(zone
			(layer "F.Cu")
			(hatch none 0.5)
			(connect_pads
				(clearance 0)
			)
			(min_thickness 0.25)
			(keepout
				(tracks not_allowed)
				(vias allowed)
				(pads allowed)
				(copperpour not_allowed)
				(footprints allowed)
			)
			(placement
				(enabled no)
				(sheetname "")
			)
			(fill
				(thermal_gap 0.5)
				(thermal_bridge_width 0.5)
				(island_removal_mode 0)
			)
			(polygon
				(pts
					(xy 133.9342 -22.4028) (xy 133.7818 -22.4028) (xy 133.7818 -21.7932) (xy 133.9342 -21.7932)
				)
			)
		)
	)
	(footprint ""
		(layer "F.Cu")
		(at 146.304 -53.848 -90)
		(property "Reference" "C257"
			(at 1.27 -2.70637 90)
			(unlocked yes)
			(layer "F.SilkS")
			(effects
				(font
					(size 0.7874 0.5842)
					(thickness 0.1524)
				)
			)
		)
		(property "Value" "VAL*"
			(at 0.0762 3.134106 270)
			(unlocked yes)
			(layer "F.Fab")
			(hide yes)
			(effects
				(font
					(size 0.7874 0.5842)
					(thickness 0.1524)
				)
			)
		)
		(property "Device Type" "CAPACITOR-G107-0F106-EM,10UF,2A"
			(at 0.0508 2.194306 270)
			(unlocked yes)
			(layer "F.Fab")
			(hide yes)
			(effects
				(font
					(size 0.7874 0.5842)
					(thickness 0.1524)
				)
			)
		)
		(property "User Part Number" "PARTNUM*"
			(at 0.1016 5.013706 270)
			(unlocked yes)
			(layer "Cmts.User")
			(hide yes)
			(effects
				(font
					(size 0.7874 0.5842)
					(thickness 0.1524)
				)
			)
		)
		(property "Tolerance" "TOL*"
			(at 0.0762 4.048506 270)
			(unlocked yes)
			(layer "Cmts.User")
			(hide yes)
			(effects
				(font
					(size 0.7874 0.5842)
					(thickness 0.1524)
				)
			)
		)
		(duplicate_pad_numbers_are_jumpers no)
		(fp_line
			(start -1.5748 0.9398)
			(end 1.5748 0.9398)
			(stroke
				(width 0.1)
				(type default)
			)
			(layer "F.SilkS")
		)
		(fp_line
			(start 1.5748 0.9398)
			(end 1.5748 -0.9398)
			(stroke
				(width 0.1)
				(type default)
			)
			(layer "F.SilkS")
		)
		(fp_line
			(start -1.5748 -0.9398)
			(end -1.5748 0.9398)
			(stroke
				(width 0.1)
				(type default)
			)
			(layer "F.SilkS")
		)
		(fp_line
			(start 1.5748 -0.9398)
			(end -1.5748 -0.9398)
			(stroke
				(width 0.1)
				(type default)
			)
			(layer "F.SilkS")
		)
		(fp_rect
			(start 1.5748 0.9398)
			(end -1.5748 -0.9398)
			(stroke
				(width 0)
				(type default)
			)
			(fill no)
			(layer "F.CrtYd")
		)
		(fp_line
			(start -1.016 0.635)
			(end 1.016 0.635)
			(stroke
				(width 0.1)
				(type default)
			)
			(layer "F.Fab")
		)
		(fp_line
			(start 1.016 0.635)
			(end 1.016 -0.635)
			(stroke
				(width 0.1)
				(type default)
			)
			(layer "F.Fab")
		)
		(fp_line
			(start -1.016 -0.635)
			(end -1.016 0.635)
			(stroke
				(width 0.1)
				(type default)
			)
			(layer "F.Fab")
		)
		(fp_line
			(start 1.016 -0.635)
			(end -1.016 -0.635)
			(stroke
				(width 0.1)
				(type default)
			)
			(layer "F.Fab")
		)
		(pad "1" smd rect
			(at -0.8382 0 270)
			(size 0.9652 1.3716)
			(layers "F.Cu" "F.Mask" "F.Paste")
			(net "VIN_XP1R0V")
		)
		(pad "2" smd rect
			(at 0.8382 0 270)
			(size 0.9652 1.3716)
			(layers "F.Cu" "F.Mask" "F.Paste")
			(net "SG")
		)
		(zone
			(layer "F.Cu")
			(hatch none 0.5)
			(connect_pads
				(clearance 0)
			)
			(min_thickness 0.25)
			(keepout
				(tracks allowed)
				(vias not_allowed)
				(pads allowed)
				(copperpour not_allowed)
				(footprints allowed)
			)
			(placement
				(enabled no)
				(sheetname "")
			)
			(fill
				(thermal_gap 0.5)
				(thermal_bridge_width 0.5)
				(island_removal_mode 0)
			)
			(polygon
				(pts
					(xy 145.669 -53.6194) (xy 146.939 -53.6194) (xy 146.939 -54.0766) (xy 145.669 -54.0766)
				)
			)
		)
	)
	(footprint ""
		(layer "F.Cu")
		(at 100.3808 -70.4596)
		(property "Reference" "C192"
			(at 2.7432 0.14097 0)
			(unlocked yes)
			(layer "F.SilkS")
			(effects
				(font
					(size 0.7874 0.5842)
					(thickness 0.1524)
				)
			)
		)
		(property "Value" "VAL*"
			(at 0.193548 2.13614 0)
			(unlocked yes)
			(layer "F.Fab")
			(hide yes)
			(effects
				(font
					(size 0.7874 0.5842)
					(thickness 0.1524)
				)
			)
		)
		(property "User Part Number" "PARTNUM*"
			(at 0.216154 4.185666 0)
			(unlocked yes)
			(layer "Cmts.User")
			(hide yes)
			(effects
				(font
					(size 0.7874 0.5842)
					(thickness 0.1524)
				)
			)
		)
		(property "Device Type" "CAPACITOR-G104-0B103-EK,0.01UFA"
			(at 0.184404 1.180592 0)
			(unlocked yes)
			(layer "F.Fab")
			(hide yes)
			(effects
				(font
					(size 0.7874 0.5842)
					(thickness 0.1524)
				)
			)
		)
		(property "Tolerance" "TOL*"
			(at 0.216154 3.1496 0)
			(unlocked yes)
			(layer "Cmts.User")
			(hide yes)
			(effects
				(font
					(size 0.7874 0.5842)
					(thickness 0.1524)
				)
			)
		)
		(duplicate_pad_numbers_are_jumpers no)
		(fp_line
			(start -0.671322 -0.4445)
			(end 0.671322 -0.4445)
			(stroke
				(width 0.1)
				(type default)
			)
			(layer "F.SilkS")
		)
		(fp_line
			(start -0.671322 0.4445)
			(end -0.671322 -0.4445)
			(stroke
				(width 0.1)
				(type default)
			)
			(layer "F.SilkS")
		)
		(fp_line
			(start 0.671322 -0.4445)
			(end 0.671322 0.4445)
			(stroke
				(width 0.1)
				(type default)
			)
			(layer "F.SilkS")
		)
		(fp_line
			(start 0.671322 0.4445)
			(end -0.671322 0.4445)
			(stroke
				(width 0.1)
				(type default)
			)
			(layer "F.SilkS")
		)
		(fp_rect
			(start -0.671322 -0.4445)
			(end 0.671322 0.4445)
			(stroke
				(width 0)
				(type default)
			)
			(fill no)
			(layer "F.CrtYd")
		)
		(fp_line
			(start -0.31496 -0.1651)
			(end -0.31496 0.1651)
			(stroke
				(width 0.1)
				(type default)
			)
			(layer "F.Fab")
		)
		(fp_line
			(start -0.31496 0.1651)
			(end 0.31496 0.1651)
			(stroke
				(width 0.1)
				(type default)
			)
			(layer "F.Fab")
		)
		(fp_line
			(start 0.31496 -0.1651)
			(end -0.31496 -0.1651)
			(stroke
				(width 0.1)
				(type default)
			)
			(layer "F.Fab")
		)
		(fp_line
			(start 0.31496 0.1651)
			(end 0.31496 -0.1651)
			(stroke
				(width 0.1)
				(type default)
			)
			(layer "F.Fab")
		)
		(pad "1" smd rect
			(at -0.264922 0)
			(size 0.3048 0.381)
			(layers "F.Cu" "F.Mask" "F.Paste")
			(net "XP1R2V_PG_R")
		)
		(pad "2" smd rect
			(at 0.264922 0)
			(size 0.3048 0.381)
			(layers "F.Cu" "F.Mask" "F.Paste")
			(net "SG")
		)
		(zone
			(layer "F.Cu")
			(hatch none 0.5)
			(connect_pads
				(clearance 0)
			)
			(min_thickness 0.25)
			(keepout
				(tracks allowed)
				(vias not_allowed)
				(pads allowed)
				(copperpour not_allowed)
				(footprints allowed)
			)
			(placement
				(enabled no)
				(sheetname "")
			)
			(fill
				(thermal_gap 0.5)
				(thermal_bridge_width 0.5)
				(island_removal_mode 0)
			)
			(polygon
				(pts
					(xy 100.268278 -70.6501) (xy 100.268278 -70.2691) (xy 100.493322 -70.2691) (xy 100.493322 -70.6501)
				)
			)
		)
	)
	(footprint ""
		(layer "F.Cu")
		(at 4.073906 -47.099982)
		(property "Reference" "J4"
			(at 4.816094 -2.390648 0)
			(unlocked yes)
			(layer "F.SilkS")
			(effects
				(font
					(size 0.7874 0.5842)
					(thickness 0.1524)
				)
			)
		)
		(property "Value" ""
			(at 0 0 0)
			(layer "F.Fab")
			(effects
				(font
					(size 1.27 1.27)
				)
			)
		)
		(property "Device Type" "CONN_JACK_1P_GH4_S_TH-G200-130A"
			(at -5.098288 5.899912 0)
			(unlocked yes)
			(layer "F.Fab")
			(hide yes)
			(effects
				(font
					(size 0.7874 0.5842)
					(thickness 0.1524)
				)
			)
		)
		(property "User Part Number" "PARTNUM*"
			(at -5.098288 7.093712 0)
			(unlocked yes)
			(layer "Cmts.User")
			(hide yes)
			(effects
				(font
					(size 0.7874 0.5842)
					(thickness 0.1524)
				)
			)
		)
		(duplicate_pad_numbers_are_jumpers no)
		(fp_line
			(start -13.953998 -3.937)
			(end 3.937 -3.937)
			(stroke
				(width 0.1)
				(type default)
			)
			(layer "F.SilkS")
		)
		(fp_line
			(start -13.953998 3.937)
			(end -13.953998 -3.937)
			(stroke
				(width 0.1)
				(type default)
			)
			(layer "F.SilkS")
		)
		(fp_line
			(start 3.937 -3.937)
			(end 3.937 3.937)
			(stroke
				(width 0.1)
				(type default)
			)
			(layer "F.SilkS")
		)
		(fp_line
			(start 3.937 3.937)
			(end -13.953998 3.937)
			(stroke
				(width 0.1)
				(type default)
			)
			(layer "F.SilkS")
		)
		(fp_rect
			(start -8.763 8.763)
			(end 8.763 -8.763)
			(stroke
				(width 0)
				(type default)
			)
			(fill no)
			(layer "B.CrtYd")
		)
		(fp_rect
			(start -14.207998 4.191)
			(end 4.191 -4.191)
			(stroke
				(width 0)
				(type default)
			)
			(fill no)
			(layer "F.CrtYd")
		)
		(fp_line
			(start -13.699998 -3.599942)
			(end 3.599942 -3.599942)
			(stroke
				(width 0.1)
				(type default)
			)
			(layer "F.Fab")
		)
		(fp_line
			(start -13.699998 3.599942)
			(end -13.699998 -3.599942)
			(stroke
				(width 0.1)
				(type default)
			)
			(layer "F.Fab")
		)
		(fp_line
			(start 3.599942 -3.599942)
			(end 3.599942 3.599942)
			(stroke
				(width 0.1)
				(type default)
			)
			(layer "F.Fab")
		)
		(fp_line
			(start 3.599942 3.599942)
			(end -13.699998 3.599942)
			(stroke
				(width 0.1)
				(type default)
			)
			(layer "F.Fab")
		)
		(fp_text user "GH3"
			(at -1.660906 4.332732 0)
			(unlocked yes)
			(layer "F.SilkS")
			(effects
				(font
					(size 0.635 0.4064)
					(thickness 0.1524)
				)
			)
		)
		(fp_text user "GH1"
			(at -0.263906 -4.227068 0)
			(unlocked yes)
			(layer "F.SilkS")
			(effects
				(font
					(size 0.635 0.4064)
					(thickness 0.1524)
				)
			)
		)
		(fp_text user "GH2"
			(at 2.911094 -4.354068 0)
			(unlocked yes)
			(layer "F.SilkS")
			(effects
				(font
					(size 0.635 0.4064)
					(thickness 0.1524)
				)
			)
		)
		(fp_text user "1"
			(at 4.015994 -0.104648 0)
			(unlocked yes)
			(layer "F.SilkS")
			(effects
				(font
					(size 0.7874 0.5842)
					(thickness 0.1524)
				)
				(justify left)
			)
		)
		(fp_text user "GH4"
			(at 4.466844 3.284982 90)
			(unlocked yes)
			(layer "F.SilkS")
			(effects
				(font
					(size 0.635 0.4064)
					(thickness 0.1524)
				)
			)
		)
		(fp_text user "GH1"
			(at -2.549906 -4.295648 0)
			(unlocked yes)
			(layer "F.Fab")
			(effects
				(font
					(size 0.7874 0.5842)
					(thickness 0.1524)
				)
			)
		)
		(fp_text user "GH3"
			(at -2.549906 4.215638 0)
			(unlocked yes)
			(layer "F.Fab")
			(effects
				(font
					(size 0.7874 0.5842)
					(thickness 0.1524)
				)
			)
		)
		(fp_text user "GH2"
			(at 2.149094 -4.168648 0)
			(unlocked yes)
			(layer "F.Fab")
			(effects
				(font
					(size 0.7874 0.5842)
					(thickness 0.1524)
				)
			)
		)
		(fp_text user "GH4"
			(at 2.54 4.64947 0)
			(unlocked yes)
			(layer "F.Fab")
			(effects
				(font
					(size 0.7874 0.5842)
					(thickness 0.1524)
				)
			)
		)
		(fp_text user "1"
			(at 3.800094 -0.356362 0)
			(unlocked yes)
			(layer "F.Fab")
			(effects
				(font
					(size 0.7874 0.5842)
					(thickness 0.1524)
				)
				(justify left)
			)
		)
		(pad "1" thru_hole circle
			(at 0 0)
			(size 2.1844 2.1844)
			(drill 1.4986)
			(layers "*.Cu" "*.Mask")
			(remove_unused_layers no)
			(net "SMA2_SIG_IO_CONN")
			(padstack
				(mode front_inner_back)
				(layer "Inner"
					(shape circle)
					(size 2.1844 2.1844)
					(clearance -0.0508)
				)
				(layer "B.Cu"
					(shape circle)
					(size 2.1844 2.1844)
				)
			)
		)
		(pad "GH1" thru_hole circle
			(at -2.54 -2.54)
			(size 2.286 2.286)
			(drill 1.6002)
			(layers "*.Cu" "*.Mask")
			(remove_unused_layers no)
			(net "SG")
			(padstack
				(mode front_inner_back)
				(layer "Inner"
					(shape circle)
					(size 2.286 2.286)
					(clearance -0.0508)
				)
				(layer "B.Cu"
					(shape circle)
					(size 2.286 2.286)
				)
			)
		)
		(pad "GH2" thru_hole circle
			(at 2.54 -2.54)
			(size 2.286 2.286)
			(drill 1.6002)
			(layers "*.Cu" "*.Mask")
			(remove_unused_layers no)
			(net "SG")
			(padstack
				(mode front_inner_back)
				(layer "Inner"
					(shape circle)
					(size 2.286 2.286)
					(clearance -0.0508)
				)
				(layer "B.Cu"
					(shape circle)
					(size 2.286 2.286)
				)
			)
		)
		(pad "GH3" thru_hole circle
			(at -2.54 2.54)
			(size 2.286 2.286)
			(drill 1.6002)
			(layers "*.Cu" "*.Mask")
			(remove_unused_layers no)
			(net "SG")
			(padstack
				(mode front_inner_back)
				(layer "Inner"
					(shape circle)
					(size 2.286 2.286)
					(clearance -0.0508)
				)
				(layer "B.Cu"
					(shape circle)
					(size 2.286 2.286)
				)
			)
		)
		(pad "GH4" thru_hole circle
			(at 2.54 2.54)
			(size 2.286 2.286)
			(drill 1.6002)
			(layers "*.Cu" "*.Mask")
			(remove_unused_layers no)
			(net "SG")
			(padstack
				(mode front_inner_back)
				(layer "Inner"
					(shape circle)
					(size 2.286 2.286)
					(clearance -0.0508)
				)
				(layer "B.Cu"
					(shape circle)
					(size 2.286 2.286)
				)
			)
		)
	)
	(footprint ""
		(layer "F.Cu")
		(at 33.7693 -16.7132 180)
		(property "Reference" "R312"
			(at -2.6543 -2.07137 0)
			(unlocked yes)
			(layer "F.SilkS")
			(effects
				(font
					(size 0.7874 0.5842)
					(thickness 0.1524)
				)
			)
		)
		(property "Value" "VAL*"
			(at 0.02032 2.13233 180)
			(unlocked yes)
			(layer "F.Fab")
			(hide yes)
			(effects
				(font
					(size 0.7874 0.5842)
					(thickness 0.1524)
				)
			)
		)
		(property "Device Type" "RESISTOR-G155-100R0-J0,0OHM,-"
			(at 0.008382 1.210564 180)
			(unlocked yes)
			(layer "F.Fab")
			(hide yes)
			(effects
				(font
					(size 0.7874 0.5842)
					(thickness 0.1524)
				)
			)
		)
		(property "User Part Number" "PARTNUM*"
			(at 0.02032 4.024884 180)
			(unlocked yes)
			(layer "Cmts.User")
			(hide yes)
			(effects
				(font
					(size 0.7874 0.5842)
					(thickness 0.1524)
				)
			)
		)
		(property "Tolerance" "TOL*"
			(at 0.044704 3.05435 180)
			(unlocked yes)
			(layer "Cmts.User")
			(hide yes)
			(effects
				(font
					(size 0.7874 0.5842)
					(thickness 0.1524)
				)
			)
		)
		(duplicate_pad_numbers_are_jumpers no)
		(fp_line
			(start 1.143 0.5588)
			(end 1.143 -0.5588)
			(stroke
				(width 0.1)
				(type default)
			)
			(layer "F.SilkS")
		)
		(fp_line
			(start 1.143 -0.5588)
			(end -1.143 -0.5588)
			(stroke
				(width 0.1)
				(type default)
			)
			(layer "F.SilkS")
		)
		(fp_line
			(start -1.143 0.5588)
			(end 1.143 0.5588)
			(stroke
				(width 0.1)
				(type default)
			)
			(layer "F.SilkS")
		)
		(fp_line
			(start -1.143 -0.5588)
			(end -1.143 0.5588)
			(stroke
				(width 0.1)
				(type default)
			)
			(layer "F.SilkS")
		)
		(fp_poly
			(pts
				(xy -1.143 0.5588) (xy 1.143 0.5588) (xy 1.143 -0.5588) (xy -1.143 -0.5588)
			)
			(stroke
				(width 0)
				(type default)
			)
			(fill no)
			(layer "F.CrtYd")
		)
		(fp_line
			(start 0.508 0.3048)
			(end 0.508 -0.3048)
			(stroke
				(width 0.1)
				(type default)
			)
			(layer "F.Fab")
		)
		(fp_line
			(start 0.508 -0.3048)
			(end -0.508 -0.3048)
			(stroke
				(width 0.1)
				(type default)
			)
			(layer "F.Fab")
		)
		(fp_line
			(start -0.508 0.3048)
			(end 0.508 0.3048)
			(stroke
				(width 0.1)
				(type default)
			)
			(layer "F.Fab")
		)
		(fp_line
			(start -0.508 -0.3048)
			(end -0.508 0.3048)
			(stroke
				(width 0.1)
				(type default)
			)
			(layer "F.Fab")
		)
		(pad "1" smd rect
			(at -0.5334 0 180)
			(size 0.7112 0.6096)
			(layers "F.Cu" "F.Mask" "F.Paste")
			(net "RGB_LED_I2C_SDA")
		)
		(pad "2" smd rect
			(at 0.5334 0 180)
			(size 0.7112 0.6096)
			(layers "F.Cu" "F.Mask" "F.Paste")
			(net "EEPROM_SDA")
		)
		(zone
			(layer "F.Cu")
			(hatch none 0.5)
			(connect_pads
				(clearance 0)
			)
			(min_thickness 0.25)
			(keepout
				(tracks allowed)
				(vias not_allowed)
				(pads allowed)
				(copperpour not_allowed)
				(footprints allowed)
			)
			(placement
				(enabled no)
				(sheetname "")
			)
			(fill
				(thermal_gap 0.5)
				(thermal_bridge_width 0.5)
				(island_removal_mode 0)
			)
			(polygon
				(pts
					(xy 33.8455 -17.018) (xy 33.6931 -17.018) (xy 33.6931 -16.4084) (xy 33.8455 -16.4084)
				)
			)
		)
		(zone
			(layer "F.Cu")
			(hatch none 0.5)
			(connect_pads
				(clearance 0)
			)
			(min_thickness 0.25)
			(keepout
				(tracks not_allowed)
				(vias allowed)
				(pads allowed)
				(copperpour not_allowed)
				(footprints allowed)
			)
			(placement
				(enabled no)
				(sheetname "")
			)
			(fill
				(thermal_gap 0.5)
				(thermal_bridge_width 0.5)
				(island_removal_mode 0)
			)
			(polygon
				(pts
					(xy 33.8455 -17.018) (xy 33.6931 -17.018) (xy 33.6931 -16.4084) (xy 33.8455 -16.4084)
				)
			)
		)
	)
	(footprint ""
		(layer "F.Cu")
		(at 86.36 -93.599 90)
		(property "Reference" "C22"
			(at -3.81 -4.78663 90)
			(unlocked yes)
			(layer "F.SilkS")
			(effects
				(font
					(size 0.7874 0.5842)
					(thickness 0.1524)
				)
			)
		)
		(property "Value" "VAL*"
			(at 0.0762 3.134106 90)
			(unlocked yes)
			(layer "F.Fab")
			(hide yes)
			(effects
				(font
					(size 0.7874 0.5842)
					(thickness 0.1524)
				)
			)
		)
		(property "Tolerance" "TOL*"
			(at 0.0762 4.048506 90)
			(unlocked yes)
			(layer "Cmts.User")
			(hide yes)
			(effects
				(font
					(size 0.7874 0.5842)
					(thickness 0.1524)
				)
			)
		)
		(property "User Part Number" "PARTNUM*"
			(at 0.1016 5.013706 90)
			(unlocked yes)
			(layer "Cmts.User")
			(hide yes)
			(effects
				(font
					(size 0.7874 0.5842)
					(thickness 0.1524)
				)
			)
		)
		(property "Device Type" "CAPACITOR-G107-0F226-CM,22UF,2A"
			(at 0.0508 2.194306 90)
			(unlocked yes)
			(layer "F.Fab")
			(hide yes)
			(effects
				(font
					(size 0.7874 0.5842)
					(thickness 0.1524)
				)
			)
		)
		(duplicate_pad_numbers_are_jumpers no)
		(fp_line
			(start 1.5748 -0.9398)
			(end -1.5748 -0.9398)
			(stroke
				(width 0.1)
				(type default)
			)
			(layer "F.SilkS")
		)
		(fp_line
			(start -1.5748 -0.9398)
			(end -1.5748 0.9398)
			(stroke
				(width 0.1)
				(type default)
			)
			(layer "F.SilkS")
		)
		(fp_line
			(start 1.5748 0.9398)
			(end 1.5748 -0.9398)
			(stroke
				(width 0.1)
				(type default)
			)
			(layer "F.SilkS")
		)
		(fp_line
			(start -1.5748 0.9398)
			(end 1.5748 0.9398)
			(stroke
				(width 0.1)
				(type default)
			)
			(layer "F.SilkS")
		)
		(fp_rect
			(start 1.5748 0.9398)
			(end -1.5748 -0.9398)
			(stroke
				(width 0)
				(type default)
			)
			(fill no)
			(layer "F.CrtYd")
		)
		(fp_line
			(start 1.016 -0.635)
			(end -1.016 -0.635)
			(stroke
				(width 0.1)
				(type default)
			)
			(layer "F.Fab")
		)
		(fp_line
			(start -1.016 -0.635)
			(end -1.016 0.635)
			(stroke
				(width 0.1)
				(type default)
			)
			(layer "F.Fab")
		)
		(fp_line
			(start 1.016 0.635)
			(end 1.016 -0.635)
			(stroke
				(width 0.1)
				(type default)
			)
			(layer "F.Fab")
		)
		(fp_line
			(start -1.016 0.635)
			(end 1.016 0.635)
			(stroke
				(width 0.1)
				(type default)
			)
			(layer "F.Fab")
		)
		(pad "1" smd rect
			(at -0.8382 0 90)
			(size 0.9652 1.3716)
			(layers "F.Cu" "F.Mask" "F.Paste")
			(net "XP3R3V")
		)
		(pad "2" smd rect
			(at 0.8382 0 90)
			(size 0.9652 1.3716)
			(layers "F.Cu" "F.Mask" "F.Paste")
			(net "SG")
		)
		(zone
			(layer "F.Cu")
			(hatch none 0.5)
			(connect_pads
				(clearance 0)
			)
			(min_thickness 0.25)
			(keepout
				(tracks allowed)
				(vias not_allowed)
				(pads allowed)
				(copperpour not_allowed)
				(footprints allowed)
			)
			(placement
				(enabled no)
				(sheetname "")
			)
			(fill
				(thermal_gap 0.5)
				(thermal_bridge_width 0.5)
				(island_removal_mode 0)
			)
			(polygon
				(pts
					(xy 86.995 -93.8276) (xy 85.725 -93.8276) (xy 85.725 -93.3704) (xy 86.995 -93.3704)
				)
			)
		)
	)
	(footprint ""
		(layer "F.Cu")
		(at 7.500112 -94.749874)
		(property "Reference" "ME9"
			(at 0.127508 -4.024376 0)
			(unlocked yes)
			(layer "F.SilkS")
			(effects
				(font
					(size 0.7874 0.5842)
					(thickness 0.1524)
				)
			)
		)
		(property "Value" ""
			(at 0 0 0)
			(layer "F.Fab")
			(effects
				(font
					(size 1.27 1.27)
				)
			)
		)
		(property "Device Type" "MEC_MTH8-MTH125C236N_V8-MTH125A"
			(at 0 5.08127 0)
			(unlocked yes)
			(layer "F.Fab")
			(hide yes)
			(effects
				(font
					(size 0.7874 0.5842)
					(thickness 0.1524)
				)
			)
		)
		(duplicate_pad_numbers_are_jumpers no)
		(fp_poly
			(pts
				(arc
					(start 3.5052 0)
					(mid -3.5052 0)
					(end 3.5052 0)
				)
			)
			(stroke
				(width 0)
				(type default)
			)
			(fill no)
			(layer "B.CrtYd")
		)
		(fp_poly
			(pts
				(arc
					(start 3.5052 0)
					(mid -3.5052 0)
					(end 3.5052 0)
				)
			)
			(stroke
				(width 0)
				(type default)
			)
			(fill no)
			(layer "F.CrtYd")
		)
		(fp_circle
			(center 0 0)
			(end 2.9972 0)
			(stroke
				(width 0.1)
				(type default)
			)
			(fill no)
			(layer "B.Fab")
		)
		(fp_circle
			(center 0 0)
			(end 2.9972 0)
			(stroke
				(width 0.1)
				(type default)
			)
			(fill no)
			(layer "F.Fab")
		)
		(pad "" np_thru_hole circle
			(at 0 0)
			(size 2.921 2.921)
			(drill 3.175)
			(layers "*.Cu" "*.Mask")
			(padstack
				(mode front_inner_back)
				(layer "Inner"
					(shape circle)
					(size 2.921 2.921)
					(clearance 0.4445)
				)
				(layer "B.Cu"
					(shape circle)
					(size 2.921 2.921)
				)
			)
		)
		(pad "1" thru_hole circle
			(at 0 -2.4511)
			(size 0.6096 0.6096)
			(drill 0.3048)
			(layers "*.Cu" "*.Mask")
			(remove_unused_layers no)
			(net "SG")
			(padstack
				(mode front_inner_back)
				(layer "Inner"
					(shape circle)
					(size 0.6096 0.6096)
					(clearance 0.1143)
				)
				(layer "B.Cu"
					(shape circle)
					(size 0.6096 0.6096)
				)
			)
		)
		(pad "2" thru_hole circle
			(at 1.733296 -1.733296)
			(size 0.6096 0.6096)
			(drill 0.3048)
			(layers "*.Cu" "*.Mask")
			(remove_unused_layers no)
			(net "SG")
			(padstack
				(mode front_inner_back)
				(layer "Inner"
					(shape circle)
					(size 0.6096 0.6096)
					(clearance 0.1143)
				)
				(layer "B.Cu"
					(shape circle)
					(size 0.6096 0.6096)
				)
			)
		)
		(pad "3" thru_hole circle
			(at 2.4511 0)
			(size 0.6096 0.6096)
			(drill 0.3048)
			(layers "*.Cu" "*.Mask")
			(remove_unused_layers no)
			(net "SG")
			(padstack
				(mode front_inner_back)
				(layer "Inner"
					(shape circle)
					(size 0.6096 0.6096)
					(clearance 0.1143)
				)
				(layer "B.Cu"
					(shape circle)
					(size 0.6096 0.6096)
				)
			)
		)
		(pad "4" thru_hole circle
			(at 1.733296 1.733296)
			(size 0.6096 0.6096)
			(drill 0.3048)
			(layers "*.Cu" "*.Mask")
			(remove_unused_layers no)
			(net "SG")
			(padstack
				(mode front_inner_back)
				(layer "Inner"
					(shape circle)
					(size 0.6096 0.6096)
					(clearance 0.1143)
				)
				(layer "B.Cu"
					(shape circle)
					(size 0.6096 0.6096)
				)
			)
		)
		(pad "5" thru_hole circle
			(at 0 2.4511)
			(size 0.6096 0.6096)
			(drill 0.3048)
			(layers "*.Cu" "*.Mask")
			(remove_unused_layers no)
			(net "SG")
			(padstack
				(mode front_inner_back)
				(layer "Inner"
					(shape circle)
					(size 0.6096 0.6096)
					(clearance 0.1143)
				)
				(layer "B.Cu"
					(shape circle)
					(size 0.6096 0.6096)
				)
			)
		)
		(pad "6" thru_hole circle
			(at -1.733296 1.733296)
			(size 0.6096 0.6096)
			(drill 0.3048)
			(layers "*.Cu" "*.Mask")
			(remove_unused_layers no)
			(net "SG")
			(padstack
				(mode front_inner_back)
				(layer "Inner"
					(shape circle)
					(size 0.6096 0.6096)
					(clearance 0.1143)
				)
				(layer "B.Cu"
					(shape circle)
					(size 0.6096 0.6096)
				)
			)
		)
		(pad "7" thru_hole circle
			(at -2.4511 0)
			(size 0.6096 0.6096)
			(drill 0.3048)
			(layers "*.Cu" "*.Mask")
			(remove_unused_layers no)
			(net "SG")
			(padstack
				(mode front_inner_back)
				(layer "Inner"
					(shape circle)
					(size 0.6096 0.6096)
					(clearance 0.1143)
				)
				(layer "B.Cu"
					(shape circle)
					(size 0.6096 0.6096)
				)
			)
		)
		(pad "8" thru_hole circle
			(at -1.733296 -1.733296)
			(size 0.6096 0.6096)
			(drill 0.3048)
			(layers "*.Cu" "*.Mask")
			(remove_unused_layers no)
			(net "SG")
			(padstack
				(mode front_inner_back)
				(layer "Inner"
					(shape circle)
					(size 0.6096 0.6096)
					(clearance 0.1143)
				)
				(layer "B.Cu"
					(shape circle)
					(size 0.6096 0.6096)
				)
			)
		)
		(zone
			(layers "F.Cu" "B.Cu" "In1.Cu" "In2.Cu" "In3.Cu" "In4.Cu" "In5.Cu" "In6.Cu"
				"In7.Cu" "In8.Cu"
			)
			(hatch none 0.5)
			(connect_pads
				(clearance 0)
			)
			(min_thickness 0.25)
			(keepout
				(tracks not_allowed)
				(vias allowed)
				(pads allowed)
				(copperpour not_allowed)
				(footprints allowed)
			)
			(placement
				(enabled no)
				(sheetname "")
			)
			(fill
				(thermal_gap 0.5)
				(thermal_bridge_width 0.5)
				(island_removal_mode 0)
			)
			(polygon
				(pts
					(arc
						(start 9.392412 -94.749874)
						(mid 5.607812 -94.749874)
						(end 9.392412 -94.749874)
					)
				)
			)
		)
	)
	(footprint ""
		(layer "F.Cu")
		(at 63.784988 -15.367 -90)
		(property "Reference" "R22"
			(at -2.413 -0.038862 90)
			(unlocked yes)
			(layer "F.SilkS")
			(effects
				(font
					(size 0.7874 0.5842)
					(thickness 0.1524)
				)
			)
		)
		(property "Value" "VAL*"
			(at 0.02032 2.13233 270)
			(unlocked yes)
			(layer "F.Fab")
			(hide yes)
			(effects
				(font
					(size 0.7874 0.5842)
					(thickness 0.1524)
				)
			)
		)
		(property "Tolerance" "TOL*"
			(at 0.044704 3.05435 270)
			(unlocked yes)
			(layer "Cmts.User")
			(hide yes)
			(effects
				(font
					(size 0.7874 0.5842)
					(thickness 0.1524)
				)
			)
		)
		(property "User Part Number" "PARTNUM*"
			(at 0.02032 4.024884 270)
			(unlocked yes)
			(layer "Cmts.User")
			(hide yes)
			(effects
				(font
					(size 0.7874 0.5842)
					(thickness 0.1524)
				)
			)
		)
		(property "Device Type" "RESISTOR-G155-100R0-J0,0OHM,-"
			(at 0.008382 1.210564 270)
			(unlocked yes)
			(layer "F.Fab")
			(hide yes)
			(effects
				(font
					(size 0.7874 0.5842)
					(thickness 0.1524)
				)
			)
		)
		(duplicate_pad_numbers_are_jumpers no)
		(fp_line
			(start -1.143 0.5588)
			(end 1.143 0.5588)
			(stroke
				(width 0.1)
				(type default)
			)
			(layer "F.SilkS")
		)
		(fp_line
			(start 1.143 0.5588)
			(end 1.143 -0.5588)
			(stroke
				(width 0.1)
				(type default)
			)
			(layer "F.SilkS")
		)
		(fp_line
			(start -1.143 -0.5588)
			(end -1.143 0.5588)
			(stroke
				(width 0.1)
				(type default)
			)
			(layer "F.SilkS")
		)
		(fp_line
			(start 1.143 -0.5588)
			(end -1.143 -0.5588)
			(stroke
				(width 0.1)
				(type default)
			)
			(layer "F.SilkS")
		)
		(fp_rect
			(start -1.143 -0.5588)
			(end 1.143 0.5588)
			(stroke
				(width 0)
				(type default)
			)
			(fill no)
			(layer "F.CrtYd")
		)
		(fp_line
			(start -0.508 0.3048)
			(end 0.508 0.3048)
			(stroke
				(width 0.1)
				(type default)
			)
			(layer "F.Fab")
		)
		(fp_line
			(start 0.508 0.3048)
			(end 0.508 -0.3048)
			(stroke
				(width 0.1)
				(type default)
			)
			(layer "F.Fab")
		)
		(fp_line
			(start -0.508 -0.3048)
			(end -0.508 0.3048)
			(stroke
				(width 0.1)
				(type default)
			)
			(layer "F.Fab")
		)
		(fp_line
			(start 0.508 -0.3048)
			(end -0.508 -0.3048)
			(stroke
				(width 0.1)
				(type default)
			)
			(layer "F.Fab")
		)
		(pad "1" smd rect
			(at -0.5334 0 270)
			(size 0.7112 0.6096)
			(layers "F.Cu" "F.Mask" "F.Paste")
			(net "CARD_PRESENT")
		)
		(pad "2" smd rect
			(at 0.5334 0 270)
			(size 0.7112 0.6096)
			(layers "F.Cu" "F.Mask" "F.Paste")
			(net "UNNAMED_3_CONN64PGF_I61_PRSNT21")
		)
		(zone
			(layer "F.Cu")
			(hatch none 0.5)
			(connect_pads
				(clearance 0)
			)
			(min_thickness 0.25)
			(keepout
				(tracks allowed)
				(vias not_allowed)
				(pads allowed)
				(copperpour not_allowed)
				(footprints allowed)
			)
			(placement
				(enabled no)
				(sheetname "")
			)
			(fill
				(thermal_gap 0.5)
				(thermal_bridge_width 0.5)
				(island_removal_mode 0)
			)
			(polygon
				(pts
					(xy 64.089788 -15.4432) (xy 63.480188 -15.4432) (xy 63.480188 -15.2908) (xy 64.089788 -15.2908)
				)
			)
		)
	)
	(footprint ""
		(layer "F.Cu")
		(at 135.5344 -94.107 90)
		(property "Reference" "C9"
			(at -2.921 0.01397 90)
			(unlocked yes)
			(layer "F.SilkS")
			(effects
				(font
					(size 0.7874 0.5842)
					(thickness 0.1524)
				)
			)
		)
		(property "Value" "VAL*"
			(at 0.0762 3.134106 90)
			(unlocked yes)
			(layer "F.Fab")
			(hide yes)
			(effects
				(font
					(size 0.7874 0.5842)
					(thickness 0.1524)
				)
			)
		)
		(property "Device Type" "CAPACITOR-G107-0F106-EM,10UF,2A"
			(at 0.0508 2.194306 90)
			(unlocked yes)
			(layer "F.Fab")
			(hide yes)
			(effects
				(font
					(size 0.7874 0.5842)
					(thickness 0.1524)
				)
			)
		)
		(property "User Part Number" "PARTNUM*"
			(at 0.1016 5.013706 90)
			(unlocked yes)
			(layer "Cmts.User")
			(hide yes)
			(effects
				(font
					(size 0.7874 0.5842)
					(thickness 0.1524)
				)
			)
		)
		(property "Tolerance" "TOL*"
			(at 0.0762 4.048506 90)
			(unlocked yes)
			(layer "Cmts.User")
			(hide yes)
			(effects
				(font
					(size 0.7874 0.5842)
					(thickness 0.1524)
				)
			)
		)
		(duplicate_pad_numbers_are_jumpers no)
		(fp_line
			(start 1.5748 -0.9398)
			(end -1.5748 -0.9398)
			(stroke
				(width 0.1)
				(type default)
			)
			(layer "F.SilkS")
		)
		(fp_line
			(start -1.5748 -0.9398)
			(end -1.5748 0.9398)
			(stroke
				(width 0.1)
				(type default)
			)
			(layer "F.SilkS")
		)
		(fp_line
			(start 1.5748 0.9398)
			(end 1.5748 -0.9398)
			(stroke
				(width 0.1)
				(type default)
			)
			(layer "F.SilkS")
		)
		(fp_line
			(start -1.5748 0.9398)
			(end 1.5748 0.9398)
			(stroke
				(width 0.1)
				(type default)
			)
			(layer "F.SilkS")
		)
		(fp_rect
			(start 1.5748 0.9398)
			(end -1.5748 -0.9398)
			(stroke
				(width 0)
				(type default)
			)
			(fill no)
			(layer "F.CrtYd")
		)
		(fp_line
			(start 1.016 -0.635)
			(end -1.016 -0.635)
			(stroke
				(width 0.1)
				(type default)
			)
			(layer "F.Fab")
		)
		(fp_line
			(start -1.016 -0.635)
			(end -1.016 0.635)
			(stroke
				(width 0.1)
				(type default)
			)
			(layer "F.Fab")
		)
		(fp_line
			(start 1.016 0.635)
			(end 1.016 -0.635)
			(stroke
				(width 0.1)
				(type default)
			)
			(layer "F.Fab")
		)
		(fp_line
			(start -1.016 0.635)
			(end 1.016 0.635)
			(stroke
				(width 0.1)
				(type default)
			)
			(layer "F.Fab")
		)
		(pad "1" smd rect
			(at -0.8382 0 90)
			(size 0.9652 1.3716)
			(layers "F.Cu" "F.Mask" "F.Paste")
			(net "XP12R0V")
		)
		(pad "2" smd rect
			(at 0.8382 0 90)
			(size 0.9652 1.3716)
			(layers "F.Cu" "F.Mask" "F.Paste")
			(net "SG")
		)
		(zone
			(layer "F.Cu")
			(hatch none 0.5)
			(connect_pads
				(clearance 0)
			)
			(min_thickness 0.25)
			(keepout
				(tracks allowed)
				(vias not_allowed)
				(pads allowed)
				(copperpour not_allowed)
				(footprints allowed)
			)
			(placement
				(enabled no)
				(sheetname "")
			)
			(fill
				(thermal_gap 0.5)
				(thermal_bridge_width 0.5)
				(island_removal_mode 0)
			)
			(polygon
				(pts
					(xy 136.1694 -94.3356) (xy 134.8994 -94.3356) (xy 134.8994 -93.8784) (xy 136.1694 -93.8784)
				)
			)
		)
	)
	(footprint ""
		(layer "F.Cu")
		(at 38.227 -74.93 180)
		(property "Reference" "R489"
			(at -0.508 -1.30937 0)
			(unlocked yes)
			(layer "F.SilkS")
			(effects
				(font
					(size 0.7874 0.5842)
					(thickness 0.1524)
				)
			)
		)
		(property "Value" "VAL*"
			(at 0.0508 2.245106 180)
			(unlocked yes)
			(layer "F.Fab")
			(hide yes)
			(effects
				(font
					(size 0.7874 0.5842)
					(thickness 0.1524)
				)
			)
		)
		(property "User Part Number" "PARTNUM*"
			(at 0.0762 4.302506 180)
			(unlocked yes)
			(layer "Cmts.User")
			(hide yes)
			(effects
				(font
					(size 0.7874 0.5842)
					(thickness 0.1524)
				)
			)
		)
		(property "Device Type" "RESISTOR-G155-03921-01,3.92KOHA"
			(at 0.0762 1.254506 180)
			(unlocked yes)
			(layer "F.Fab")
			(hide yes)
			(effects
				(font
					(size 0.7874 0.5842)
					(thickness 0.1524)
				)
			)
		)
		(property "Tolerance" "TOL*"
			(at 0.0508 3.261106 180)
			(unlocked yes)
			(layer "Cmts.User")
			(hide yes)
			(effects
				(font
					(size 0.7874 0.5842)
					(thickness 0.1524)
				)
			)
		)
		(duplicate_pad_numbers_are_jumpers no)
		(fp_line
			(start 1.143 0.5588)
			(end 1.143 -0.5588)
			(stroke
				(width 0.1)
				(type default)
			)
			(layer "F.SilkS")
		)
		(fp_line
			(start 1.143 -0.5588)
			(end -1.143 -0.5588)
			(stroke
				(width 0.1)
				(type default)
			)
			(layer "F.SilkS")
		)
		(fp_line
			(start -1.143 0.5588)
			(end 1.143 0.5588)
			(stroke
				(width 0.1)
				(type default)
			)
			(layer "F.SilkS")
		)
		(fp_line
			(start -1.143 -0.5588)
			(end -1.143 0.5588)
			(stroke
				(width 0.1)
				(type default)
			)
			(layer "F.SilkS")
		)
		(fp_poly
			(pts
				(xy -1.143 0.5588) (xy 1.143 0.5588) (xy 1.143 -0.5588) (xy -1.143 -0.5588)
			)
			(stroke
				(width 0)
				(type default)
			)
			(fill no)
			(layer "F.CrtYd")
		)
		(fp_line
			(start 0.508 0.3048)
			(end 0.508 -0.3048)
			(stroke
				(width 0.1)
				(type default)
			)
			(layer "F.Fab")
		)
		(fp_line
			(start 0.508 -0.3048)
			(end -0.508 -0.3048)
			(stroke
				(width 0.1)
				(type default)
			)
			(layer "F.Fab")
		)
		(fp_line
			(start -0.508 0.3048)
			(end 0.508 0.3048)
			(stroke
				(width 0.1)
				(type default)
			)
			(layer "F.Fab")
		)
		(fp_line
			(start -0.508 -0.3048)
			(end -0.508 0.3048)
			(stroke
				(width 0.1)
				(type default)
			)
			(layer "F.Fab")
		)
		(pad "1" smd rect
			(at -0.5334 0 180)
			(size 0.7112 0.6096)
			(layers "F.Cu" "F.Mask" "F.Paste")
			(net "UNNAMED_525_ISL80101IRAJZDFN10_")
		)
		(pad "2" smd rect
			(at 0.5334 0 180)
			(size 0.7112 0.6096)
			(layers "F.Cu" "F.Mask" "F.Paste")
			(net "SG")
		)
		(zone
			(layer "F.Cu")
			(hatch none 0.5)
			(connect_pads
				(clearance 0)
			)
			(min_thickness 0.25)
			(keepout
				(tracks allowed)
				(vias not_allowed)
				(pads allowed)
				(copperpour not_allowed)
				(footprints allowed)
			)
			(placement
				(enabled no)
				(sheetname "")
			)
			(fill
				(thermal_gap 0.5)
				(thermal_bridge_width 0.5)
				(island_removal_mode 0)
			)
			(polygon
				(pts
					(xy 38.3032 -75.2348) (xy 38.1508 -75.2348) (xy 38.1508 -74.6252) (xy 38.3032 -74.6252)
				)
			)
		)
		(zone
			(layer "F.Cu")
			(hatch none 0.5)
			(connect_pads
				(clearance 0)
			)
			(min_thickness 0.25)
			(keepout
				(tracks not_allowed)
				(vias allowed)
				(pads allowed)
				(copperpour not_allowed)
				(footprints allowed)
			)
			(placement
				(enabled no)
				(sheetname "")
			)
			(fill
				(thermal_gap 0.5)
				(thermal_bridge_width 0.5)
				(island_removal_mode 0)
			)
			(polygon
				(pts
					(xy 38.3032 -75.2348) (xy 38.1508 -75.2348) (xy 38.1508 -74.6252) (xy 38.3032 -74.6252)
				)
			)
		)
	)
	(footprint ""
		(layer "F.Cu")
		(at 16.852392 -67.6656)
		(property "Reference" "R72"
			(at -1.993392 -0.50165 0)
			(unlocked yes)
			(layer "F.SilkS")
			(effects
				(font
					(size 0.635 0.4064)
					(thickness 0.1524)
				)
			)
		)
		(property "Value" "VAL*"
			(at 0.02032 2.13233 0)
			(unlocked yes)
			(layer "F.Fab")
			(hide yes)
			(effects
				(font
					(size 0.7874 0.5842)
					(thickness 0.1524)
				)
			)
		)
		(property "Tolerance" "TOL*"
			(at 0.044704 3.05435 0)
			(unlocked yes)
			(layer "Cmts.User")
			(hide yes)
			(effects
				(font
					(size 0.7874 0.5842)
					(thickness 0.1524)
				)
			)
		)
		(property "User Part Number" "PARTNUM*"
			(at 0.02032 4.024884 0)
			(unlocked yes)
			(layer "Cmts.User")
			(hide yes)
			(effects
				(font
					(size 0.7874 0.5842)
					(thickness 0.1524)
				)
			)
		)
		(property "Device Type" "RESISTOR-G155-133R0-01,33OHM,1%"
			(at 0.008382 1.210564 0)
			(unlocked yes)
			(layer "F.Fab")
			(hide yes)
			(effects
				(font
					(size 0.7874 0.5842)
					(thickness 0.1524)
				)
			)
		)
		(duplicate_pad_numbers_are_jumpers no)
		(fp_line
			(start -1.143 -0.5588)
			(end -1.143 0.5588)
			(stroke
				(width 0.1)
				(type default)
			)
			(layer "F.SilkS")
		)
		(fp_line
			(start -1.143 0.5588)
			(end 1.143 0.5588)
			(stroke
				(width 0.1)
				(type default)
			)
			(layer "F.SilkS")
		)
		(fp_line
			(start 1.143 -0.5588)
			(end -1.143 -0.5588)
			(stroke
				(width 0.1)
				(type default)
			)
			(layer "F.SilkS")
		)
		(fp_line
			(start 1.143 0.5588)
			(end 1.143 -0.5588)
			(stroke
				(width 0.1)
				(type default)
			)
			(layer "F.SilkS")
		)
		(fp_rect
			(start -1.143 -0.5588)
			(end 1.143 0.5588)
			(stroke
				(width 0)
				(type default)
			)
			(fill no)
			(layer "F.CrtYd")
		)
		(fp_line
			(start -0.508 -0.3048)
			(end -0.508 0.3048)
			(stroke
				(width 0.1)
				(type default)
			)
			(layer "F.Fab")
		)
		(fp_line
			(start -0.508 0.3048)
			(end 0.508 0.3048)
			(stroke
				(width 0.1)
				(type default)
			)
			(layer "F.Fab")
		)
		(fp_line
			(start 0.508 -0.3048)
			(end -0.508 -0.3048)
			(stroke
				(width 0.1)
				(type default)
			)
			(layer "F.Fab")
		)
		(fp_line
			(start 0.508 0.3048)
			(end 0.508 -0.3048)
			(stroke
				(width 0.1)
				(type default)
			)
			(layer "F.Fab")
		)
		(pad "1" smd rect
			(at -0.5334 0)
			(size 0.7112 0.6096)
			(layers "F.Cu" "F.Mask" "F.Paste")
			(net "BF_ICP10100_I2C_SDA")
		)
		(pad "2" smd rect
			(at 0.5334 0)
			(size 0.7112 0.6096)
			(layers "F.Cu" "F.Mask" "F.Paste")
			(net "R_ICP10100_I2C_SDA")
		)
		(zone
			(layer "F.Cu")
			(hatch none 0.5)
			(connect_pads
				(clearance 0)
			)
			(min_thickness 0.25)
			(keepout
				(tracks allowed)
				(vias not_allowed)
				(pads allowed)
				(copperpour not_allowed)
				(footprints allowed)
			)
			(placement
				(enabled no)
				(sheetname "")
			)
			(fill
				(thermal_gap 0.5)
				(thermal_bridge_width 0.5)
				(island_removal_mode 0)
			)
			(polygon
				(pts
					(xy 16.776192 -67.9704) (xy 16.776192 -67.3608) (xy 16.928592 -67.3608) (xy 16.928592 -67.9704)
				)
			)
		)
	)
	(footprint ""
		(layer "F.Cu")
		(at 46.863 -77.216)
		(property "Reference" "C304"
			(at 3.175 0.16637 0)
			(unlocked yes)
			(layer "F.SilkS")
			(effects
				(font
					(size 0.7874 0.5842)
					(thickness 0.1524)
				)
			)
		)
		(property "Value" "VAL*"
			(at 0.0762 2.067306 0)
			(unlocked yes)
			(layer "F.Fab")
			(hide yes)
			(effects
				(font
					(size 0.7874 0.5842)
					(thickness 0.1524)
				)
			)
		)
		(property "Tolerance" "TOL*"
			(at 0.0762 3.032506 0)
			(unlocked yes)
			(layer "Cmts.User")
			(hide yes)
			(effects
				(font
					(size 0.7874 0.5842)
					(thickness 0.1524)
				)
			)
		)
		(property "User Part Number" "PARTNUM*"
			(at 0.1016 4.023106 0)
			(unlocked yes)
			(layer "Cmts.User")
			(hide yes)
			(effects
				(font
					(size 0.7874 0.5842)
					(thickness 0.1524)
				)
			)
		)
		(property "Device Type" "CAPACITOR-G105-0B104-EK,0.1UF,A"
			(at 0.0508 1.127506 0)
			(unlocked yes)
			(layer "F.Fab")
			(hide yes)
			(effects
				(font
					(size 0.7874 0.5842)
					(thickness 0.1524)
				)
			)
		)
		(duplicate_pad_numbers_are_jumpers no)
		(fp_line
			(start -1.143 -0.5588)
			(end -1.143 0.5588)
			(stroke
				(width 0.1)
				(type default)
			)
			(layer "F.SilkS")
		)
		(fp_line
			(start -1.143 0.5588)
			(end 1.143 0.5588)
			(stroke
				(width 0.1)
				(type default)
			)
			(layer "F.SilkS")
		)
		(fp_line
			(start 1.143 -0.5588)
			(end -1.143 -0.5588)
			(stroke
				(width 0.1)
				(type default)
			)
			(layer "F.SilkS")
		)
		(fp_line
			(start 1.143 0.5588)
			(end 1.143 -0.5588)
			(stroke
				(width 0.1)
				(type default)
			)
			(layer "F.SilkS")
		)
		(fp_poly
			(pts
				(xy -1.143 0.5588) (xy 1.143 0.5588) (xy 1.143 -0.5588) (xy -1.143 -0.5588)
			)
			(stroke
				(width 0)
				(type default)
			)
			(fill no)
			(layer "F.CrtYd")
		)
		(fp_line
			(start -0.508 -0.3048)
			(end -0.508 0.3048)
			(stroke
				(width 0.1)
				(type default)
			)
			(layer "F.Fab")
		)
		(fp_line
			(start -0.508 0.3048)
			(end 0.508 0.3048)
			(stroke
				(width 0.1)
				(type default)
			)
			(layer "F.Fab")
		)
		(fp_line
			(start 0.508 -0.3048)
			(end -0.508 -0.3048)
			(stroke
				(width 0.1)
				(type default)
			)
			(layer "F.Fab")
		)
		(fp_line
			(start 0.508 0.3048)
			(end 0.508 -0.3048)
			(stroke
				(width 0.1)
				(type default)
			)
			(layer "F.Fab")
		)
		(pad "1" smd rect
			(at -0.5334 0)
			(size 0.7112 0.6096)
			(layers "F.Cu" "F.Mask" "F.Paste")
			(net "UNNAMED_525_CAPACITOR_I16_1")
		)
		(pad "2" smd rect
			(at 0.5334 0)
			(size 0.7112 0.6096)
			(layers "F.Cu" "F.Mask" "F.Paste")
			(net "SG")
		)
		(zone
			(layer "F.Cu")
			(hatch none 0.5)
			(connect_pads
				(clearance 0)
			)
			(min_thickness 0.25)
			(keepout
				(tracks not_allowed)
				(vias allowed)
				(pads allowed)
				(copperpour not_allowed)
				(footprints allowed)
			)
			(placement
				(enabled no)
				(sheetname "")
			)
			(fill
				(thermal_gap 0.5)
				(thermal_bridge_width 0.5)
				(island_removal_mode 0)
			)
			(polygon
				(pts
					(xy 46.7868 -76.9112) (xy 46.9392 -76.9112) (xy 46.9392 -77.5208) (xy 46.7868 -77.5208)
				)
			)
		)
		(zone
			(layer "F.Cu")
			(hatch none 0.5)
			(connect_pads
				(clearance 0)
			)
			(min_thickness 0.25)
			(keepout
				(tracks allowed)
				(vias not_allowed)
				(pads allowed)
				(copperpour not_allowed)
				(footprints allowed)
			)
			(placement
				(enabled no)
				(sheetname "")
			)
			(fill
				(thermal_gap 0.5)
				(thermal_bridge_width 0.5)
				(island_removal_mode 0)
			)
			(polygon
				(pts
					(xy 46.7868 -76.9112) (xy 46.9392 -76.9112) (xy 46.9392 -77.5208) (xy 46.7868 -77.5208)
				)
			)
		)
	)
	(footprint ""
		(layer "F.Cu")
		(at 87.4522 -97.4598 -90)
		(property "Reference" "R35"
			(at 5.2578 5.87883 90)
			(unlocked yes)
			(layer "F.SilkS")
			(effects
				(font
					(size 0.7874 0.5842)
					(thickness 0.1524)
				)
			)
		)
		(property "Value" "VAL*"
			(at 0.02032 2.13233 270)
			(unlocked yes)
			(layer "F.Fab")
			(hide yes)
			(effects
				(font
					(size 0.7874 0.5842)
					(thickness 0.1524)
				)
			)
		)
		(property "Tolerance" "TOL*"
			(at 0.044704 3.05435 270)
			(unlocked yes)
			(layer "Cmts.User")
			(hide yes)
			(effects
				(font
					(size 0.7874 0.5842)
					(thickness 0.1524)
				)
			)
		)
		(property "User Part Number" "PARTNUM*"
			(at 0.02032 4.024884 270)
			(unlocked yes)
			(layer "Cmts.User")
			(hide yes)
			(effects
				(font
					(size 0.7874 0.5842)
					(thickness 0.1524)
				)
			)
		)
		(property "Device Type" "RESISTOR-G155-11003-01,100KOHMA"
			(at 0.008382 1.210564 270)
			(unlocked yes)
			(layer "F.Fab")
			(hide yes)
			(effects
				(font
					(size 0.7874 0.5842)
					(thickness 0.1524)
				)
			)
		)
		(duplicate_pad_numbers_are_jumpers no)
		(fp_line
			(start -1.143 0.5588)
			(end 1.143 0.5588)
			(stroke
				(width 0.1)
				(type default)
			)
			(layer "F.SilkS")
		)
		(fp_line
			(start 1.143 0.5588)
			(end 1.143 -0.5588)
			(stroke
				(width 0.1)
				(type default)
			)
			(layer "F.SilkS")
		)
		(fp_line
			(start -1.143 -0.5588)
			(end -1.143 0.5588)
			(stroke
				(width 0.1)
				(type default)
			)
			(layer "F.SilkS")
		)
		(fp_line
			(start 1.143 -0.5588)
			(end -1.143 -0.5588)
			(stroke
				(width 0.1)
				(type default)
			)
			(layer "F.SilkS")
		)
		(fp_rect
			(start 1.143 0.5588)
			(end -1.143 -0.5588)
			(stroke
				(width 0)
				(type default)
			)
			(fill no)
			(layer "F.CrtYd")
		)
		(fp_line
			(start -0.508 0.3048)
			(end 0.508 0.3048)
			(stroke
				(width 0.1)
				(type default)
			)
			(layer "F.Fab")
		)
		(fp_line
			(start 0.508 0.3048)
			(end 0.508 -0.3048)
			(stroke
				(width 0.1)
				(type default)
			)
			(layer "F.Fab")
		)
		(fp_line
			(start -0.508 -0.3048)
			(end -0.508 0.3048)
			(stroke
				(width 0.1)
				(type default)
			)
			(layer "F.Fab")
		)
		(fp_line
			(start 0.508 -0.3048)
			(end -0.508 -0.3048)
			(stroke
				(width 0.1)
				(type default)
			)
			(layer "F.Fab")
		)
		(pad "1" smd rect
			(at -0.5334 0 270)
			(size 0.7112 0.6096)
			(layers "F.Cu" "F.Mask" "F.Paste")
			(net "XP3R3V_RT")
		)
		(pad "2" smd rect
			(at 0.5334 0 270)
			(size 0.7112 0.6096)
			(layers "F.Cu" "F.Mask" "F.Paste")
			(net "XP3R3V_AGND")
		)
		(zone
			(layer "F.Cu")
			(hatch none 0.5)
			(connect_pads
				(clearance 0)
			)
			(min_thickness 0.25)
			(keepout
				(tracks allowed)
				(vias not_allowed)
				(pads allowed)
				(copperpour not_allowed)
				(footprints allowed)
			)
			(placement
				(enabled no)
				(sheetname "")
			)
			(fill
				(thermal_gap 0.5)
				(thermal_bridge_width 0.5)
				(island_removal_mode 0)
			)
			(polygon
				(pts
					(xy 87.1474 -97.3836) (xy 87.757 -97.3836) (xy 87.757 -97.536) (xy 87.1474 -97.536)
				)
			)
		)
	)
	(footprint ""
		(layer "F.Cu")
		(at 70.578218 -23.734522)
		(property "Reference" "MAC_PIN6"
			(at 2.667762 2.580132 0)
			(unlocked yes)
			(layer "F.SilkS")
			(effects
				(font
					(size 0.7874 0.5842)
					(thickness 0.1524)
				)
			)
		)
		(property "Value" ""
			(at 0 0 0)
			(layer "F.Fab")
			(effects
				(font
					(size 1.27 1.27)
				)
			)
		)
		(property "Device Type" "NUT-A200-00029-FB"
			(at 0 2.632964 0)
			(unlocked yes)
			(layer "F.Fab")
			(hide yes)
			(effects
				(font
					(size 0.7874 0.5842)
					(thickness 0.1524)
				)
			)
		)
		(property "User Part Number" "PARTNUM*"
			(at 0 3.826764 0)
			(unlocked yes)
			(layer "Cmts.User")
			(hide yes)
			(effects
				(font
					(size 0.7874 0.5842)
					(thickness 0.1524)
				)
			)
		)
		(duplicate_pad_numbers_are_jumpers no)
		(fp_circle
			(center 0 0)
			(end 1.524 0)
			(stroke
				(width 0.1)
				(type default)
			)
			(fill no)
			(layer "F.SilkS")
		)
		(fp_poly
			(pts
				(arc
					(start -1.260856 -0.1524)
					(mid -0.898049 -0.898049)
					(end -0.1524 -1.260856)
				)
				(arc
					(start -0.1524 -0.991616)
					(mid -0.709411 -0.709411)
					(end -0.991616 -0.1524)
				)
			)
			(stroke
				(width 0)
				(type default)
			)
			(fill yes)
			(layer "F.Paste")
		)
		(fp_poly
			(pts
				(arc
					(start -0.1524 1.260856)
					(mid -0.898049 0.898049)
					(end -1.260856 0.1524)
				)
				(arc
					(start -0.991616 0.1524)
					(mid -0.709411 0.709411)
					(end -0.1524 0.991616)
				)
			)
			(stroke
				(width 0)
				(type default)
			)
			(fill yes)
			(layer "F.Paste")
		)
		(fp_poly
			(pts
				(arc
					(start 0.1524 -1.260856)
					(mid 0.898049 -0.898049)
					(end 1.260856 -0.1524)
				)
				(arc
					(start 0.991616 -0.1524)
					(mid 0.709411 -0.709411)
					(end 0.1524 -0.991616)
				)
			)
			(stroke
				(width 0)
				(type default)
			)
			(fill yes)
			(layer "F.Paste")
		)
		(fp_poly
			(pts
				(arc
					(start 1.260856 0.1524)
					(mid 0.898049 0.898049)
					(end 0.1524 1.260856)
				)
				(arc
					(start 0.1524 0.991616)
					(mid 0.709411 0.709411)
					(end 0.991616 0.1524)
				)
			)
			(stroke
				(width 0)
				(type default)
			)
			(fill yes)
			(layer "F.Paste")
		)
		(fp_poly
			(pts
				(arc
					(start 6.35 0)
					(mid -6.35 0)
					(end 6.35 0)
				)
			)
			(stroke
				(width 0)
				(type default)
			)
			(fill no)
			(layer "B.CrtYd")
		)
		(fp_poly
			(pts
				(arc
					(start 1.778 0)
					(mid -1.778 0)
					(end 1.778 0)
				)
			)
			(stroke
				(width 0)
				(type default)
			)
			(fill no)
			(layer "F.CrtYd")
		)
		(fp_circle
			(center 0 0)
			(end 1.1684 0)
			(stroke
				(width 0.1)
				(type default)
			)
			(fill no)
			(layer "F.Fab")
		)
		(pad "1" thru_hole circle
			(at 0 0)
			(size 2.54 2.54)
			(drill 2.0066)
			(layers "*.Cu" "*.Mask")
			(remove_unused_layers no)
			(net "R_MAC_BITEOUT")
			(thermal_gap 0.0254)
			(padstack
				(mode front_inner_back)
				(layer "Inner"
					(shape circle)
					(size 2.54 2.54)
					(clearance 0.0254)
				)
				(layer "B.Cu"
					(shape circle)
					(size 2.54 2.54)
				)
			)
		)
	)
	(footprint ""
		(layer "F.Cu")
		(at 115.443 -76.073 180)
		(property "Reference" "R143"
			(at -3.429 0.46863 0)
			(unlocked yes)
			(layer "F.SilkS")
			(effects
				(font
					(size 0.7874 0.5842)
					(thickness 0.1524)
				)
			)
		)
		(property "Value" "VAL*"
			(at 0.02032 2.13233 180)
			(unlocked yes)
			(layer "F.Fab")
			(hide yes)
			(effects
				(font
					(size 0.7874 0.5842)
					(thickness 0.1524)
				)
			)
		)
		(property "Device Type" "RESISTOR-G155-133R0-01,33OHM,1%"
			(at 0.008382 1.210564 180)
			(unlocked yes)
			(layer "F.Fab")
			(hide yes)
			(effects
				(font
					(size 0.7874 0.5842)
					(thickness 0.1524)
				)
			)
		)
		(property "User Part Number" "PARTNUM*"
			(at 0.02032 4.024884 180)
			(unlocked yes)
			(layer "Cmts.User")
			(hide yes)
			(effects
				(font
					(size 0.7874 0.5842)
					(thickness 0.1524)
				)
			)
		)
		(property "Tolerance" "TOL*"
			(at 0.044704 3.05435 180)
			(unlocked yes)
			(layer "Cmts.User")
			(hide yes)
			(effects
				(font
					(size 0.7874 0.5842)
					(thickness 0.1524)
				)
			)
		)
		(duplicate_pad_numbers_are_jumpers no)
		(fp_line
			(start 1.143 0.5588)
			(end 1.143 -0.5588)
			(stroke
				(width 0.1)
				(type default)
			)
			(layer "F.SilkS")
		)
		(fp_line
			(start 1.143 -0.5588)
			(end -1.143 -0.5588)
			(stroke
				(width 0.1)
				(type default)
			)
			(layer "F.SilkS")
		)
		(fp_line
			(start -1.143 0.5588)
			(end 1.143 0.5588)
			(stroke
				(width 0.1)
				(type default)
			)
			(layer "F.SilkS")
		)
		(fp_line
			(start -1.143 -0.5588)
			(end -1.143 0.5588)
			(stroke
				(width 0.1)
				(type default)
			)
			(layer "F.SilkS")
		)
		(fp_rect
			(start 1.143 0.5588)
			(end -1.143 -0.5588)
			(stroke
				(width 0)
				(type default)
			)
			(fill no)
			(layer "F.CrtYd")
		)
		(fp_line
			(start 0.508 0.3048)
			(end 0.508 -0.3048)
			(stroke
				(width 0.1)
				(type default)
			)
			(layer "F.Fab")
		)
		(fp_line
			(start 0.508 -0.3048)
			(end -0.508 -0.3048)
			(stroke
				(width 0.1)
				(type default)
			)
			(layer "F.Fab")
		)
		(fp_line
			(start -0.508 0.3048)
			(end 0.508 0.3048)
			(stroke
				(width 0.1)
				(type default)
			)
			(layer "F.Fab")
		)
		(fp_line
			(start -0.508 -0.3048)
			(end -0.508 0.3048)
			(stroke
				(width 0.1)
				(type default)
			)
			(layer "F.Fab")
		)
		(pad "1" smd rect
			(at -0.5334 0 180)
			(size 0.7112 0.6096)
			(layers "F.Cu" "F.Mask" "F.Paste")
			(net "FPGA_CFG_INIT_N")
		)
		(pad "2" smd rect
			(at 0.5334 0 180)
			(size 0.7112 0.6096)
			(layers "F.Cu" "F.Mask" "F.Paste")
			(net "UNNAMED_515_NCP45560IMNTWGHDFN1")
		)
		(zone
			(layer "F.Cu")
			(hatch none 0.5)
			(connect_pads
				(clearance 0)
			)
			(min_thickness 0.25)
			(keepout
				(tracks allowed)
				(vias not_allowed)
				(pads allowed)
				(copperpour not_allowed)
				(footprints allowed)
			)
			(placement
				(enabled no)
				(sheetname "")
			)
			(fill
				(thermal_gap 0.5)
				(thermal_bridge_width 0.5)
				(island_removal_mode 0)
			)
			(polygon
				(pts
					(xy 115.3668 -76.3778) (xy 115.3668 -75.7682) (xy 115.5192 -75.7682) (xy 115.5192 -76.3778)
				)
			)
		)
	)
	(footprint ""
		(layer "F.Cu")
		(at 66.802 -123.698)
		(property "Reference" "SP38"
			(at 0 0 0)
			(layer "F.SilkS")
			(hide yes)
			(effects
				(font
					(size 1.27 1.27)
				)
			)
		)
		(property "Value" ""
			(at 0 0 0)
			(layer "F.Fab")
			(effects
				(font
					(size 1.27 1.27)
				)
			)
		)
		(duplicate_pad_numbers_are_jumpers no)
	)
	(footprint ""
		(layer "F.Cu")
		(at 100.2538 -68.072 180)
		(property "Reference" "R178"
			(at -2.8702 0.08763 0)
			(unlocked yes)
			(layer "F.SilkS")
			(effects
				(font
					(size 0.7874 0.5842)
					(thickness 0.1524)
				)
			)
		)
		(property "Value" "VAL*"
			(at 0.02032 2.13233 180)
			(unlocked yes)
			(layer "F.Fab")
			(hide yes)
			(effects
				(font
					(size 0.7874 0.5842)
					(thickness 0.1524)
				)
			)
		)
		(property "Tolerance" "TOL*"
			(at 0.044704 3.05435 180)
			(unlocked yes)
			(layer "Cmts.User")
			(hide yes)
			(effects
				(font
					(size 0.7874 0.5842)
					(thickness 0.1524)
				)
			)
		)
		(property "User Part Number" "PARTNUM*"
			(at 0.02032 4.024884 180)
			(unlocked yes)
			(layer "Cmts.User")
			(hide yes)
			(effects
				(font
					(size 0.7874 0.5842)
					(thickness 0.1524)
				)
			)
		)
		(property "Device Type" "RESISTOR-G155-14701-01,4.7KOHMA"
			(at 0.008382 1.210564 180)
			(unlocked yes)
			(layer "F.Fab")
			(hide yes)
			(effects
				(font
					(size 0.7874 0.5842)
					(thickness 0.1524)
				)
			)
		)
		(duplicate_pad_numbers_are_jumpers no)
		(fp_line
			(start 1.143 0.5588)
			(end 1.143 -0.5588)
			(stroke
				(width 0.1)
				(type default)
			)
			(layer "F.SilkS")
		)
		(fp_line
			(start 1.143 -0.5588)
			(end -1.143 -0.5588)
			(stroke
				(width 0.1)
				(type default)
			)
			(layer "F.SilkS")
		)
		(fp_line
			(start -1.143 0.5588)
			(end 1.143 0.5588)
			(stroke
				(width 0.1)
				(type default)
			)
			(layer "F.SilkS")
		)
		(fp_line
			(start -1.143 -0.5588)
			(end -1.143 0.5588)
			(stroke
				(width 0.1)
				(type default)
			)
			(layer "F.SilkS")
		)
		(fp_rect
			(start 1.143 -0.5588)
			(end -1.143 0.5588)
			(stroke
				(width 0)
				(type default)
			)
			(fill no)
			(layer "F.CrtYd")
		)
		(fp_line
			(start 0.508 0.3048)
			(end 0.508 -0.3048)
			(stroke
				(width 0.1)
				(type default)
			)
			(layer "F.Fab")
		)
		(fp_line
			(start 0.508 -0.3048)
			(end -0.508 -0.3048)
			(stroke
				(width 0.1)
				(type default)
			)
			(layer "F.Fab")
		)
		(fp_line
			(start -0.508 0.3048)
			(end 0.508 0.3048)
			(stroke
				(width 0.1)
				(type default)
			)
			(layer "F.Fab")
		)
		(fp_line
			(start -0.508 -0.3048)
			(end -0.508 0.3048)
			(stroke
				(width 0.1)
				(type default)
			)
			(layer "F.Fab")
		)
		(pad "1" smd rect
			(at -0.5334 0 180)
			(size 0.7112 0.6096)
			(layers "F.Cu" "F.Mask" "F.Paste")
			(net "XP3R3V")
		)
		(pad "2" smd rect
			(at 0.5334 0 180)
			(size 0.7112 0.6096)
			(layers "F.Cu" "F.Mask" "F.Paste")
			(net "XP1R2V_PG_R")
		)
		(zone
			(layer "F.Cu")
			(hatch none 0.5)
			(connect_pads
				(clearance 0)
			)
			(min_thickness 0.25)
			(keepout
				(tracks allowed)
				(vias not_allowed)
				(pads allowed)
				(copperpour not_allowed)
				(footprints allowed)
			)
			(placement
				(enabled no)
				(sheetname "")
			)
			(fill
				(thermal_gap 0.5)
				(thermal_bridge_width 0.5)
				(island_removal_mode 0)
			)
			(polygon
				(pts
					(xy 100.1776 -67.7672) (xy 100.33 -67.7672) (xy 100.33 -68.3768) (xy 100.1776 -68.3768)
				)
			)
		)
	)
	(footprint ""
		(layer "F.Cu")
		(at 1.500124 -82.600038 90)
		(property "Reference" "DS18"
			(at -4.241038 0.698246 90)
			(unlocked yes)
			(layer "F.SilkS")
			(effects
				(font
					(size 0.7874 0.5842)
					(thickness 0.1524)
				)
			)
		)
		(property "Value" ""
			(at 0 0 90)
			(layer "F.Fab")
			(effects
				(font
					(size 1.27 1.27)
				)
			)
		)
		(property "User Part Number" "PARTNUM*"
			(at 0.015494 4.486402 90)
			(unlocked yes)
			(layer "Cmts.User")
			(hide yes)
			(effects
				(font
					(size 0.7874 0.5842)
					(thickness 0.1524)
				)
			)
		)
		(property "Device Type" "LED_4P_V14-G170-10189-01"
			(at 0.015494 3.292602 90)
			(unlocked yes)
			(layer "F.Fab")
			(hide yes)
			(effects
				(font
					(size 0.7874 0.5842)
					(thickness 0.1524)
				)
			)
		)
		(duplicate_pad_numbers_are_jumpers no)
		(fp_line
			(start 1.378966 -0.829056)
			(end -1.378966 -0.829056)
			(stroke
				(width 0.1)
				(type default)
			)
			(layer "F.SilkS")
		)
		(fp_line
			(start -1.378966 -0.829056)
			(end -1.378966 -0.452628)
			(stroke
				(width 0.1)
				(type default)
			)
			(layer "F.SilkS")
		)
		(fp_line
			(start 1.998218 -0.452628)
			(end 1.378966 -0.452628)
			(stroke
				(width 0.1)
				(type default)
			)
			(layer "F.SilkS")
		)
		(fp_line
			(start 1.378966 -0.452628)
			(end 1.378966 -0.829056)
			(stroke
				(width 0.1)
				(type default)
			)
			(layer "F.SilkS")
		)
		(fp_line
			(start -1.378966 -0.452628)
			(end -1.998218 -0.452628)
			(stroke
				(width 0.1)
				(type default)
			)
			(layer "F.SilkS")
		)
		(fp_line
			(start -1.998218 -0.452628)
			(end -1.998218 1.103884)
			(stroke
				(width 0.1)
				(type default)
			)
			(layer "F.SilkS")
		)
		(fp_line
			(start 1.998218 1.103884)
			(end 1.998218 -0.452628)
			(stroke
				(width 0.1)
				(type default)
			)
			(layer "F.SilkS")
		)
		(fp_line
			(start -1.998218 1.103884)
			(end 1.998218 1.103884)
			(stroke
				(width 0.1)
				(type default)
			)
			(layer "F.SilkS")
		)
		(fp_poly
			(pts
				(xy 0.918464 -1.698498) (xy 1.223264 -1.46939) (xy 0.994664 -1.46939) (xy 0.994664 -1.24079) (xy 0.842264 -1.24079)
				(xy 0.842264 -1.46939) (xy 0.613664 -1.46939)
			)
			(stroke
				(width 0)
				(type default)
			)
			(fill yes)
			(layer "F.SilkS")
		)
		(fp_poly
			(pts
				(xy -0.73406 -1.677416) (xy -0.42926 -1.448308) (xy -0.65786 -1.448308) (xy -0.65786 -1.219708)
				(xy -0.81026 -1.219708) (xy -0.81026 -1.448308) (xy -1.03886 -1.448308)
			)
			(stroke
				(width 0)
				(type default)
			)
			(fill yes)
			(layer "F.SilkS")
		)
		(fp_poly
			(pts
				(xy -2.252218 1.357884) (xy -2.252218 -0.706628) (xy -1.632966 -0.706628) (xy -1.632966 -1.083056)
				(xy 1.632966 -1.083056) (xy 1.632966 -0.706628) (xy 2.252218 -0.706628) (xy 2.252218 1.357884)
			)
			(stroke
				(width 0)
				(type default)
			)
			(fill no)
			(layer "F.CrtYd")
		)
		(fp_line
			(start 1.124966 -0.575056)
			(end -1.124966 -0.575056)
			(stroke
				(width 0.1)
				(type default)
			)
			(layer "F.Fab")
		)
		(fp_line
			(start -1.124966 -0.575056)
			(end -1.124966 -0.075184)
			(stroke
				(width 0.1)
				(type default)
			)
			(layer "F.Fab")
		)
		(fp_line
			(start 1.325118 -0.075184)
			(end 1.124966 -0.075184)
			(stroke
				(width 0.1)
				(type default)
			)
			(layer "F.Fab")
		)
		(fp_line
			(start 1.124966 -0.075184)
			(end 1.124966 -0.575056)
			(stroke
				(width 0.1)
				(type default)
			)
			(layer "F.Fab")
		)
		(fp_line
			(start -1.124966 -0.075184)
			(end -1.325118 -0.075184)
			(stroke
				(width 0.1)
				(type default)
			)
			(layer "F.Fab")
		)
		(fp_line
			(start -1.325118 -0.075184)
			(end -1.325118 0.574802)
			(stroke
				(width 0.1)
				(type default)
			)
			(layer "F.Fab")
		)
		(fp_line
			(start 1.325118 0.574802)
			(end 1.325118 -0.075184)
			(stroke
				(width 0.1)
				(type default)
			)
			(layer "F.Fab")
		)
		(fp_line
			(start -1.325118 0.574802)
			(end 1.325118 0.574802)
			(stroke
				(width 0.1)
				(type default)
			)
			(layer "F.Fab")
		)
		(fp_poly
			(pts
				(xy 0.918464 -1.698498) (xy 1.223264 -1.46939) (xy 0.994664 -1.46939) (xy 0.994664 -1.24079) (xy 0.842264 -1.24079)
				(xy 0.842264 -1.46939) (xy 0.613664 -1.46939)
			)
			(stroke
				(width 0)
				(type default)
			)
			(fill yes)
			(layer "F.Fab")
		)
		(fp_poly
			(pts
				(xy -0.73406 -1.677416) (xy -0.42926 -1.448308) (xy -0.65786 -1.448308) (xy -0.65786 -1.219708)
				(xy -0.81026 -1.219708) (xy -0.81026 -1.448308) (xy -1.03886 -1.448308)
			)
			(stroke
				(width 0)
				(type default)
			)
			(fill yes)
			(layer "F.Fab")
		)
		(fp_text user "1"
			(at -2.37617 0.445516 90)
			(unlocked yes)
			(layer "F.SilkS")
			(effects
				(font
					(size 0.635 0.4064)
					(thickness 0.1524)
				)
			)
		)
		(fp_text user "4"
			(at 0.350012 1.420876 0)
			(unlocked yes)
			(layer "F.SilkS")
			(effects
				(font
					(size 0.635 0.4064)
					(thickness 0.1524)
				)
			)
		)
		(fp_text user "2"
			(at -1.681988 1.420876 0)
			(unlocked yes)
			(layer "F.SilkS")
			(effects
				(font
					(size 0.635 0.4064)
					(thickness 0.1524)
				)
			)
		)
		(fp_text user "3"
			(at -0.030988 2.182876 0)
			(unlocked yes)
			(layer "F.SilkS")
			(effects
				(font
					(size 0.635 0.4064)
					(thickness 0.1524)
				)
			)
		)
		(fp_text user "1"
			(at -2.375916 0.376682 90)
			(unlocked yes)
			(layer "F.Fab")
			(effects
				(font
					(size 0.7874 0.5842)
					(thickness 0.1524)
				)
			)
		)
		(fp_text user "4"
			(at 1.727962 0.952246 90)
			(unlocked yes)
			(layer "F.Fab")
			(effects
				(font
					(size 0.7874 0.5842)
					(thickness 0.1524)
				)
			)
		)
		(fp_text user "3"
			(at 0.4953 1.283208 90)
			(unlocked yes)
			(layer "F.Fab")
			(effects
				(font
					(size 0.7874 0.5842)
					(thickness 0.1524)
				)
			)
		)
		(fp_text user "2"
			(at -0.526542 1.306576 90)
			(unlocked yes)
			(layer "F.Fab")
			(effects
				(font
					(size 0.7874 0.5842)
					(thickness 0.1524)
				)
			)
		)
		(pad "1" smd rect
			(at -1.325118 0.245872 90)
			(size 0.8382 0.889)
			(layers "F.Cu" "F.Mask" "F.Paste")
			(net "UNNAMED_14_LED4PV14_I269_1")
		)
		(pad "2" smd rect
			(at -0.424942 0.595884 90)
			(size 0.4572 0.508)
			(layers "F.Cu" "F.Mask" "F.Paste")
			(net "XP3R3V_FPGA")
		)
		(pad "3" smd rect
			(at 0.424942 0.595884 90)
			(size 0.4572 0.508)
			(layers "F.Cu" "F.Mask" "F.Paste")
			(net "UNNAMED_14_LED4PV14_I269_3")
		)
		(pad "4" smd rect
			(at 1.325118 0.245872 90)
			(size 0.8382 0.889)
			(layers "F.Cu" "F.Mask" "F.Paste")
			(net "UNNAMED_14_LED4PV14_I269_4")
		)
	)
	(footprint ""
		(layer "F.Cu")
		(at 137.414 -24.384)
		(property "Reference" "TP46"
			(at -1.0922 -1.61163 0)
			(unlocked yes)
			(layer "F.SilkS")
			(effects
				(font
					(size 0.7874 0.5842)
					(thickness 0.1524)
				)
				(justify left)
			)
		)
		(property "Value" ""
			(at 0 0 0)
			(layer "F.Fab")
			(effects
				(font
					(size 1.27 1.27)
				)
			)
		)
		(property "Device Type" "TP_PIONT-TP010CT020B030_PTH-TPA"
			(at -1.341882 0.996696 0)
			(unlocked yes)
			(layer "F.Fab")
			(hide yes)
			(effects
				(font
					(size 0.7874 0.5842)
					(thickness 0.000001)
				)
				(justify left)
			)
		)
		(duplicate_pad_numbers_are_jumpers no)
		(fp_poly
			(pts
				(arc
					(start 0.889 0)
					(mid -0.889 0)
					(end 0.889 0)
				)
			)
			(stroke
				(width 0)
				(type default)
			)
			(fill no)
			(layer "B.CrtYd")
		)
		(fp_poly
			(pts
				(arc
					(start 0.889 0)
					(mid -0.889 0)
					(end 0.889 0)
				)
			)
			(stroke
				(width 0)
				(type default)
			)
			(fill no)
			(layer "F.CrtYd")
		)
		(pad "1" thru_hole circle
			(at 0 0)
			(size 0.508 0.508)
			(drill 0.254)
			(layers "*.Cu" "*.Mask")
			(remove_unused_layers no)
			(net "FPGA_CFG_INIT_N")
			(clearance 0.1016)
			(padstack
				(mode front_inner_back)
				(layer "Inner"
					(shape circle)
					(size 0.508 0.508)
					(clearance 0.1016)
				)
				(layer "B.Cu"
					(shape circle)
					(size 0.762 0.762)
					(clearance -0.0254)
				)
			)
		)
	)
	(footprint ""
		(layer "F.Cu")
		(at 129.7432 -68.7578 180)
		(property "Reference" "U21"
			(at -0.3048 2.70383 0)
			(unlocked yes)
			(layer "F.SilkS")
			(effects
				(font
					(size 0.7874 0.5842)
					(thickness 0.1524)
				)
			)
		)
		(property "Value" ""
			(at 0 0 180)
			(layer "F.Fab")
			(effects
				(font
					(size 1.27 1.27)
				)
			)
		)
		(property "Device Type" "ISL80101IRAJZ_DFN10-G222-10136A"
			(at 0.276606 2.583688 180)
			(unlocked yes)
			(layer "F.Fab")
			(hide yes)
			(effects
				(font
					(size 0.7874 0.5842)
					(thickness 0.1524)
				)
			)
		)
		(property "User Part Number" "PARTNUM*"
			(at 0.276606 3.517646 180)
			(unlocked yes)
			(layer "Cmts.User")
			(hide yes)
			(effects
				(font
					(size 0.7874 0.5842)
					(thickness 0.1524)
				)
			)
		)
		(duplicate_pad_numbers_are_jumpers no)
		(fp_line
			(start 2.290318 1.779016)
			(end -2.290318 1.779016)
			(stroke
				(width 0.1)
				(type default)
			)
			(layer "F.SilkS")
		)
		(fp_line
			(start 2.290318 -1.779016)
			(end 2.290318 1.779016)
			(stroke
				(width 0.1)
				(type default)
			)
			(layer "F.SilkS")
		)
		(fp_line
			(start -2.290318 1.779016)
			(end -2.290318 -1.779016)
			(stroke
				(width 0.1)
				(type default)
			)
			(layer "F.SilkS")
		)
		(fp_line
			(start -2.290318 -1.779016)
			(end 2.290318 -1.779016)
			(stroke
				(width 0.1)
				(type default)
			)
			(layer "F.SilkS")
		)
		(fp_poly
			(pts
				(arc
					(start -3.315462 -1.023112)
					(mid -2.553462 -1.023112)
					(end -3.315462 -1.023112)
				)
			)
			(stroke
				(width 0)
				(type default)
			)
			(fill yes)
			(layer "F.SilkS")
		)
		(fp_poly
			(pts
				(xy -0.7239 -0.1016)
				(arc
					(start -0.7239 -0.6477)
					(mid -0.290295 -0.468095)
					(end -0.4699 -0.9017)
				)
				(xy 0.7239 -0.9017) (xy 0.7239 -0.1016)
			)
			(stroke
				(width 0)
				(type default)
			)
			(fill yes)
			(layer "F.Paste")
		)
		(fp_poly
			(pts
				(arc
					(start 0.2159 0.6477)
					(mid 0.288508 0.8255)
					(end 0.46482 0.9017)
				)
				(xy -0.7239 0.9017) (xy -0.7239 0.1016) (xy 0.7239 0.1016)
				(arc
					(start 0.7239 0.64262)
					(mid 0.647736 0.466272)
					(end 0.4699 0.3937)
				)
				(arc
					(start 0.4699 0.3937)
					(mid 0.290295 0.468095)
					(end 0.2159 0.6477)
				)
			)
			(stroke
				(width 0)
				(type default)
			)
			(fill yes)
			(layer "F.Paste")
		)
		(fp_poly
			(pts
				(xy -2.544318 2.033016) (xy 2.544318 2.033016) (xy 2.544318 -2.033016) (xy -2.544318 -2.033016)
			)
			(stroke
				(width 0)
				(type default)
			)
			(fill no)
			(layer "F.CrtYd")
		)
		(fp_line
			(start 1.525016 1.525016)
			(end -1.525016 1.525016)
			(stroke
				(width 0.1)
				(type default)
			)
			(layer "F.Fab")
		)
		(fp_line
			(start 1.525016 -1.525016)
			(end 1.525016 1.525016)
			(stroke
				(width 0.1)
				(type default)
			)
			(layer "F.Fab")
		)
		(fp_line
			(start -1.525016 1.525016)
			(end -1.525016 -1.525016)
			(stroke
				(width 0.1)
				(type default)
			)
			(layer "F.Fab")
		)
		(fp_line
			(start -1.525016 -1.525016)
			(end 1.525016 -1.525016)
			(stroke
				(width 0.1)
				(type default)
			)
			(layer "F.Fab")
		)
		(fp_poly
			(pts
				(arc
					(start -3.315462 -1.023112)
					(mid -2.553462 -1.023112)
					(end -3.315462 -1.023112)
				)
			)
			(stroke
				(width 0)
				(type default)
			)
			(fill yes)
			(layer "F.Fab")
		)
		(fp_text user "6"
			(at 2.7432 0.98425 0)
			(unlocked yes)
			(layer "F.SilkS")
			(effects
				(font
					(size 0.635 0.4064)
					(thickness 0.1524)
				)
			)
		)
		(fp_text user "10"
			(at 2.71145 -0.9398 90)
			(unlocked yes)
			(layer "F.SilkS")
			(effects
				(font
					(size 0.635 0.4064)
					(thickness 0.1524)
				)
			)
		)
		(fp_text user "5"
			(at -2.8448 0.60325 0)
			(unlocked yes)
			(layer "F.SilkS")
			(effects
				(font
					(size 0.635 0.4064)
					(thickness 0.1524)
				)
			)
		)
		(fp_text user "6"
			(at 2.6162 1.05283 0)
			(unlocked yes)
			(layer "F.Fab")
			(effects
				(font
					(size 0.7874 0.5842)
					(thickness 0.1524)
				)
			)
		)
		(fp_text user "10"
			(at 2.57683 -1.3208 90)
			(unlocked yes)
			(layer "F.Fab")
			(effects
				(font
					(size 0.7874 0.5842)
					(thickness 0.1524)
				)
			)
		)
		(fp_text user "5"
			(at -2.825496 1.29921 0)
			(unlocked yes)
			(layer "F.Fab")
			(effects
				(font
					(size 0.7874 0.5842)
					(thickness 0.1524)
				)
			)
		)
		(pad "1" smd circle
			(at -1.515618 -1.000252)
			(size 0 0)
			(layers "F.Cu" "F.Mask" "F.Paste")
			(net "XP1R8V_FPGA")
		)
		(pad "2" smd rect
			(at -1.515618 -0.500126 180)
			(size 1.0414 0.3048)
			(layers "F.Cu" "F.Mask" "F.Paste")
			(net "XP1R8V_FPGA")
		)
		(pad "3" smd rect
			(at -1.515618 0 180)
			(size 1.0414 0.3048)
			(layers "F.Cu" "F.Mask" "F.Paste")
			(net "XP1R8V_FB")
		)
		(pad "4" smd rect
			(at -1.515618 0.500126 180)
			(size 1.0414 0.3048)
			(layers "F.Cu" "F.Mask" "F.Paste")
			(net "XP1R8V_PG_R")
		)
		(pad "5" smd circle
			(at -1.515618 1.000252 180)
			(size 0 0)
			(layers "F.Cu" "F.Mask" "F.Paste")
			(net "SG")
		)
		(pad "6" smd circle
			(at 1.515618 1.000252 180)
			(size 0 0)
			(layers "F.Cu" "F.Mask" "F.Paste")
			(net "XP1R8V_SS")
		)
		(pad "7" smd rect
			(at 1.515618 0.500126 180)
			(size 1.0414 0.3048)
			(layers "F.Cu" "F.Mask" "F.Paste")
			(net "XP1R8V_EN_R")
		)
		(pad "8" smd rect
			(at 1.515618 0 180)
			(size 1.0414 0.3048)
			(layers "F.Cu" "F.Mask" "F.Paste")
			(net "Net_765")
		)
		(pad "9" smd rect
			(at 1.515618 -0.500126 180)
			(size 1.0414 0.3048)
			(layers "F.Cu" "F.Mask" "F.Paste")
			(net "XP1R8V_VIN")
		)
		(pad "10" smd circle
			(at 1.515618 -1.000252)
			(size 0 0)
			(layers "F.Cu" "F.Mask" "F.Paste")
			(net "XP1R8V_VIN")
		)
		(pad "11" smd rect
			(at 0 0 180)
			(size 1.4478 1.8034)
			(layers "F.Cu" "F.Mask" "F.Paste")
			(net "SG")
		)
	)
	(footprint ""
		(layer "F.Cu")
		(at 98.806 -24.638)
		(property "Reference" "C249"
			(at -11.43 0.16637 0)
			(unlocked yes)
			(layer "F.SilkS")
			(effects
				(font
					(size 0.7874 0.5842)
					(thickness 0.1524)
				)
			)
		)
		(property "Value" "VAL*"
			(at 0.0762 2.067306 0)
			(unlocked yes)
			(layer "F.Fab")
			(hide yes)
			(effects
				(font
					(size 0.7874 0.5842)
					(thickness 0.1524)
				)
			)
		)
		(property "Tolerance" "TOL*"
			(at 0.0762 3.032506 0)
			(unlocked yes)
			(layer "Cmts.User")
			(hide yes)
			(effects
				(font
					(size 0.7874 0.5842)
					(thickness 0.1524)
				)
			)
		)
		(property "User Part Number" "PARTNUM*"
			(at 0.1016 4.023106 0)
			(unlocked yes)
			(layer "Cmts.User")
			(hide yes)
			(effects
				(font
					(size 0.7874 0.5842)
					(thickness 0.1524)
				)
			)
		)
		(property "Device Type" "CAPACITOR-G105-0B104-EK,0.1UF,A"
			(at 0.0508 1.127506 0)
			(unlocked yes)
			(layer "F.Fab")
			(hide yes)
			(effects
				(font
					(size 0.7874 0.5842)
					(thickness 0.1524)
				)
			)
		)
		(duplicate_pad_numbers_are_jumpers no)
		(fp_line
			(start -1.143 -0.5588)
			(end -1.143 0.5588)
			(stroke
				(width 0.1)
				(type default)
			)
			(layer "F.SilkS")
		)
		(fp_line
			(start -1.143 0.5588)
			(end 1.143 0.5588)
			(stroke
				(width 0.1)
				(type default)
			)
			(layer "F.SilkS")
		)
		(fp_line
			(start 1.143 -0.5588)
			(end -1.143 -0.5588)
			(stroke
				(width 0.1)
				(type default)
			)
			(layer "F.SilkS")
		)
		(fp_line
			(start 1.143 0.5588)
			(end 1.143 -0.5588)
			(stroke
				(width 0.1)
				(type default)
			)
			(layer "F.SilkS")
		)
		(fp_rect
			(start -1.143 0.5588)
			(end 1.143 -0.5588)
			(stroke
				(width 0)
				(type default)
			)
			(fill no)
			(layer "F.CrtYd")
		)
		(fp_line
			(start -0.508 -0.3048)
			(end -0.508 0.3048)
			(stroke
				(width 0.1)
				(type default)
			)
			(layer "F.Fab")
		)
		(fp_line
			(start -0.508 0.3048)
			(end 0.508 0.3048)
			(stroke
				(width 0.1)
				(type default)
			)
			(layer "F.Fab")
		)
		(fp_line
			(start 0.508 -0.3048)
			(end -0.508 -0.3048)
			(stroke
				(width 0.1)
				(type default)
			)
			(layer "F.Fab")
		)
		(fp_line
			(start 0.508 0.3048)
			(end 0.508 -0.3048)
			(stroke
				(width 0.1)
				(type default)
			)
			(layer "F.Fab")
		)
		(pad "1" smd rect
			(at -0.5334 0)
			(size 0.7112 0.6096)
			(layers "F.Cu" "F.Mask" "F.Paste")
			(net "VDD3V3_OSC_125M")
		)
		(pad "2" smd rect
			(at 0.5334 0)
			(size 0.7112 0.6096)
			(layers "F.Cu" "F.Mask" "F.Paste")
			(net "SG")
		)
		(zone
			(layer "F.Cu")
			(hatch none 0.5)
			(connect_pads
				(clearance 0)
			)
			(min_thickness 0.25)
			(keepout
				(tracks allowed)
				(vias not_allowed)
				(pads allowed)
				(copperpour not_allowed)
				(footprints allowed)
			)
			(placement
				(enabled no)
				(sheetname "")
			)
			(fill
				(thermal_gap 0.5)
				(thermal_bridge_width 0.5)
				(island_removal_mode 0)
			)
			(polygon
				(pts
					(xy 98.7298 -24.3332) (xy 98.8822 -24.3332) (xy 98.8822 -24.9428) (xy 98.7298 -24.9428)
				)
			)
		)
	)
	(footprint ""
		(layer "F.Cu")
		(at 110.3122 -24.7142 180)
		(property "Reference" "R239"
			(at 0.9652 -8.62457 0)
			(unlocked yes)
			(layer "F.SilkS")
			(effects
				(font
					(size 0.7874 0.5842)
					(thickness 0.1524)
				)
			)
		)
		(property "Value" "VAL*"
			(at 0.02032 2.13233 180)
			(unlocked yes)
			(layer "F.Fab")
			(hide yes)
			(effects
				(font
					(size 0.7874 0.5842)
					(thickness 0.1524)
				)
			)
		)
		(property "Device Type" "RESISTOR-G155-11500-01,150OHM,A"
			(at 0.008382 1.210564 180)
			(unlocked yes)
			(layer "F.Fab")
			(hide yes)
			(effects
				(font
					(size 0.7874 0.5842)
					(thickness 0.1524)
				)
			)
		)
		(property "User Part Number" "PARTNUM*"
			(at 0.02032 4.024884 180)
			(unlocked yes)
			(layer "Cmts.User")
			(hide yes)
			(effects
				(font
					(size 0.7874 0.5842)
					(thickness 0.1524)
				)
			)
		)
		(property "Tolerance" "TOL*"
			(at 0.044704 3.05435 180)
			(unlocked yes)
			(layer "Cmts.User")
			(hide yes)
			(effects
				(font
					(size 0.7874 0.5842)
					(thickness 0.1524)
				)
			)
		)
		(duplicate_pad_numbers_are_jumpers no)
		(fp_line
			(start 1.143 0.5588)
			(end 1.143 -0.5588)
			(stroke
				(width 0.1)
				(type default)
			)
			(layer "F.SilkS")
		)
		(fp_line
			(start 1.143 -0.5588)
			(end -1.143 -0.5588)
			(stroke
				(width 0.1)
				(type default)
			)
			(layer "F.SilkS")
		)
		(fp_line
			(start -1.143 0.5588)
			(end 1.143 0.5588)
			(stroke
				(width 0.1)
				(type default)
			)
			(layer "F.SilkS")
		)
		(fp_line
			(start -1.143 -0.5588)
			(end -1.143 0.5588)
			(stroke
				(width 0.1)
				(type default)
			)
			(layer "F.SilkS")
		)
		(fp_rect
			(start 1.143 0.5588)
			(end -1.143 -0.5588)
			(stroke
				(width 0)
				(type default)
			)
			(fill no)
			(layer "F.CrtYd")
		)
		(fp_line
			(start 0.508 0.3048)
			(end 0.508 -0.3048)
			(stroke
				(width 0.1)
				(type default)
			)
			(layer "F.Fab")
		)
		(fp_line
			(start 0.508 -0.3048)
			(end -0.508 -0.3048)
			(stroke
				(width 0.1)
				(type default)
			)
			(layer "F.Fab")
		)
		(fp_line
			(start -0.508 0.3048)
			(end 0.508 0.3048)
			(stroke
				(width 0.1)
				(type default)
			)
			(layer "F.Fab")
		)
		(fp_line
			(start -0.508 -0.3048)
			(end -0.508 0.3048)
			(stroke
				(width 0.1)
				(type default)
			)
			(layer "F.Fab")
		)
		(pad "1" smd rect
			(at -0.5334 0 180)
			(size 0.7112 0.6096)
			(layers "F.Cu" "F.Mask" "F.Paste")
			(net "OSC_200M_CLKN")
		)
		(pad "2" smd rect
			(at 0.5334 0 180)
			(size 0.7112 0.6096)
			(layers "F.Cu" "F.Mask" "F.Paste")
			(net "SG")
		)
		(zone
			(layer "F.Cu")
			(hatch none 0.5)
			(connect_pads
				(clearance 0)
			)
			(min_thickness 0.25)
			(keepout
				(tracks allowed)
				(vias not_allowed)
				(pads allowed)
				(copperpour not_allowed)
				(footprints allowed)
			)
			(placement
				(enabled no)
				(sheetname "")
			)
			(fill
				(thermal_gap 0.5)
				(thermal_bridge_width 0.5)
				(island_removal_mode 0)
			)
			(polygon
				(pts
					(xy 110.236 -25.019) (xy 110.236 -24.4094) (xy 110.3884 -24.4094) (xy 110.3884 -25.019)
				)
			)
		)
	)
	(footprint ""
		(layer "F.Cu")
		(at 37.1094 -99.0854)
		(property "Reference" "C75"
			(at 1.6256 6.28777 0)
			(unlocked yes)
			(layer "F.SilkS")
			(effects
				(font
					(size 0.7874 0.5842)
					(thickness 0.1524)
				)
			)
		)
		(property "Value" "VAL*"
			(at 0.193548 2.13614 0)
			(unlocked yes)
			(layer "F.Fab")
			(hide yes)
			(effects
				(font
					(size 0.7874 0.5842)
					(thickness 0.1524)
				)
			)
		)
		(property "Tolerance" "TOL*"
			(at 0.216154 3.1496 0)
			(unlocked yes)
			(layer "Cmts.User")
			(hide yes)
			(effects
				(font
					(size 0.7874 0.5842)
					(thickness 0.1524)
				)
			)
		)
		(property "Device Type" "CAPACITOR-G104-0B103-EK,0.01UFA"
			(at 0.184404 1.180592 0)
			(unlocked yes)
			(layer "F.Fab")
			(hide yes)
			(effects
				(font
					(size 0.7874 0.5842)
					(thickness 0.1524)
				)
			)
		)
		(property "User Part Number" "PARTNUM*"
			(at 0.216154 4.185666 0)
			(unlocked yes)
			(layer "Cmts.User")
			(hide yes)
			(effects
				(font
					(size 0.7874 0.5842)
					(thickness 0.1524)
				)
			)
		)
		(duplicate_pad_numbers_are_jumpers no)
		(fp_line
			(start -0.671322 -0.4445)
			(end 0.671322 -0.4445)
			(stroke
				(width 0.1)
				(type default)
			)
			(layer "F.SilkS")
		)
		(fp_line
			(start -0.671322 0.4445)
			(end -0.671322 -0.4445)
			(stroke
				(width 0.1)
				(type default)
			)
			(layer "F.SilkS")
		)
		(fp_line
			(start 0.671322 -0.4445)
			(end 0.671322 0.4445)
			(stroke
				(width 0.1)
				(type default)
			)
			(layer "F.SilkS")
		)
		(fp_line
			(start 0.671322 0.4445)
			(end -0.671322 0.4445)
			(stroke
				(width 0.1)
				(type default)
			)
			(layer "F.SilkS")
		)
		(fp_rect
			(start 0.671322 -0.4445)
			(end -0.671322 0.4445)
			(stroke
				(width 0)
				(type default)
			)
			(fill no)
			(layer "F.CrtYd")
		)
		(fp_line
			(start -0.31496 -0.1651)
			(end -0.31496 0.1651)
			(stroke
				(width 0.1)
				(type default)
			)
			(layer "F.Fab")
		)
		(fp_line
			(start -0.31496 0.1651)
			(end 0.31496 0.1651)
			(stroke
				(width 0.1)
				(type default)
			)
			(layer "F.Fab")
		)
		(fp_line
			(start 0.31496 -0.1651)
			(end -0.31496 -0.1651)
			(stroke
				(width 0.1)
				(type default)
			)
			(layer "F.Fab")
		)
		(fp_line
			(start 0.31496 0.1651)
			(end 0.31496 -0.1651)
			(stroke
				(width 0.1)
				(type default)
			)
			(layer "F.Fab")
		)
		(pad "1" smd rect
			(at -0.264922 0)
			(size 0.3048 0.381)
			(layers "F.Cu" "F.Mask" "F.Paste")
			(net "SG")
		)
		(pad "2" smd rect
			(at 0.264922 0)
			(size 0.3048 0.381)
			(layers "F.Cu" "F.Mask" "F.Paste")
			(net "XP5R0V_PG")
		)
		(zone
			(layer "F.Cu")
			(hatch none 0.5)
			(connect_pads
				(clearance 0)
			)
			(min_thickness 0.25)
			(keepout
				(tracks allowed)
				(vias not_allowed)
				(pads allowed)
				(copperpour not_allowed)
				(footprints allowed)
			)
			(placement
				(enabled no)
				(sheetname "")
			)
			(fill
				(thermal_gap 0.5)
				(thermal_bridge_width 0.5)
				(island_removal_mode 0)
			)
			(polygon
				(pts
					(xy 37.221922 -99.2759) (xy 36.996878 -99.2759) (xy 36.996878 -98.8949) (xy 37.221922 -98.8949)
				)
			)
		)
	)
	(footprint ""
		(layer "F.Cu")
		(at 156.04998 -107.849924 -90)
		(property "Reference" "DS11"
			(at -0.100076 -2.23139 90)
			(unlocked yes)
			(layer "F.SilkS")
			(effects
				(font
					(size 0.7874 0.5842)
					(thickness 0.1524)
				)
			)
		)
		(property "Value" ""
			(at 0 0 270)
			(layer "F.Fab")
			(effects
				(font
					(size 1.27 1.27)
				)
			)
		)
		(property "Device Type" "OPTICAL-G170-10143-01"
			(at 0.1778 1.483081 270)
			(unlocked yes)
			(layer "F.Fab")
			(hide yes)
			(effects
				(font
					(size 0.786892 0.583946)
					(thickness 0.000001)
				)
			)
		)
		(property "User Part Number" "PARTNUM*"
			(at 0.1778 2.422881 270)
			(unlocked yes)
			(layer "Cmts.User")
			(hide yes)
			(effects
				(font
					(size 0.786892 0.583946)
					(thickness 0.000001)
				)
			)
		)
		(duplicate_pad_numbers_are_jumpers no)
		(fp_line
			(start -1.3208 1.0922)
			(end -2.5908 1.0922)
			(stroke
				(width 0.1)
				(type default)
			)
			(layer "F.SilkS")
		)
		(fp_line
			(start -1.397508 0.704088)
			(end -1.397508 -0.704088)
			(stroke
				(width 0.1)
				(type default)
			)
			(layer "F.SilkS")
		)
		(fp_line
			(start 1.397508 0.704088)
			(end -1.397508 0.704088)
			(stroke
				(width 0.1)
				(type default)
			)
			(layer "F.SilkS")
		)
		(fp_line
			(start -1.9558 0.4572)
			(end -1.9558 1.7272)
			(stroke
				(width 0.1)
				(type default)
			)
			(layer "F.SilkS")
		)
		(fp_line
			(start -1.397508 -0.704088)
			(end 1.397508 -0.704088)
			(stroke
				(width 0.1)
				(type default)
			)
			(layer "F.SilkS")
		)
		(fp_line
			(start 1.397508 -0.704088)
			(end 1.397508 0.704088)
			(stroke
				(width 0.1)
				(type default)
			)
			(layer "F.SilkS")
		)
		(fp_rect
			(start 1.905508 0.704088)
			(end 1.397508 -0.704088)
			(stroke
				(width 0)
				(type default)
			)
			(fill yes)
			(layer "F.SilkS")
		)
		(fp_rect
			(start 1.905508 0.958088)
			(end -1.651508 -0.958088)
			(stroke
				(width 0)
				(type default)
			)
			(fill no)
			(layer "F.CrtYd")
		)
		(fp_line
			(start -1.1938 1.2192)
			(end -2.4638 1.2192)
			(stroke
				(width 0.1)
				(type default)
			)
			(layer "F.Fab")
		)
		(fp_line
			(start -1.8288 0.5842)
			(end -1.8288 1.8542)
			(stroke
				(width 0.1)
				(type default)
			)
			(layer "F.Fab")
		)
		(fp_line
			(start -0.850138 0.450088)
			(end 0.850138 0.450088)
			(stroke
				(width 0.1)
				(type default)
			)
			(layer "F.Fab")
		)
		(fp_line
			(start 0.850138 0.450088)
			(end 0.850138 -0.450088)
			(stroke
				(width 0.1)
				(type default)
			)
			(layer "F.Fab")
		)
		(fp_line
			(start -0.850138 -0.450088)
			(end -0.850138 0.450088)
			(stroke
				(width 0.1)
				(type default)
			)
			(layer "F.Fab")
		)
		(fp_line
			(start 0.850138 -0.450088)
			(end -0.850138 -0.450088)
			(stroke
				(width 0.1)
				(type default)
			)
			(layer "F.Fab")
		)
		(fp_rect
			(start 0.850138 0.450088)
			(end 0.342138 -0.450088)
			(stroke
				(width 0)
				(type default)
			)
			(fill yes)
			(layer "F.Fab")
		)
		(fp_text user "A"
			(at -1.719326 -1.30302 0)
			(unlocked yes)
			(layer "F.SilkS")
			(effects
				(font
					(size 0.635 0.4064)
					(thickness 0.1524)
				)
			)
		)
		(fp_text user "C"
			(at 1.455674 -1.30302 0)
			(unlocked yes)
			(layer "F.SilkS")
			(effects
				(font
					(size 0.635 0.4064)
					(thickness 0.1524)
				)
			)
		)
		(fp_text user "A"
			(at -2.219706 -0.16002 0)
			(unlocked yes)
			(layer "F.Fab")
			(effects
				(font
					(size 0.7874 0.5842)
					(thickness 0.1524)
				)
			)
		)
		(fp_text user "C"
			(at 1.209294 -1.17602 0)
			(unlocked yes)
			(layer "F.Fab")
			(effects
				(font
					(size 0.7874 0.5842)
					(thickness 0.1524)
				)
			)
		)
		(pad "A" smd rect
			(at -0.749808 0 270)
			(size 0.7874 0.7874)
			(layers "F.Cu" "F.Mask" "F.Paste")
			(net "UNNAMED_14_OPTICAL_I139_A")
		)
		(pad "C" smd rect
			(at 0.749808 0 270)
			(size 0.7874 0.7874)
			(layers "F.Cu" "F.Mask" "F.Paste")
			(net "FPGA_USR_LED0")
		)
	)
	(footprint ""
		(layer "F.Cu")
		(at 101.0412 -64.2874 -90)
		(property "Reference" "R170"
			(at 2.6924 -0.85217 90)
			(unlocked yes)
			(layer "F.SilkS")
			(effects
				(font
					(size 0.7874 0.5842)
					(thickness 0.1524)
				)
			)
		)
		(property "Value" "VAL*"
			(at 0.02032 2.13233 270)
			(unlocked yes)
			(layer "F.Fab")
			(hide yes)
			(effects
				(font
					(size 0.7874 0.5842)
					(thickness 0.1524)
				)
			)
		)
		(property "Tolerance" "TOL*"
			(at 0.044704 3.05435 270)
			(unlocked yes)
			(layer "Cmts.User")
			(hide yes)
			(effects
				(font
					(size 0.7874 0.5842)
					(thickness 0.1524)
				)
			)
		)
		(property "User Part Number" "PARTNUM*"
			(at 0.02032 4.024884 270)
			(unlocked yes)
			(layer "Cmts.User")
			(hide yes)
			(effects
				(font
					(size 0.7874 0.5842)
					(thickness 0.1524)
				)
			)
		)
		(property "Device Type" "RESISTOR-G155-11002-01,10KOHM,A"
			(at 0.008382 1.210564 270)
			(unlocked yes)
			(layer "F.Fab")
			(hide yes)
			(effects
				(font
					(size 0.7874 0.5842)
					(thickness 0.1524)
				)
			)
		)
		(duplicate_pad_numbers_are_jumpers no)
		(fp_line
			(start -1.143 0.5588)
			(end 1.143 0.5588)
			(stroke
				(width 0.1)
				(type default)
			)
			(layer "F.SilkS")
		)
		(fp_line
			(start 1.143 0.5588)
			(end 1.143 -0.5588)
			(stroke
				(width 0.1)
				(type default)
			)
			(layer "F.SilkS")
		)
		(fp_line
			(start -1.143 -0.5588)
			(end -1.143 0.5588)
			(stroke
				(width 0.1)
				(type default)
			)
			(layer "F.SilkS")
		)
		(fp_line
			(start 1.143 -0.5588)
			(end -1.143 -0.5588)
			(stroke
				(width 0.1)
				(type default)
			)
			(layer "F.SilkS")
		)
		(fp_rect
			(start -1.143 0.5588)
			(end 1.143 -0.5588)
			(stroke
				(width 0)
				(type default)
			)
			(fill no)
			(layer "F.CrtYd")
		)
		(fp_line
			(start -0.508 0.3048)
			(end 0.508 0.3048)
			(stroke
				(width 0.1)
				(type default)
			)
			(layer "F.Fab")
		)
		(fp_line
			(start 0.508 0.3048)
			(end 0.508 -0.3048)
			(stroke
				(width 0.1)
				(type default)
			)
			(layer "F.Fab")
		)
		(fp_line
			(start -0.508 -0.3048)
			(end -0.508 0.3048)
			(stroke
				(width 0.1)
				(type default)
			)
			(layer "F.Fab")
		)
		(fp_line
			(start 0.508 -0.3048)
			(end -0.508 -0.3048)
			(stroke
				(width 0.1)
				(type default)
			)
			(layer "F.Fab")
		)
		(pad "1" smd rect
			(at -0.5334 0 270)
			(size 0.7112 0.6096)
			(layers "F.Cu" "F.Mask" "F.Paste")
			(net "XP3R3V_FPGA")
		)
		(pad "2" smd rect
			(at 0.5334 0 270)
			(size 0.7112 0.6096)
			(layers "F.Cu" "F.Mask" "F.Paste")
			(net "FPGA_IO_0")
		)
		(zone
			(layer "F.Cu")
			(hatch none 0.5)
			(connect_pads
				(clearance 0)
			)
			(min_thickness 0.25)
			(keepout
				(tracks allowed)
				(vias not_allowed)
				(pads allowed)
				(copperpour not_allowed)
				(footprints allowed)
			)
			(placement
				(enabled no)
				(sheetname "")
			)
			(fill
				(thermal_gap 0.5)
				(thermal_bridge_width 0.5)
				(island_removal_mode 0)
			)
			(polygon
				(pts
					(xy 100.7364 -64.3636) (xy 100.7364 -64.2112) (xy 101.346 -64.2112) (xy 101.346 -64.3636)
				)
			)
		)
	)
	(footprint ""
		(layer "F.Cu")
		(at 96.4438 -75.946 -90)
		(property "Reference" "C188"
			(at -19.177 27.82443 90)
			(unlocked yes)
			(layer "F.SilkS")
			(effects
				(font
					(size 0.7874 0.5842)
					(thickness 0.1524)
				)
			)
		)
		(property "Value" "VAL*"
			(at 0.0762 2.067306 270)
			(unlocked yes)
			(layer "F.Fab")
			(hide yes)
			(effects
				(font
					(size 0.7874 0.5842)
					(thickness 0.1524)
				)
			)
		)
		(property "Tolerance" "TOL*"
			(at 0.0762 3.032506 270)
			(unlocked yes)
			(layer "Cmts.User")
			(hide yes)
			(effects
				(font
					(size 0.7874 0.5842)
					(thickness 0.1524)
				)
			)
		)
		(property "User Part Number" "PARTNUM*"
			(at 0.1016 4.023106 270)
			(unlocked yes)
			(layer "Cmts.User")
			(hide yes)
			(effects
				(font
					(size 0.7874 0.5842)
					(thickness 0.1524)
				)
			)
		)
		(property "Device Type" "CAPACITOR-G105-0B104-EK,0.1UF,A"
			(at 0.0508 1.127506 270)
			(unlocked yes)
			(layer "F.Fab")
			(hide yes)
			(effects
				(font
					(size 0.7874 0.5842)
					(thickness 0.1524)
				)
			)
		)
		(duplicate_pad_numbers_are_jumpers no)
		(fp_line
			(start -1.143 0.5588)
			(end 1.143 0.5588)
			(stroke
				(width 0.1)
				(type default)
			)
			(layer "F.SilkS")
		)
		(fp_line
			(start 1.143 0.5588)
			(end 1.143 -0.5588)
			(stroke
				(width 0.1)
				(type default)
			)
			(layer "F.SilkS")
		)
		(fp_line
			(start -1.143 -0.5588)
			(end -1.143 0.5588)
			(stroke
				(width 0.1)
				(type default)
			)
			(layer "F.SilkS")
		)
		(fp_line
			(start 1.143 -0.5588)
			(end -1.143 -0.5588)
			(stroke
				(width 0.1)
				(type default)
			)
			(layer "F.SilkS")
		)
		(fp_rect
			(start -1.143 0.5588)
			(end 1.143 -0.5588)
			(stroke
				(width 0)
				(type default)
			)
			(fill no)
			(layer "F.CrtYd")
		)
		(fp_line
			(start -0.508 0.3048)
			(end 0.508 0.3048)
			(stroke
				(width 0.1)
				(type default)
			)
			(layer "F.Fab")
		)
		(fp_line
			(start 0.508 0.3048)
			(end 0.508 -0.3048)
			(stroke
				(width 0.1)
				(type default)
			)
			(layer "F.Fab")
		)
		(fp_line
			(start -0.508 -0.3048)
			(end -0.508 0.3048)
			(stroke
				(width 0.1)
				(type default)
			)
			(layer "F.Fab")
		)
		(fp_line
			(start 0.508 -0.3048)
			(end -0.508 -0.3048)
			(stroke
				(width 0.1)
				(type default)
			)
			(layer "F.Fab")
		)
		(pad "1" smd rect
			(at -0.5334 0 270)
			(size 0.7112 0.6096)
			(layers "F.Cu" "F.Mask" "F.Paste")
			(net "XP1R2V_VIN")
		)
		(pad "2" smd rect
			(at 0.5334 0 270)
			(size 0.7112 0.6096)
			(layers "F.Cu" "F.Mask" "F.Paste")
			(net "SG")
		)
		(zone
			(layer "F.Cu")
			(hatch none 0.5)
			(connect_pads
				(clearance 0)
			)
			(min_thickness 0.25)
			(keepout
				(tracks allowed)
				(vias not_allowed)
				(pads allowed)
				(copperpour not_allowed)
				(footprints allowed)
			)
			(placement
				(enabled no)
				(sheetname "")
			)
			(fill
				(thermal_gap 0.5)
				(thermal_bridge_width 0.5)
				(island_removal_mode 0)
			)
			(polygon
				(pts
					(xy 96.139 -76.0222) (xy 96.139 -75.8698) (xy 96.7486 -75.8698) (xy 96.7486 -76.0222)
				)
			)
		)
	)
	(footprint ""
		(layer "F.Cu")
		(at 11.557 -42.291 90)
		(property "Reference" "R499"
			(at 0 -1.16205 90)
			(unlocked yes)
			(layer "F.SilkS")
			(effects
				(font
					(size 0.635 0.4064)
					(thickness 0.1524)
				)
			)
		)
		(property "Value" "VAL*"
			(at 0.02032 2.13233 90)
			(unlocked yes)
			(layer "F.Fab")
			(hide yes)
			(effects
				(font
					(size 0.7874 0.5842)
					(thickness 0.1524)
				)
			)
		)
		(property "Tolerance" "TOL*"
			(at 0.044704 3.05435 90)
			(unlocked yes)
			(layer "Cmts.User")
			(hide yes)
			(effects
				(font
					(size 0.7874 0.5842)
					(thickness 0.1524)
				)
			)
		)
		(property "User Part Number" "PARTNUM*"
			(at 0.02032 4.024884 90)
			(unlocked yes)
			(layer "Cmts.User")
			(hide yes)
			(effects
				(font
					(size 0.7874 0.5842)
					(thickness 0.1524)
				)
			)
		)
		(property "Device Type" "RESISTOR-G155-11004-01,1MOHM,1%"
			(at 0.008382 1.210564 90)
			(unlocked yes)
			(layer "F.Fab")
			(hide yes)
			(effects
				(font
					(size 0.7874 0.5842)
					(thickness 0.1524)
				)
			)
		)
		(duplicate_pad_numbers_are_jumpers no)
		(fp_line
			(start 1.143 -0.5588)
			(end -1.143 -0.5588)
			(stroke
				(width 0.1)
				(type default)
			)
			(layer "F.SilkS")
		)
		(fp_line
			(start -1.143 -0.5588)
			(end -1.143 0.5588)
			(stroke
				(width 0.1)
				(type default)
			)
			(layer "F.SilkS")
		)
		(fp_line
			(start 1.143 0.5588)
			(end 1.143 -0.5588)
			(stroke
				(width 0.1)
				(type default)
			)
			(layer "F.SilkS")
		)
		(fp_line
			(start -1.143 0.5588)
			(end 1.143 0.5588)
			(stroke
				(width 0.1)
				(type default)
			)
			(layer "F.SilkS")
		)
		(fp_poly
			(pts
				(xy -1.143 0.5588) (xy 1.143 0.5588) (xy 1.143 -0.5588) (xy -1.143 -0.5588)
			)
			(stroke
				(width 0)
				(type default)
			)
			(fill no)
			(layer "F.CrtYd")
		)
		(fp_line
			(start 0.508 -0.3048)
			(end -0.508 -0.3048)
			(stroke
				(width 0.1)
				(type default)
			)
			(layer "F.Fab")
		)
		(fp_line
			(start -0.508 -0.3048)
			(end -0.508 0.3048)
			(stroke
				(width 0.1)
				(type default)
			)
			(layer "F.Fab")
		)
		(fp_line
			(start 0.508 0.3048)
			(end 0.508 -0.3048)
			(stroke
				(width 0.1)
				(type default)
			)
			(layer "F.Fab")
		)
		(fp_line
			(start -0.508 0.3048)
			(end 0.508 0.3048)
			(stroke
				(width 0.1)
				(type default)
			)
			(layer "F.Fab")
		)
		(pad "1" smd rect
			(at -0.5334 0 90)
			(size 0.7112 0.6096)
			(layers "F.Cu" "F.Mask" "F.Paste")
			(net "SG")
		)
		(pad "2" smd rect
			(at 0.5334 0 90)
			(size 0.7112 0.6096)
			(layers "F.Cu" "F.Mask" "F.Paste")
			(net "BF_SMA2_SIG_IO_CONN")
		)
		(zone
			(layer "F.Cu")
			(hatch none 0.5)
			(connect_pads
				(clearance 0)
			)
			(min_thickness 0.25)
			(keepout
				(tracks allowed)
				(vias not_allowed)
				(pads allowed)
				(copperpour not_allowed)
				(footprints allowed)
			)
			(placement
				(enabled no)
				(sheetname "")
			)
			(fill
				(thermal_gap 0.5)
				(thermal_bridge_width 0.5)
				(island_removal_mode 0)
			)
			(polygon
				(pts
					(xy 11.8618 -42.2148) (xy 11.8618 -42.3672) (xy 11.2522 -42.3672) (xy 11.2522 -42.2148)
				)
			)
		)
		(zone
			(layer "F.Cu")
			(hatch none 0.5)
			(connect_pads
				(clearance 0)
			)
			(min_thickness 0.25)
			(keepout
				(tracks not_allowed)
				(vias allowed)
				(pads allowed)
				(copperpour not_allowed)
				(footprints allowed)
			)
			(placement
				(enabled no)
				(sheetname "")
			)
			(fill
				(thermal_gap 0.5)
				(thermal_bridge_width 0.5)
				(island_removal_mode 0)
			)
			(polygon
				(pts
					(xy 11.8618 -42.2148) (xy 11.8618 -42.3672) (xy 11.2522 -42.3672) (xy 11.2522 -42.2148)
				)
			)
		)
	)
	(footprint ""
		(layer "F.Cu")
		(at 18.415 -81.28 180)
		(property "Reference" "R472"
			(at 0.635 -2.32537 0)
			(unlocked yes)
			(layer "F.SilkS")
			(effects
				(font
					(size 0.7874 0.5842)
					(thickness 0.1524)
				)
			)
		)
		(property "Value" "VAL*"
			(at 0.02032 2.13233 180)
			(unlocked yes)
			(layer "F.Fab")
			(hide yes)
			(effects
				(font
					(size 0.7874 0.5842)
					(thickness 0.1524)
				)
			)
		)
		(property "Tolerance" "TOL*"
			(at 0.044704 3.05435 180)
			(unlocked yes)
			(layer "Cmts.User")
			(hide yes)
			(effects
				(font
					(size 0.7874 0.5842)
					(thickness 0.1524)
				)
			)
		)
		(property "User Part Number" "PARTNUM*"
			(at 0.02032 4.024884 180)
			(unlocked yes)
			(layer "Cmts.User")
			(hide yes)
			(effects
				(font
					(size 0.7874 0.5842)
					(thickness 0.1524)
				)
			)
		)
		(property "Device Type" "RESISTOR-G155-100R0-J0,0OHM,-"
			(at 0.008382 1.210564 180)
			(unlocked yes)
			(layer "F.Fab")
			(hide yes)
			(effects
				(font
					(size 0.7874 0.5842)
					(thickness 0.1524)
				)
			)
		)
		(duplicate_pad_numbers_are_jumpers no)
		(fp_line
			(start 1.143 0.5588)
			(end 1.143 -0.5588)
			(stroke
				(width 0.1)
				(type default)
			)
			(layer "F.SilkS")
		)
		(fp_line
			(start 1.143 -0.5588)
			(end -1.143 -0.5588)
			(stroke
				(width 0.1)
				(type default)
			)
			(layer "F.SilkS")
		)
		(fp_line
			(start -1.143 0.5588)
			(end 1.143 0.5588)
			(stroke
				(width 0.1)
				(type default)
			)
			(layer "F.SilkS")
		)
		(fp_line
			(start -1.143 -0.5588)
			(end -1.143 0.5588)
			(stroke
				(width 0.1)
				(type default)
			)
			(layer "F.SilkS")
		)
		(fp_poly
			(pts
				(xy -1.143 0.5588) (xy 1.143 0.5588) (xy 1.143 -0.5588) (xy -1.143 -0.5588)
			)
			(stroke
				(width 0)
				(type default)
			)
			(fill no)
			(layer "F.CrtYd")
		)
		(fp_line
			(start 0.508 0.3048)
			(end 0.508 -0.3048)
			(stroke
				(width 0.1)
				(type default)
			)
			(layer "F.Fab")
		)
		(fp_line
			(start 0.508 -0.3048)
			(end -0.508 -0.3048)
			(stroke
				(width 0.1)
				(type default)
			)
			(layer "F.Fab")
		)
		(fp_line
			(start -0.508 0.3048)
			(end 0.508 0.3048)
			(stroke
				(width 0.1)
				(type default)
			)
			(layer "F.Fab")
		)
		(fp_line
			(start -0.508 -0.3048)
			(end -0.508 0.3048)
			(stroke
				(width 0.1)
				(type default)
			)
			(layer "F.Fab")
		)
		(pad "1" smd rect
			(at -0.5334 0 180)
			(size 0.7112 0.6096)
			(layers "F.Cu" "F.Mask" "F.Paste")
			(net "R_FT4232_I2C_SDA_OUT")
		)
		(pad "2" smd rect
			(at 0.5334 0 180)
			(size 0.7112 0.6096)
			(layers "F.Cu" "F.Mask" "F.Paste")
			(net "FT4232_I2C_SDA")
		)
		(zone
			(layer "F.Cu")
			(hatch none 0.5)
			(connect_pads
				(clearance 0)
			)
			(min_thickness 0.25)
			(keepout
				(tracks not_allowed)
				(vias allowed)
				(pads allowed)
				(copperpour not_allowed)
				(footprints allowed)
			)
			(placement
				(enabled no)
				(sheetname "")
			)
			(fill
				(thermal_gap 0.5)
				(thermal_bridge_width 0.5)
				(island_removal_mode 0)
			)
			(polygon
				(pts
					(xy 18.4912 -81.5848) (xy 18.3388 -81.5848) (xy 18.3388 -80.9752) (xy 18.4912 -80.9752)
				)
			)
		)
		(zone
			(layer "F.Cu")
			(hatch none 0.5)
			(connect_pads
				(clearance 0)
			)
			(min_thickness 0.25)
			(keepout
				(tracks allowed)
				(vias not_allowed)
				(pads allowed)
				(copperpour not_allowed)
				(footprints allowed)
			)
			(placement
				(enabled no)
				(sheetname "")
			)
			(fill
				(thermal_gap 0.5)
				(thermal_bridge_width 0.5)
				(island_removal_mode 0)
			)
			(polygon
				(pts
					(xy 18.4912 -81.5848) (xy 18.3388 -81.5848) (xy 18.3388 -80.9752) (xy 18.4912 -80.9752)
				)
			)
		)
	)
	(footprint ""
		(layer "F.Cu")
		(at 7.1374 -39.318692 90)
		(property "Reference" "R272"
			(at 2.337308 0.08255 90)
			(unlocked yes)
			(layer "F.SilkS")
			(effects
				(font
					(size 0.635 0.4064)
					(thickness 0.1524)
				)
			)
		)
		(property "Value" "VAL*"
			(at 0.02032 2.13233 90)
			(unlocked yes)
			(layer "F.Fab")
			(hide yes)
			(effects
				(font
					(size 0.7874 0.5842)
					(thickness 0.1524)
				)
			)
		)
		(property "Device Type" "RESISTOR-G155-11000-01,100OHM,A"
			(at 0.008382 1.210564 90)
			(unlocked yes)
			(layer "F.Fab")
			(hide yes)
			(effects
				(font
					(size 0.7874 0.5842)
					(thickness 0.1524)
				)
			)
		)
		(property "User Part Number" "PARTNUM*"
			(at 0.02032 4.024884 90)
			(unlocked yes)
			(layer "Cmts.User")
			(hide yes)
			(effects
				(font
					(size 0.7874 0.5842)
					(thickness 0.1524)
				)
			)
		)
		(property "Tolerance" "TOL*"
			(at 0.044704 3.05435 90)
			(unlocked yes)
			(layer "Cmts.User")
			(hide yes)
			(effects
				(font
					(size 0.7874 0.5842)
					(thickness 0.1524)
				)
			)
		)
		(duplicate_pad_numbers_are_jumpers no)
		(fp_line
			(start 1.143 -0.5588)
			(end -1.143 -0.5588)
			(stroke
				(width 0.1)
				(type default)
			)
			(layer "F.SilkS")
		)
		(fp_line
			(start -1.143 -0.5588)
			(end -1.143 0.5588)
			(stroke
				(width 0.1)
				(type default)
			)
			(layer "F.SilkS")
		)
		(fp_line
			(start 1.143 0.5588)
			(end 1.143 -0.5588)
			(stroke
				(width 0.1)
				(type default)
			)
			(layer "F.SilkS")
		)
		(fp_line
			(start -1.143 0.5588)
			(end 1.143 0.5588)
			(stroke
				(width 0.1)
				(type default)
			)
			(layer "F.SilkS")
		)
		(fp_poly
			(pts
				(xy -1.143 0.5588) (xy 1.143 0.5588) (xy 1.143 -0.5588) (xy -1.143 -0.5588)
			)
			(stroke
				(width 0)
				(type default)
			)
			(fill no)
			(layer "F.CrtYd")
		)
		(fp_line
			(start 0.508 -0.3048)
			(end -0.508 -0.3048)
			(stroke
				(width 0.1)
				(type default)
			)
			(layer "F.Fab")
		)
		(fp_line
			(start -0.508 -0.3048)
			(end -0.508 0.3048)
			(stroke
				(width 0.1)
				(type default)
			)
			(layer "F.Fab")
		)
		(fp_line
			(start 0.508 0.3048)
			(end 0.508 -0.3048)
			(stroke
				(width 0.1)
				(type default)
			)
			(layer "F.Fab")
		)
		(fp_line
			(start -0.508 0.3048)
			(end 0.508 0.3048)
			(stroke
				(width 0.1)
				(type default)
			)
			(layer "F.Fab")
		)
		(pad "1" smd rect
			(at -0.5334 0 90)
			(size 0.7112 0.6096)
			(layers "F.Cu" "F.Mask" "F.Paste")
			(net "FPGA_OUT_SMA1_LED_RED_N")
		)
		(pad "2" smd rect
			(at 0.5334 0 90)
			(size 0.7112 0.6096)
			(layers "F.Cu" "F.Mask" "F.Paste")
			(net "UNNAMED_14_LED4PV14_I265_3")
		)
		(zone
			(layer "F.Cu")
			(hatch none 0.5)
			(connect_pads
				(clearance 0)
			)
			(min_thickness 0.25)
			(keepout
				(tracks allowed)
				(vias not_allowed)
				(pads allowed)
				(copperpour not_allowed)
				(footprints allowed)
			)
			(placement
				(enabled no)
				(sheetname "")
			)
			(fill
				(thermal_gap 0.5)
				(thermal_bridge_width 0.5)
				(island_removal_mode 0)
			)
			(polygon
				(pts
					(xy 7.4422 -39.242492) (xy 7.4422 -39.394892) (xy 6.8326 -39.394892) (xy 6.8326 -39.242492)
				)
			)
		)
		(zone
			(layer "F.Cu")
			(hatch none 0.5)
			(connect_pads
				(clearance 0)
			)
			(min_thickness 0.25)
			(keepout
				(tracks not_allowed)
				(vias allowed)
				(pads allowed)
				(copperpour not_allowed)
				(footprints allowed)
			)
			(placement
				(enabled no)
				(sheetname "")
			)
			(fill
				(thermal_gap 0.5)
				(thermal_bridge_width 0.5)
				(island_removal_mode 0)
			)
			(polygon
				(pts
					(xy 7.4422 -39.242492) (xy 7.4422 -39.394892) (xy 6.8326 -39.394892) (xy 6.8326 -39.242492)
				)
			)
		)
	)
	(footprint ""
		(layer "F.Cu")
		(at 100.076 -56.769)
		(property "Reference" "TP186"
			(at 2.06375 0.4318 90)
			(unlocked yes)
			(layer "F.SilkS")
			(effects
				(font
					(size 0.635 0.4064)
					(thickness 0.1524)
				)
				(justify left)
			)
		)
		(property "Value" ""
			(at 0 0 0)
			(layer "F.Fab")
			(effects
				(font
					(size 1.27 1.27)
				)
			)
		)
		(property "Device Type" "TP_PIONT-TP010CT020B030_PTH-TPA"
			(at -1.341882 0.996696 0)
			(unlocked yes)
			(layer "F.Fab")
			(hide yes)
			(effects
				(font
					(size 0.7874 0.5842)
					(thickness 0.1524)
				)
				(justify left)
			)
		)
		(duplicate_pad_numbers_are_jumpers no)
		(fp_poly
			(pts
				(arc
					(start 0.889 0)
					(mid -0.889 0)
					(end 0.889 0)
				)
			)
			(stroke
				(width 0)
				(type default)
			)
			(fill no)
			(layer "B.CrtYd")
		)
		(fp_poly
			(pts
				(arc
					(start 0.889 0)
					(mid -0.889 0)
					(end 0.889 0)
				)
			)
			(stroke
				(width 0)
				(type default)
			)
			(fill no)
			(layer "F.CrtYd")
		)
		(pad "1" thru_hole circle
			(at 0 0)
			(size 0.508 0.508)
			(drill 0.254)
			(layers "*.Cu" "*.Mask")
			(remove_unused_layers no)
			(net "IO_L23N_16")
			(clearance 0.1016)
			(padstack
				(mode front_inner_back)
				(layer "Inner"
					(shape circle)
					(size 0.508 0.508)
					(clearance 0.1016)
				)
				(layer "B.Cu"
					(shape circle)
					(size 0.762 0.762)
					(clearance -0.0254)
				)
			)
		)
	)
	(footprint ""
		(layer "F.Cu")
		(at 99.5426 -64.2874 -90)
		(property "Reference" "R172"
			(at 2.6924 -0.69977 90)
			(unlocked yes)
			(layer "F.SilkS")
			(effects
				(font
					(size 0.7874 0.5842)
					(thickness 0.1524)
				)
			)
		)
		(property "Value" "VAL*"
			(at 0.02032 2.13233 270)
			(unlocked yes)
			(layer "F.Fab")
			(hide yes)
			(effects
				(font
					(size 0.7874 0.5842)
					(thickness 0.1524)
				)
			)
		)
		(property "Tolerance" "TOL*"
			(at 0.044704 3.05435 270)
			(unlocked yes)
			(layer "Cmts.User")
			(hide yes)
			(effects
				(font
					(size 0.7874 0.5842)
					(thickness 0.1524)
				)
			)
		)
		(property "User Part Number" "PARTNUM*"
			(at 0.02032 4.024884 270)
			(unlocked yes)
			(layer "Cmts.User")
			(hide yes)
			(effects
				(font
					(size 0.7874 0.5842)
					(thickness 0.1524)
				)
			)
		)
		(property "Device Type" "RESISTOR-G155-11002-01,10KOHM,A"
			(at 0.008382 1.210564 270)
			(unlocked yes)
			(layer "F.Fab")
			(hide yes)
			(effects
				(font
					(size 0.7874 0.5842)
					(thickness 0.1524)
				)
			)
		)
		(duplicate_pad_numbers_are_jumpers no)
		(fp_line
			(start -1.143 0.5588)
			(end 1.143 0.5588)
			(stroke
				(width 0.1)
				(type default)
			)
			(layer "F.SilkS")
		)
		(fp_line
			(start 1.143 0.5588)
			(end 1.143 -0.5588)
			(stroke
				(width 0.1)
				(type default)
			)
			(layer "F.SilkS")
		)
		(fp_line
			(start -1.143 -0.5588)
			(end -1.143 0.5588)
			(stroke
				(width 0.1)
				(type default)
			)
			(layer "F.SilkS")
		)
		(fp_line
			(start 1.143 -0.5588)
			(end -1.143 -0.5588)
			(stroke
				(width 0.1)
				(type default)
			)
			(layer "F.SilkS")
		)
		(fp_rect
			(start 1.143 0.5588)
			(end -1.143 -0.5588)
			(stroke
				(width 0)
				(type default)
			)
			(fill no)
			(layer "F.CrtYd")
		)
		(fp_line
			(start -0.508 0.3048)
			(end 0.508 0.3048)
			(stroke
				(width 0.1)
				(type default)
			)
			(layer "F.Fab")
		)
		(fp_line
			(start 0.508 0.3048)
			(end 0.508 -0.3048)
			(stroke
				(width 0.1)
				(type default)
			)
			(layer "F.Fab")
		)
		(fp_line
			(start -0.508 -0.3048)
			(end -0.508 0.3048)
			(stroke
				(width 0.1)
				(type default)
			)
			(layer "F.Fab")
		)
		(fp_line
			(start 0.508 -0.3048)
			(end -0.508 -0.3048)
			(stroke
				(width 0.1)
				(type default)
			)
			(layer "F.Fab")
		)
		(pad "1" smd rect
			(at -0.5334 0 270)
			(size 0.7112 0.6096)
			(layers "F.Cu" "F.Mask" "F.Paste")
			(net "XP3R3V_FPGA")
		)
		(pad "2" smd rect
			(at 0.5334 0 270)
			(size 0.7112 0.6096)
			(layers "F.Cu" "F.Mask" "F.Paste")
			(net "FPGA_IO_1")
		)
		(zone
			(layer "F.Cu")
			(hatch none 0.5)
			(connect_pads
				(clearance 0)
			)
			(min_thickness 0.25)
			(keepout
				(tracks allowed)
				(vias not_allowed)
				(pads allowed)
				(copperpour not_allowed)
				(footprints allowed)
			)
			(placement
				(enabled no)
				(sheetname "")
			)
			(fill
				(thermal_gap 0.5)
				(thermal_bridge_width 0.5)
				(island_removal_mode 0)
			)
			(polygon
				(pts
					(xy 99.2378 -64.2112) (xy 99.8474 -64.2112) (xy 99.8474 -64.3636) (xy 99.2378 -64.3636)
				)
			)
		)
	)
	(footprint ""
		(layer "F.Cu")
		(at 15.494 -83.566)
		(property "Reference" "R445"
			(at -1.397 1.18237 0)
			(unlocked yes)
			(layer "F.SilkS")
			(effects
				(font
					(size 0.7874 0.5842)
					(thickness 0.1524)
				)
			)
		)
		(property "Value" "VAL*"
			(at 0.02032 2.13233 0)
			(unlocked yes)
			(layer "F.Fab")
			(hide yes)
			(effects
				(font
					(size 0.7874 0.5842)
					(thickness 0.1524)
				)
			)
		)
		(property "Tolerance" "TOL*"
			(at 0.044704 3.05435 0)
			(unlocked yes)
			(layer "Cmts.User")
			(hide yes)
			(effects
				(font
					(size 0.7874 0.5842)
					(thickness 0.1524)
				)
			)
		)
		(property "User Part Number" "PARTNUM*"
			(at 0.02032 4.024884 0)
			(unlocked yes)
			(layer "Cmts.User")
			(hide yes)
			(effects
				(font
					(size 0.7874 0.5842)
					(thickness 0.1524)
				)
			)
		)
		(property "Device Type" "RESISTOR-G155-05101-01,5.1KOHMA"
			(at 0.008382 1.210564 0)
			(unlocked yes)
			(layer "F.Fab")
			(hide yes)
			(effects
				(font
					(size 0.7874 0.5842)
					(thickness 0.1524)
				)
			)
		)
		(duplicate_pad_numbers_are_jumpers no)
		(fp_line
			(start -1.143 -0.5588)
			(end -1.143 0.5588)
			(stroke
				(width 0.1)
				(type default)
			)
			(layer "F.SilkS")
		)
		(fp_line
			(start -1.143 0.5588)
			(end 1.143 0.5588)
			(stroke
				(width 0.1)
				(type default)
			)
			(layer "F.SilkS")
		)
		(fp_line
			(start 1.143 -0.5588)
			(end -1.143 -0.5588)
			(stroke
				(width 0.1)
				(type default)
			)
			(layer "F.SilkS")
		)
		(fp_line
			(start 1.143 0.5588)
			(end 1.143 -0.5588)
			(stroke
				(width 0.1)
				(type default)
			)
			(layer "F.SilkS")
		)
		(fp_poly
			(pts
				(xy -1.143 0.5588) (xy 1.143 0.5588) (xy 1.143 -0.5588) (xy -1.143 -0.5588)
			)
			(stroke
				(width 0)
				(type default)
			)
			(fill no)
			(layer "F.CrtYd")
		)
		(fp_line
			(start -0.508 -0.3048)
			(end -0.508 0.3048)
			(stroke
				(width 0.1)
				(type default)
			)
			(layer "F.Fab")
		)
		(fp_line
			(start -0.508 0.3048)
			(end 0.508 0.3048)
			(stroke
				(width 0.1)
				(type default)
			)
			(layer "F.Fab")
		)
		(fp_line
			(start 0.508 -0.3048)
			(end -0.508 -0.3048)
			(stroke
				(width 0.1)
				(type default)
			)
			(layer "F.Fab")
		)
		(fp_line
			(start 0.508 0.3048)
			(end 0.508 -0.3048)
			(stroke
				(width 0.1)
				(type default)
			)
			(layer "F.Fab")
		)
		(pad "1" smd rect
			(at -0.5334 0)
			(size 0.7112 0.6096)
			(layers "F.Cu" "F.Mask" "F.Paste")
			(net "UNNAMED_524_CONNUSB14PGH4FRAT_1")
		)
		(pad "2" smd rect
			(at 0.5334 0)
			(size 0.7112 0.6096)
			(layers "F.Cu" "F.Mask" "F.Paste")
			(net "SG")
		)
		(zone
			(layer "F.Cu")
			(hatch none 0.5)
			(connect_pads
				(clearance 0)
			)
			(min_thickness 0.25)
			(keepout
				(tracks not_allowed)
				(vias allowed)
				(pads allowed)
				(copperpour not_allowed)
				(footprints allowed)
			)
			(placement
				(enabled no)
				(sheetname "")
			)
			(fill
				(thermal_gap 0.5)
				(thermal_bridge_width 0.5)
				(island_removal_mode 0)
			)
			(polygon
				(pts
					(xy 15.4178 -83.2612) (xy 15.5702 -83.2612) (xy 15.5702 -83.8708) (xy 15.4178 -83.8708)
				)
			)
		)
		(zone
			(layer "F.Cu")
			(hatch none 0.5)
			(connect_pads
				(clearance 0)
			)
			(min_thickness 0.25)
			(keepout
				(tracks allowed)
				(vias not_allowed)
				(pads allowed)
				(copperpour not_allowed)
				(footprints allowed)
			)
			(placement
				(enabled no)
				(sheetname "")
			)
			(fill
				(thermal_gap 0.5)
				(thermal_bridge_width 0.5)
				(island_removal_mode 0)
			)
			(polygon
				(pts
					(xy 15.4178 -83.2612) (xy 15.5702 -83.2612) (xy 15.5702 -83.8708) (xy 15.4178 -83.8708)
				)
			)
		)
	)
	(footprint ""
		(layer "F.Cu")
		(at 103.632 -24.638)
		(property "Reference" "R242"
			(at -10.033 0.16637 0)
			(unlocked yes)
			(layer "F.SilkS")
			(effects
				(font
					(size 0.7874 0.5842)
					(thickness 0.1524)
				)
			)
		)
		(property "Value" "VAL*"
			(at 0.02032 2.13233 0)
			(unlocked yes)
			(layer "F.Fab")
			(hide yes)
			(effects
				(font
					(size 0.7874 0.5842)
					(thickness 0.1524)
				)
			)
		)
		(property "Tolerance" "TOL*"
			(at 0.044704 3.05435 0)
			(unlocked yes)
			(layer "Cmts.User")
			(hide yes)
			(effects
				(font
					(size 0.7874 0.5842)
					(thickness 0.1524)
				)
			)
		)
		(property "User Part Number" "PARTNUM*"
			(at 0.02032 4.024884 0)
			(unlocked yes)
			(layer "Cmts.User")
			(hide yes)
			(effects
				(font
					(size 0.7874 0.5842)
					(thickness 0.1524)
				)
			)
		)
		(property "Device Type" "RESISTOR-G155-11500-01,150OHM,A"
			(at 0.008382 1.210564 0)
			(unlocked yes)
			(layer "F.Fab")
			(hide yes)
			(effects
				(font
					(size 0.7874 0.5842)
					(thickness 0.1524)
				)
			)
		)
		(duplicate_pad_numbers_are_jumpers no)
		(fp_line
			(start -1.143 -0.5588)
			(end -1.143 0.5588)
			(stroke
				(width 0.1)
				(type default)
			)
			(layer "F.SilkS")
		)
		(fp_line
			(start -1.143 0.5588)
			(end 1.143 0.5588)
			(stroke
				(width 0.1)
				(type default)
			)
			(layer "F.SilkS")
		)
		(fp_line
			(start 1.143 -0.5588)
			(end -1.143 -0.5588)
			(stroke
				(width 0.1)
				(type default)
			)
			(layer "F.SilkS")
		)
		(fp_line
			(start 1.143 0.5588)
			(end 1.143 -0.5588)
			(stroke
				(width 0.1)
				(type default)
			)
			(layer "F.SilkS")
		)
		(fp_rect
			(start -1.143 0.5588)
			(end 1.143 -0.5588)
			(stroke
				(width 0)
				(type default)
			)
			(fill no)
			(layer "F.CrtYd")
		)
		(fp_line
			(start -0.508 -0.3048)
			(end -0.508 0.3048)
			(stroke
				(width 0.1)
				(type default)
			)
			(layer "F.Fab")
		)
		(fp_line
			(start -0.508 0.3048)
			(end 0.508 0.3048)
			(stroke
				(width 0.1)
				(type default)
			)
			(layer "F.Fab")
		)
		(fp_line
			(start 0.508 -0.3048)
			(end -0.508 -0.3048)
			(stroke
				(width 0.1)
				(type default)
			)
			(layer "F.Fab")
		)
		(fp_line
			(start 0.508 0.3048)
			(end 0.508 -0.3048)
			(stroke
				(width 0.1)
				(type default)
			)
			(layer "F.Fab")
		)
		(pad "1" smd rect
			(at -0.5334 0)
			(size 0.7112 0.6096)
			(layers "F.Cu" "F.Mask" "F.Paste")
			(net "OSC_125M_CLKP")
		)
		(pad "2" smd rect
			(at 0.5334 0)
			(size 0.7112 0.6096)
			(layers "F.Cu" "F.Mask" "F.Paste")
			(net "SG")
		)
		(zone
			(layer "F.Cu")
			(hatch none 0.5)
			(connect_pads
				(clearance 0)
			)
			(min_thickness 0.25)
			(keepout
				(tracks allowed)
				(vias not_allowed)
				(pads allowed)
				(copperpour not_allowed)
				(footprints allowed)
			)
			(placement
				(enabled no)
				(sheetname "")
			)
			(fill
				(thermal_gap 0.5)
				(thermal_bridge_width 0.5)
				(island_removal_mode 0)
			)
			(polygon
				(pts
					(xy 103.5558 -24.3332) (xy 103.7082 -24.3332) (xy 103.7082 -24.9428) (xy 103.5558 -24.9428)
				)
			)
		)
	)
	(footprint ""
		(layer "F.Cu")
		(at 31.115 -96.266)
		(property "Reference" "C87"
			(at 3.08737 1.016 90)
			(unlocked yes)
			(layer "F.SilkS")
			(effects
				(font
					(size 0.7874 0.5842)
					(thickness 0.1524)
				)
			)
		)
		(property "Value" "VAL*"
			(at 0.193548 2.13614 0)
			(unlocked yes)
			(layer "F.Fab")
			(hide yes)
			(effects
				(font
					(size 0.7874 0.5842)
					(thickness 0.1524)
				)
			)
		)
		(property "Tolerance" "TOL*"
			(at 0.216154 3.1496 0)
			(unlocked yes)
			(layer "Cmts.User")
			(hide yes)
			(effects
				(font
					(size 0.7874 0.5842)
					(thickness 0.1524)
				)
			)
		)
		(property "Device Type" "CAPACITOR-G104-0A180-FJ,18PF,5%"
			(at 0.184404 1.180592 0)
			(unlocked yes)
			(layer "F.Fab")
			(hide yes)
			(effects
				(font
					(size 0.7874 0.5842)
					(thickness 0.1524)
				)
			)
		)
		(property "User Part Number" "PARTNUM*"
			(at 0.216154 4.185666 0)
			(unlocked yes)
			(layer "Cmts.User")
			(hide yes)
			(effects
				(font
					(size 0.7874 0.5842)
					(thickness 0.1524)
				)
			)
		)
		(duplicate_pad_numbers_are_jumpers no)
		(fp_line
			(start -0.671322 -0.4445)
			(end 0.671322 -0.4445)
			(stroke
				(width 0.1)
				(type default)
			)
			(layer "F.SilkS")
		)
		(fp_line
			(start -0.671322 0.4445)
			(end -0.671322 -0.4445)
			(stroke
				(width 0.1)
				(type default)
			)
			(layer "F.SilkS")
		)
		(fp_line
			(start 0.671322 -0.4445)
			(end 0.671322 0.4445)
			(stroke
				(width 0.1)
				(type default)
			)
			(layer "F.SilkS")
		)
		(fp_line
			(start 0.671322 0.4445)
			(end -0.671322 0.4445)
			(stroke
				(width 0.1)
				(type default)
			)
			(layer "F.SilkS")
		)
		(fp_rect
			(start -0.671322 -0.4445)
			(end 0.671322 0.4445)
			(stroke
				(width 0)
				(type default)
			)
			(fill no)
			(layer "F.CrtYd")
		)
		(fp_line
			(start -0.31496 -0.1651)
			(end -0.31496 0.1651)
			(stroke
				(width 0.1)
				(type default)
			)
			(layer "F.Fab")
		)
		(fp_line
			(start -0.31496 0.1651)
			(end 0.31496 0.1651)
			(stroke
				(width 0.1)
				(type default)
			)
			(layer "F.Fab")
		)
		(fp_line
			(start 0.31496 -0.1651)
			(end -0.31496 -0.1651)
			(stroke
				(width 0.1)
				(type default)
			)
			(layer "F.Fab")
		)
		(fp_line
			(start 0.31496 0.1651)
			(end 0.31496 -0.1651)
			(stroke
				(width 0.1)
				(type default)
			)
			(layer "F.Fab")
		)
		(pad "1" smd rect
			(at -0.264922 0)
			(size 0.3048 0.381)
			(layers "F.Cu" "F.Mask" "F.Paste")
			(net "SG")
		)
		(pad "2" smd rect
			(at 0.264922 0)
			(size 0.3048 0.381)
			(layers "F.Cu" "F.Mask" "F.Paste")
			(net "UNNAMED_524_CAPACITOR_I10_2")
		)
		(zone
			(layer "F.Cu")
			(hatch none 0.5)
			(connect_pads
				(clearance 0)
			)
			(min_thickness 0.25)
			(keepout
				(tracks allowed)
				(vias not_allowed)
				(pads allowed)
				(copperpour not_allowed)
				(footprints allowed)
			)
			(placement
				(enabled no)
				(sheetname "")
			)
			(fill
				(thermal_gap 0.5)
				(thermal_bridge_width 0.5)
				(island_removal_mode 0)
			)
			(polygon
				(pts
					(xy 31.002478 -96.4565) (xy 31.002478 -96.0755) (xy 31.227522 -96.0755) (xy 31.227522 -96.4565)
				)
			)
		)
	)
	(footprint ""
		(layer "F.Cu")
		(at 146.1516 -59.563 -90)
		(property "Reference" "R255"
			(at 1.016 -1.84277 90)
			(unlocked yes)
			(layer "F.SilkS")
			(effects
				(font
					(size 0.7874 0.5842)
					(thickness 0.1524)
				)
			)
		)
		(property "Value" "VAL*"
			(at 0.02032 2.13233 270)
			(unlocked yes)
			(layer "F.Fab")
			(hide yes)
			(effects
				(font
					(size 0.7874 0.5842)
					(thickness 0.1524)
				)
			)
		)
		(property "Device Type" "RESISTOR-G155-02262-01,22.6K,1%"
			(at 0.008382 1.210564 270)
			(unlocked yes)
			(layer "F.Fab")
			(hide yes)
			(effects
				(font
					(size 0.7874 0.5842)
					(thickness 0.1524)
				)
			)
		)
		(property "User Part Number" "PARTNUM*"
			(at 0.02032 4.024884 270)
			(unlocked yes)
			(layer "Cmts.User")
			(hide yes)
			(effects
				(font
					(size 0.7874 0.5842)
					(thickness 0.1524)
				)
			)
		)
		(property "Tolerance" "TOL*"
			(at 0.044704 3.05435 270)
			(unlocked yes)
			(layer "Cmts.User")
			(hide yes)
			(effects
				(font
					(size 0.7874 0.5842)
					(thickness 0.1524)
				)
			)
		)
		(duplicate_pad_numbers_are_jumpers no)
		(fp_line
			(start -1.143 0.5588)
			(end 1.143 0.5588)
			(stroke
				(width 0.1)
				(type default)
			)
			(layer "F.SilkS")
		)
		(fp_line
			(start 1.143 0.5588)
			(end 1.143 -0.5588)
			(stroke
				(width 0.1)
				(type default)
			)
			(layer "F.SilkS")
		)
		(fp_line
			(start -1.143 -0.5588)
			(end -1.143 0.5588)
			(stroke
				(width 0.1)
				(type default)
			)
			(layer "F.SilkS")
		)
		(fp_line
			(start 1.143 -0.5588)
			(end -1.143 -0.5588)
			(stroke
				(width 0.1)
				(type default)
			)
			(layer "F.SilkS")
		)
		(fp_rect
			(start 1.143 0.5588)
			(end -1.143 -0.5588)
			(stroke
				(width 0)
				(type default)
			)
			(fill no)
			(layer "F.CrtYd")
		)
		(fp_line
			(start -0.508 0.3048)
			(end 0.508 0.3048)
			(stroke
				(width 0.1)
				(type default)
			)
			(layer "F.Fab")
		)
		(fp_line
			(start 0.508 0.3048)
			(end 0.508 -0.3048)
			(stroke
				(width 0.1)
				(type default)
			)
			(layer "F.Fab")
		)
		(fp_line
			(start -0.508 -0.3048)
			(end -0.508 0.3048)
			(stroke
				(width 0.1)
				(type default)
			)
			(layer "F.Fab")
		)
		(fp_line
			(start 0.508 -0.3048)
			(end -0.508 -0.3048)
			(stroke
				(width 0.1)
				(type default)
			)
			(layer "F.Fab")
		)
		(pad "1" smd rect
			(at -0.5334 0 270)
			(size 0.7112 0.6096)
			(layers "F.Cu" "F.Mask" "F.Paste")
			(net "UNNAMED_523_CAPACITOR_I28_1")
		)
		(pad "2" smd rect
			(at 0.5334 0 270)
			(size 0.7112 0.6096)
			(layers "F.Cu" "F.Mask" "F.Paste")
			(net "XP1R0V_FB_R_TO_AGND")
		)
		(zone
			(layer "F.Cu")
			(hatch none 0.5)
			(connect_pads
				(clearance 0)
			)
			(min_thickness 0.25)
			(keepout
				(tracks allowed)
				(vias not_allowed)
				(pads allowed)
				(copperpour not_allowed)
				(footprints allowed)
			)
			(placement
				(enabled no)
				(sheetname "")
			)
			(fill
				(thermal_gap 0.5)
				(thermal_bridge_width 0.5)
				(island_removal_mode 0)
			)
			(polygon
				(pts
					(xy 145.8468 -59.4868) (xy 146.4564 -59.4868) (xy 146.4564 -59.6392) (xy 145.8468 -59.6392)
				)
			)
		)
	)
	(footprint ""
		(layer "F.Cu")
		(at 14.732 -22.987 -90)
		(property "Reference" "R368"
			(at 0.635 3.64363 90)
			(unlocked yes)
			(layer "F.SilkS")
			(effects
				(font
					(size 0.7874 0.5842)
					(thickness 0.1524)
				)
			)
		)
		(property "Value" "VAL*"
			(at 0.02032 2.13233 270)
			(unlocked yes)
			(layer "F.Fab")
			(hide yes)
			(effects
				(font
					(size 0.7874 0.5842)
					(thickness 0.1524)
				)
			)
		)
		(property "Tolerance" "TOL*"
			(at 0.044704 3.05435 270)
			(unlocked yes)
			(layer "Cmts.User")
			(hide yes)
			(effects
				(font
					(size 0.7874 0.5842)
					(thickness 0.1524)
				)
			)
		)
		(property "User Part Number" "PARTNUM*"
			(at 0.02032 4.024884 270)
			(unlocked yes)
			(layer "Cmts.User")
			(hide yes)
			(effects
				(font
					(size 0.7874 0.5842)
					(thickness 0.1524)
				)
			)
		)
		(property "Device Type" "RESISTOR-G155-14701-01,4.7KOHMA"
			(at 0.008382 1.210564 270)
			(unlocked yes)
			(layer "F.Fab")
			(hide yes)
			(effects
				(font
					(size 0.7874 0.5842)
					(thickness 0.1524)
				)
			)
		)
		(duplicate_pad_numbers_are_jumpers no)
		(fp_line
			(start -1.143 0.5588)
			(end 1.143 0.5588)
			(stroke
				(width 0.1)
				(type default)
			)
			(layer "F.SilkS")
		)
		(fp_line
			(start 1.143 0.5588)
			(end 1.143 -0.5588)
			(stroke
				(width 0.1)
				(type default)
			)
			(layer "F.SilkS")
		)
		(fp_line
			(start -1.143 -0.5588)
			(end -1.143 0.5588)
			(stroke
				(width 0.1)
				(type default)
			)
			(layer "F.SilkS")
		)
		(fp_line
			(start 1.143 -0.5588)
			(end -1.143 -0.5588)
			(stroke
				(width 0.1)
				(type default)
			)
			(layer "F.SilkS")
		)
		(fp_rect
			(start -1.143 0.5588)
			(end 1.143 -0.5588)
			(stroke
				(width 0)
				(type default)
			)
			(fill no)
			(layer "F.CrtYd")
		)
		(fp_line
			(start -0.508 0.3048)
			(end 0.508 0.3048)
			(stroke
				(width 0.1)
				(type default)
			)
			(layer "F.Fab")
		)
		(fp_line
			(start 0.508 0.3048)
			(end 0.508 -0.3048)
			(stroke
				(width 0.1)
				(type default)
			)
			(layer "F.Fab")
		)
		(fp_line
			(start -0.508 -0.3048)
			(end -0.508 0.3048)
			(stroke
				(width 0.1)
				(type default)
			)
			(layer "F.Fab")
		)
		(fp_line
			(start 0.508 -0.3048)
			(end -0.508 -0.3048)
			(stroke
				(width 0.1)
				(type default)
			)
			(layer "F.Fab")
		)
		(pad "1" smd rect
			(at -0.5334 0 270)
			(size 0.7112 0.6096)
			(layers "F.Cu" "F.Mask" "F.Paste")
			(net "XP3R3V_FPGA")
		)
		(pad "2" smd rect
			(at 0.5334 0 270)
			(size 0.7112 0.6096)
			(layers "F.Cu" "F.Mask" "F.Paste")
			(net "SMA4_SIG_OUT_BF_EN_N")
		)
		(zone
			(layer "F.Cu")
			(hatch none 0.5)
			(connect_pads
				(clearance 0)
			)
			(min_thickness 0.25)
			(keepout
				(tracks not_allowed)
				(vias allowed)
				(pads allowed)
				(copperpour not_allowed)
				(footprints allowed)
			)
			(placement
				(enabled no)
				(sheetname "")
			)
			(fill
				(thermal_gap 0.5)
				(thermal_bridge_width 0.5)
				(island_removal_mode 0)
			)
			(polygon
				(pts
					(xy 14.4272 -23.0632) (xy 14.4272 -22.9108) (xy 15.0368 -22.9108) (xy 15.0368 -23.0632)
				)
			)
		)
		(zone
			(layer "F.Cu")
			(hatch none 0.5)
			(connect_pads
				(clearance 0)
			)
			(min_thickness 0.25)
			(keepout
				(tracks allowed)
				(vias not_allowed)
				(pads allowed)
				(copperpour not_allowed)
				(footprints allowed)
			)
			(placement
				(enabled no)
				(sheetname "")
			)
			(fill
				(thermal_gap 0.5)
				(thermal_bridge_width 0.5)
				(island_removal_mode 0)
			)
			(polygon
				(pts
					(xy 14.4272 -23.0632) (xy 14.4272 -22.9108) (xy 15.0368 -22.9108) (xy 15.0368 -23.0632)
				)
			)
		)
	)
	(footprint ""
		(layer "F.Cu")
		(at 32.021018 -26.426922)
		(property "Reference" "MAC_PIN3"
			(at -2.176018 -2.621026 0)
			(unlocked yes)
			(layer "F.SilkS")
			(effects
				(font
					(size 0.7874 0.5842)
					(thickness 0.1524)
				)
			)
		)
		(property "Value" ""
			(at 0 0 0)
			(layer "F.Fab")
			(effects
				(font
					(size 1.27 1.27)
				)
			)
		)
		(property "User Part Number" "PARTNUM*"
			(at 0 3.826764 0)
			(unlocked yes)
			(layer "Cmts.User")
			(hide yes)
			(effects
				(font
					(size 0.7874 0.5842)
					(thickness 0.1524)
				)
			)
		)
		(property "Device Type" "NUT-A200-00029-FB"
			(at 0 2.632964 0)
			(unlocked yes)
			(layer "F.Fab")
			(hide yes)
			(effects
				(font
					(size 0.7874 0.5842)
					(thickness 0.1524)
				)
			)
		)
		(duplicate_pad_numbers_are_jumpers no)
		(fp_circle
			(center 0 0)
			(end 1.524 0)
			(stroke
				(width 0.1)
				(type default)
			)
			(fill no)
			(layer "F.SilkS")
		)
		(fp_poly
			(pts
				(arc
					(start -1.260856 -0.1524)
					(mid -0.898049 -0.898049)
					(end -0.1524 -1.260856)
				)
				(arc
					(start -0.1524 -0.991616)
					(mid -0.709411 -0.709411)
					(end -0.991616 -0.1524)
				)
			)
			(stroke
				(width 0)
				(type default)
			)
			(fill yes)
			(layer "F.Paste")
		)
		(fp_poly
			(pts
				(arc
					(start -0.1524 1.260856)
					(mid -0.898049 0.898049)
					(end -1.260856 0.1524)
				)
				(arc
					(start -0.991616 0.1524)
					(mid -0.709411 0.709411)
					(end -0.1524 0.991616)
				)
			)
			(stroke
				(width 0)
				(type default)
			)
			(fill yes)
			(layer "F.Paste")
		)
		(fp_poly
			(pts
				(arc
					(start 0.1524 -1.260856)
					(mid 0.898049 -0.898049)
					(end 1.260856 -0.1524)
				)
				(arc
					(start 0.991616 -0.1524)
					(mid 0.709411 -0.709411)
					(end 0.1524 -0.991616)
				)
			)
			(stroke
				(width 0)
				(type default)
			)
			(fill yes)
			(layer "F.Paste")
		)
		(fp_poly
			(pts
				(arc
					(start 1.260856 0.1524)
					(mid 0.898049 0.898049)
					(end 0.1524 1.260856)
				)
				(arc
					(start 0.1524 0.991616)
					(mid 0.709411 0.709411)
					(end 0.991616 0.1524)
				)
			)
			(stroke
				(width 0)
				(type default)
			)
			(fill yes)
			(layer "F.Paste")
		)
		(fp_poly
			(pts
				(arc
					(start 6.35 0)
					(mid -6.35 0)
					(end 6.35 0)
				)
			)
			(stroke
				(width 0)
				(type default)
			)
			(fill no)
			(layer "B.CrtYd")
		)
		(fp_poly
			(pts
				(arc
					(start 1.778 0)
					(mid -1.778 0)
					(end 1.778 0)
				)
			)
			(stroke
				(width 0)
				(type default)
			)
			(fill no)
			(layer "F.CrtYd")
		)
		(fp_circle
			(center 0 0)
			(end 1.1684 0)
			(stroke
				(width 0.1)
				(type default)
			)
			(fill no)
			(layer "F.Fab")
		)
		(pad "1" thru_hole circle
			(at 0 0)
			(size 2.54 2.54)
			(drill 2.0066)
			(layers "*.Cu" "*.Mask")
			(remove_unused_layers no)
			(net "R_MAC_10MHZ_RF_OUT")
			(thermal_gap 0.0254)
			(padstack
				(mode front_inner_back)
				(layer "Inner"
					(shape circle)
					(size 2.54 2.54)
					(clearance 0.0254)
				)
				(layer "B.Cu"
					(shape circle)
					(size 2.54 2.54)
				)
			)
		)
	)
	(footprint ""
		(layer "F.Cu")
		(at 127.889 -37.846)
		(property "Reference" "TP138"
			(at 2.26695 2.3749 90)
			(unlocked yes)
			(layer "F.SilkS")
			(effects
				(font
					(size 0.635 0.4064)
					(thickness 0.1524)
				)
				(justify left)
			)
		)
		(property "Value" ""
			(at 0 0 0)
			(layer "F.Fab")
			(effects
				(font
					(size 1.27 1.27)
				)
			)
		)
		(property "Device Type" "TP_PIONT-TP010CT020B030_PTH-TPA"
			(at -1.341882 0.996696 0)
			(unlocked yes)
			(layer "F.Fab")
			(hide yes)
			(effects
				(font
					(size 0.7874 0.5842)
					(thickness 0.1524)
				)
				(justify left)
			)
		)
		(duplicate_pad_numbers_are_jumpers no)
		(fp_poly
			(pts
				(arc
					(start 0.889 0)
					(mid -0.889 0)
					(end 0.889 0)
				)
			)
			(stroke
				(width 0)
				(type default)
			)
			(fill no)
			(layer "B.CrtYd")
		)
		(fp_poly
			(pts
				(arc
					(start 0.889 0)
					(mid -0.889 0)
					(end 0.889 0)
				)
			)
			(stroke
				(width 0)
				(type default)
			)
			(fill no)
			(layer "F.CrtYd")
		)
		(pad "1" thru_hole circle
			(at 0 0)
			(size 0.508 0.508)
			(drill 0.254)
			(layers "*.Cu" "*.Mask")
			(remove_unused_layers no)
			(net "IO_L23P_34")
			(clearance 0.1016)
			(padstack
				(mode front_inner_back)
				(layer "Inner"
					(shape circle)
					(size 0.508 0.508)
					(clearance 0.1016)
				)
				(layer "B.Cu"
					(shape circle)
					(size 0.762 0.762)
					(clearance -0.0254)
				)
			)
		)
	)
	(footprint ""
		(layer "F.Cu")
		(at 90.932 -66.421)
		(property "Reference" "TP58"
			(at -1.6764 -1.11125 0)
			(unlocked yes)
			(layer "F.SilkS")
			(effects
				(font
					(size 0.635 0.4064)
					(thickness 0.1524)
				)
				(justify left)
			)
		)
		(property "Value" ""
			(at 0 0 0)
			(layer "F.Fab")
			(effects
				(font
					(size 1.27 1.27)
				)
			)
		)
		(property "Device Type" "TP_PIONT-TP010CT020B030_PTH-TPA"
			(at -1.341882 0.996696 0)
			(unlocked yes)
			(layer "F.Fab")
			(hide yes)
			(effects
				(font
					(size 0.7874 0.5842)
					(thickness 0.1524)
				)
				(justify left)
			)
		)
		(duplicate_pad_numbers_are_jumpers no)
		(fp_poly
			(pts
				(arc
					(start 0.889 0)
					(mid -0.889 0)
					(end 0.889 0)
				)
			)
			(stroke
				(width 0)
				(type default)
			)
			(fill no)
			(layer "B.CrtYd")
		)
		(fp_poly
			(pts
				(arc
					(start 0.889 0)
					(mid -0.889 0)
					(end 0.889 0)
				)
			)
			(stroke
				(width 0)
				(type default)
			)
			(fill no)
			(layer "F.CrtYd")
		)
		(pad "1" thru_hole circle
			(at 0 0)
			(size 0.508 0.508)
			(drill 0.254)
			(layers "*.Cu" "*.Mask")
			(remove_unused_layers no)
			(net "XP3R3V_FPGA")
			(clearance 0.1016)
			(padstack
				(mode front_inner_back)
				(layer "Inner"
					(shape circle)
					(size 0.508 0.508)
					(clearance 0.1016)
				)
				(layer "B.Cu"
					(shape circle)
					(size 0.762 0.762)
					(clearance -0.0254)
				)
			)
		)
	)
	(footprint ""
		(layer "F.Cu")
		(at 55.5244 -103.4034 90)
		(property "Reference" "C14"
			(at 0 3.84937 90)
			(unlocked yes)
			(layer "F.SilkS")
			(effects
				(font
					(size 0.7874 0.5842)
					(thickness 0.1524)
				)
			)
		)
		(property "Value" "VAL*"
			(at 0.0762 3.134106 90)
			(unlocked yes)
			(layer "F.Fab")
			(hide yes)
			(effects
				(font
					(size 0.7874 0.5842)
					(thickness 0.1524)
				)
			)
		)
		(property "Device Type" "CAPACITOR-G107-0F226-CM,22UF,2A"
			(at 0.0508 2.194306 90)
			(unlocked yes)
			(layer "F.Fab")
			(hide yes)
			(effects
				(font
					(size 0.7874 0.5842)
					(thickness 0.1524)
				)
			)
		)
		(property "User Part Number" "PARTNUM*"
			(at 0.1016 5.013706 90)
			(unlocked yes)
			(layer "Cmts.User")
			(hide yes)
			(effects
				(font
					(size 0.7874 0.5842)
					(thickness 0.1524)
				)
			)
		)
		(property "Tolerance" "TOL*"
			(at 0.0762 4.048506 90)
			(unlocked yes)
			(layer "Cmts.User")
			(hide yes)
			(effects
				(font
					(size 0.7874 0.5842)
					(thickness 0.1524)
				)
			)
		)
		(duplicate_pad_numbers_are_jumpers no)
		(fp_line
			(start 1.5748 -0.9398)
			(end -1.5748 -0.9398)
			(stroke
				(width 0.1)
				(type default)
			)
			(layer "F.SilkS")
		)
		(fp_line
			(start -1.5748 -0.9398)
			(end -1.5748 0.9398)
			(stroke
				(width 0.1)
				(type default)
			)
			(layer "F.SilkS")
		)
		(fp_line
			(start 1.5748 0.9398)
			(end 1.5748 -0.9398)
			(stroke
				(width 0.1)
				(type default)
			)
			(layer "F.SilkS")
		)
		(fp_line
			(start -1.5748 0.9398)
			(end 1.5748 0.9398)
			(stroke
				(width 0.1)
				(type default)
			)
			(layer "F.SilkS")
		)
		(fp_rect
			(start 1.5748 0.9398)
			(end -1.5748 -0.9398)
			(stroke
				(width 0)
				(type default)
			)
			(fill no)
			(layer "F.CrtYd")
		)
		(fp_line
			(start 1.016 -0.635)
			(end -1.016 -0.635)
			(stroke
				(width 0.1)
				(type default)
			)
			(layer "F.Fab")
		)
		(fp_line
			(start -1.016 -0.635)
			(end -1.016 0.635)
			(stroke
				(width 0.1)
				(type default)
			)
			(layer "F.Fab")
		)
		(fp_line
			(start 1.016 0.635)
			(end 1.016 -0.635)
			(stroke
				(width 0.1)
				(type default)
			)
			(layer "F.Fab")
		)
		(fp_line
			(start -1.016 0.635)
			(end 1.016 0.635)
			(stroke
				(width 0.1)
				(type default)
			)
			(layer "F.Fab")
		)
		(pad "1" smd rect
			(at -0.8382 0 90)
			(size 0.9652 1.3716)
			(layers "F.Cu" "F.Mask" "F.Paste")
			(net "XP5R0V")
		)
		(pad "2" smd rect
			(at 0.8382 0 90)
			(size 0.9652 1.3716)
			(layers "F.Cu" "F.Mask" "F.Paste")
			(net "SG")
		)
		(zone
			(layer "F.Cu")
			(hatch none 0.5)
			(connect_pads
				(clearance 0)
			)
			(min_thickness 0.25)
			(keepout
				(tracks allowed)
				(vias not_allowed)
				(pads allowed)
				(copperpour not_allowed)
				(footprints allowed)
			)
			(placement
				(enabled no)
				(sheetname "")
			)
			(fill
				(thermal_gap 0.5)
				(thermal_bridge_width 0.5)
				(island_removal_mode 0)
			)
			(polygon
				(pts
					(xy 56.1594 -103.632) (xy 54.8894 -103.632) (xy 54.8894 -103.1748) (xy 56.1594 -103.1748)
				)
			)
		)
	)
	(footprint ""
		(layer "F.Cu")
		(at 153.67 -57.658)
		(property "Reference" "C275"
			(at 1.905 2.32537 0)
			(unlocked yes)
			(layer "F.SilkS")
			(effects
				(font
					(size 0.7874 0.5842)
					(thickness 0.1524)
				)
			)
		)
		(property "Value" "VAL*"
			(at 0.0762 2.067306 0)
			(unlocked yes)
			(layer "F.Fab")
			(hide yes)
			(effects
				(font
					(size 0.7874 0.5842)
					(thickness 0.1524)
				)
			)
		)
		(property "Tolerance" "TOL*"
			(at 0.0762 3.032506 0)
			(unlocked yes)
			(layer "Cmts.User")
			(hide yes)
			(effects
				(font
					(size 0.7874 0.5842)
					(thickness 0.1524)
				)
			)
		)
		(property "User Part Number" "PARTNUM*"
			(at 0.1016 4.023106 0)
			(unlocked yes)
			(layer "Cmts.User")
			(hide yes)
			(effects
				(font
					(size 0.7874 0.5842)
					(thickness 0.1524)
				)
			)
		)
		(property "Device Type" "CAPACITOR-G105-0B104-EK,0.1UF,A"
			(at 0.0508 1.127506 0)
			(unlocked yes)
			(layer "F.Fab")
			(hide yes)
			(effects
				(font
					(size 0.7874 0.5842)
					(thickness 0.1524)
				)
			)
		)
		(duplicate_pad_numbers_are_jumpers no)
		(fp_line
			(start -1.143 -0.5588)
			(end -1.143 0.5588)
			(stroke
				(width 0.1)
				(type default)
			)
			(layer "F.SilkS")
		)
		(fp_line
			(start -1.143 0.5588)
			(end 1.143 0.5588)
			(stroke
				(width 0.1)
				(type default)
			)
			(layer "F.SilkS")
		)
		(fp_line
			(start 1.143 -0.5588)
			(end -1.143 -0.5588)
			(stroke
				(width 0.1)
				(type default)
			)
			(layer "F.SilkS")
		)
		(fp_line
			(start 1.143 0.5588)
			(end 1.143 -0.5588)
			(stroke
				(width 0.1)
				(type default)
			)
			(layer "F.SilkS")
		)
		(fp_rect
			(start 1.143 -0.5588)
			(end -1.143 0.5588)
			(stroke
				(width 0)
				(type default)
			)
			(fill no)
			(layer "F.CrtYd")
		)
		(fp_line
			(start -0.508 -0.3048)
			(end -0.508 0.3048)
			(stroke
				(width 0.1)
				(type default)
			)
			(layer "F.Fab")
		)
		(fp_line
			(start -0.508 0.3048)
			(end 0.508 0.3048)
			(stroke
				(width 0.1)
				(type default)
			)
			(layer "F.Fab")
		)
		(fp_line
			(start 0.508 -0.3048)
			(end -0.508 -0.3048)
			(stroke
				(width 0.1)
				(type default)
			)
			(layer "F.Fab")
		)
		(fp_line
			(start 0.508 0.3048)
			(end 0.508 -0.3048)
			(stroke
				(width 0.1)
				(type default)
			)
			(layer "F.Fab")
		)
		(pad "1" smd rect
			(at -0.5334 0)
			(size 0.7112 0.6096)
			(layers "F.Cu" "F.Mask" "F.Paste")
			(net "VDD3V3_SHT31A")
		)
		(pad "2" smd rect
			(at 0.5334 0)
			(size 0.7112 0.6096)
			(layers "F.Cu" "F.Mask" "F.Paste")
			(net "SG")
		)
		(zone
			(layer "F.Cu")
			(hatch none 0.5)
			(connect_pads
				(clearance 0)
			)
			(min_thickness 0.25)
			(keepout
				(tracks allowed)
				(vias not_allowed)
				(pads allowed)
				(copperpour not_allowed)
				(footprints allowed)
			)
			(placement
				(enabled no)
				(sheetname "")
			)
			(fill
				(thermal_gap 0.5)
				(thermal_bridge_width 0.5)
				(island_removal_mode 0)
			)
			(polygon
				(pts
					(xy 153.7462 -57.9628) (xy 153.5938 -57.9628) (xy 153.5938 -57.3532) (xy 153.7462 -57.3532)
				)
			)
		)
	)
	(footprint ""
		(layer "F.Cu")
		(at 162.56 -28.829 180)
		(property "Reference" "C305"
			(at -2.667 0.72263 0)
			(unlocked yes)
			(layer "F.SilkS")
			(effects
				(font
					(size 0.7874 0.5842)
					(thickness 0.1524)
				)
			)
		)
		(property "Value" "VAL*"
			(at 0.0762 2.067306 180)
			(unlocked yes)
			(layer "F.Fab")
			(hide yes)
			(effects
				(font
					(size 0.7874 0.5842)
					(thickness 0.1524)
				)
			)
		)
		(property "Tolerance" "TOL*"
			(at 0.0762 3.032506 180)
			(unlocked yes)
			(layer "Cmts.User")
			(hide yes)
			(effects
				(font
					(size 0.7874 0.5842)
					(thickness 0.1524)
				)
			)
		)
		(property "User Part Number" "PARTNUM*"
			(at 0.1016 4.023106 180)
			(unlocked yes)
			(layer "Cmts.User")
			(hide yes)
			(effects
				(font
					(size 0.7874 0.5842)
					(thickness 0.1524)
				)
			)
		)
		(property "Device Type" "CAPACITOR-G105-0B104-EK,0.1UF,A"
			(at 0.0508 1.127506 180)
			(unlocked yes)
			(layer "F.Fab")
			(hide yes)
			(effects
				(font
					(size 0.7874 0.5842)
					(thickness 0.1524)
				)
			)
		)
		(duplicate_pad_numbers_are_jumpers no)
		(fp_line
			(start 1.143 0.5588)
			(end 1.143 -0.5588)
			(stroke
				(width 0.1)
				(type default)
			)
			(layer "F.SilkS")
		)
		(fp_line
			(start 1.143 -0.5588)
			(end -1.143 -0.5588)
			(stroke
				(width 0.1)
				(type default)
			)
			(layer "F.SilkS")
		)
		(fp_line
			(start -1.143 0.5588)
			(end 1.143 0.5588)
			(stroke
				(width 0.1)
				(type default)
			)
			(layer "F.SilkS")
		)
		(fp_line
			(start -1.143 -0.5588)
			(end -1.143 0.5588)
			(stroke
				(width 0.1)
				(type default)
			)
			(layer "F.SilkS")
		)
		(fp_rect
			(start 1.143 -0.5588)
			(end -1.143 0.5588)
			(stroke
				(width 0)
				(type default)
			)
			(fill no)
			(layer "F.CrtYd")
		)
		(fp_line
			(start 0.508 0.3048)
			(end 0.508 -0.3048)
			(stroke
				(width 0.1)
				(type default)
			)
			(layer "F.Fab")
		)
		(fp_line
			(start 0.508 -0.3048)
			(end -0.508 -0.3048)
			(stroke
				(width 0.1)
				(type default)
			)
			(layer "F.Fab")
		)
		(fp_line
			(start -0.508 0.3048)
			(end 0.508 0.3048)
			(stroke
				(width 0.1)
				(type default)
			)
			(layer "F.Fab")
		)
		(fp_line
			(start -0.508 -0.3048)
			(end -0.508 0.3048)
			(stroke
				(width 0.1)
				(type default)
			)
			(layer "F.Fab")
		)
		(pad "1" smd rect
			(at -0.5334 0 180)
			(size 0.7112 0.6096)
			(layers "F.Cu" "F.Mask" "F.Paste")
			(net "SG")
		)
		(pad "2" smd rect
			(at 0.5334 0 180)
			(size 0.7112 0.6096)
			(layers "F.Cu" "F.Mask" "F.Paste")
			(net "XP3R3V_FPGA")
		)
		(zone
			(layer "F.Cu")
			(hatch none 0.5)
			(connect_pads
				(clearance 0)
			)
			(min_thickness 0.25)
			(keepout
				(tracks allowed)
				(vias not_allowed)
				(pads allowed)
				(copperpour not_allowed)
				(footprints allowed)
			)
			(placement
				(enabled no)
				(sheetname "")
			)
			(fill
				(thermal_gap 0.5)
				(thermal_bridge_width 0.5)
				(island_removal_mode 0)
			)
			(polygon
				(pts
					(xy 162.4838 -28.5242) (xy 162.6362 -28.5242) (xy 162.6362 -29.1338) (xy 162.4838 -29.1338)
				)
			)
		)
		(zone
			(layer "F.Cu")
			(hatch none 0.5)
			(connect_pads
				(clearance 0)
			)
			(min_thickness 0.25)
			(keepout
				(tracks not_allowed)
				(vias allowed)
				(pads allowed)
				(copperpour not_allowed)
				(footprints allowed)
			)
			(placement
				(enabled no)
				(sheetname "")
			)
			(fill
				(thermal_gap 0.5)
				(thermal_bridge_width 0.5)
				(island_removal_mode 0)
			)
			(polygon
				(pts
					(xy 162.4838 -28.5242) (xy 162.6362 -28.5242) (xy 162.6362 -29.1338) (xy 162.4838 -29.1338)
				)
			)
		)
	)
	(footprint ""
		(layer "F.Cu")
		(at 118.491 -28.0416 90)
		(property "Reference" "TP202"
			(at -2.8194 1.30175 90)
			(unlocked yes)
			(layer "F.SilkS")
			(effects
				(font
					(size 0.635 0.4064)
					(thickness 0.1524)
				)
				(justify left)
			)
		)
		(property "Value" ""
			(at 0 0 90)
			(layer "F.Fab")
			(effects
				(font
					(size 1.27 1.27)
				)
			)
		)
		(property "Device Type" "TP_PIONT-TP010CT020B030_PTH-TPA"
			(at -1.341882 0.996696 90)
			(unlocked yes)
			(layer "F.Fab")
			(hide yes)
			(effects
				(font
					(size 0.7874 0.5842)
					(thickness 0.1524)
				)
				(justify left)
			)
		)
		(duplicate_pad_numbers_are_jumpers no)
		(fp_poly
			(pts
				(arc
					(start 0 0.889)
					(mid 0 -0.889)
					(end 0 0.889)
				)
			)
			(stroke
				(width 0)
				(type default)
			)
			(fill no)
			(layer "B.CrtYd")
		)
		(fp_poly
			(pts
				(arc
					(start 0 0.889)
					(mid 0 -0.889)
					(end 0 0.889)
				)
			)
			(stroke
				(width 0)
				(type default)
			)
			(fill no)
			(layer "F.CrtYd")
		)
		(pad "1" thru_hole circle
			(at 0 0 90)
			(size 0.508 0.508)
			(drill 0.254)
			(layers "*.Cu" "*.Mask")
			(remove_unused_layers no)
			(net "IO_L22N_35")
			(clearance 0.1016)
			(padstack
				(mode front_inner_back)
				(layer "Inner"
					(shape circle)
					(size 0.508 0.508)
					(clearance 0.1016)
				)
				(layer "B.Cu"
					(shape circle)
					(size 0.762 0.762)
					(clearance -0.0254)
				)
			)
		)
	)
	(footprint ""
		(layer "F.Cu")
		(at 83.5152 -106.7308 180)
		(property "Reference" "C50"
			(at -0.3048 1.68783 0)
			(unlocked yes)
			(layer "F.SilkS")
			(effects
				(font
					(size 0.7874 0.5842)
					(thickness 0.1524)
				)
			)
		)
		(property "Value" "VAL*"
			(at 0.0762 3.134106 180)
			(unlocked yes)
			(layer "F.Fab")
			(hide yes)
			(effects
				(font
					(size 0.7874 0.5842)
					(thickness 0.1524)
				)
			)
		)
		(property "Tolerance" "TOL*"
			(at 0.0762 4.048506 180)
			(unlocked yes)
			(layer "Cmts.User")
			(hide yes)
			(effects
				(font
					(size 0.7874 0.5842)
					(thickness 0.1524)
				)
			)
		)
		(property "User Part Number" "PARTNUM*"
			(at 0.1016 5.013706 180)
			(unlocked yes)
			(layer "Cmts.User")
			(hide yes)
			(effects
				(font
					(size 0.7874 0.5842)
					(thickness 0.1524)
				)
			)
		)
		(property "Device Type" "CAPACITOR-G107-0F106-EM,10UF,2A"
			(at 0.0508 2.194306 180)
			(unlocked yes)
			(layer "F.Fab")
			(hide yes)
			(effects
				(font
					(size 0.7874 0.5842)
					(thickness 0.1524)
				)
			)
		)
		(duplicate_pad_numbers_are_jumpers no)
		(fp_line
			(start 1.5748 0.9398)
			(end 1.5748 -0.9398)
			(stroke
				(width 0.1)
				(type default)
			)
			(layer "F.SilkS")
		)
		(fp_line
			(start 1.5748 -0.9398)
			(end -1.5748 -0.9398)
			(stroke
				(width 0.1)
				(type default)
			)
			(layer "F.SilkS")
		)
		(fp_line
			(start -1.5748 0.9398)
			(end 1.5748 0.9398)
			(stroke
				(width 0.1)
				(type default)
			)
			(layer "F.SilkS")
		)
		(fp_line
			(start -1.5748 -0.9398)
			(end -1.5748 0.9398)
			(stroke
				(width 0.1)
				(type default)
			)
			(layer "F.SilkS")
		)
		(fp_rect
			(start 1.5748 -0.9398)
			(end -1.5748 0.9398)
			(stroke
				(width 0)
				(type default)
			)
			(fill no)
			(layer "F.CrtYd")
		)
		(fp_line
			(start 1.016 0.635)
			(end 1.016 -0.635)
			(stroke
				(width 0.1)
				(type default)
			)
			(layer "F.Fab")
		)
		(fp_line
			(start 1.016 -0.635)
			(end -1.016 -0.635)
			(stroke
				(width 0.1)
				(type default)
			)
			(layer "F.Fab")
		)
		(fp_line
			(start -1.016 0.635)
			(end 1.016 0.635)
			(stroke
				(width 0.1)
				(type default)
			)
			(layer "F.Fab")
		)
		(fp_line
			(start -1.016 -0.635)
			(end -1.016 0.635)
			(stroke
				(width 0.1)
				(type default)
			)
			(layer "F.Fab")
		)
		(pad "1" smd rect
			(at -0.8382 0 180)
			(size 0.9652 1.3716)
			(layers "F.Cu" "F.Mask" "F.Paste")
			(net "VIN_XP3R3")
		)
		(pad "2" smd rect
			(at 0.8382 0 180)
			(size 0.9652 1.3716)
			(layers "F.Cu" "F.Mask" "F.Paste")
			(net "SG")
		)
		(zone
			(layer "F.Cu")
			(hatch none 0.5)
			(connect_pads
				(clearance 0)
			)
			(min_thickness 0.25)
			(keepout
				(tracks allowed)
				(vias not_allowed)
				(pads allowed)
				(copperpour not_allowed)
				(footprints allowed)
			)
			(placement
				(enabled no)
				(sheetname "")
			)
			(fill
				(thermal_gap 0.5)
				(thermal_bridge_width 0.5)
				(island_removal_mode 0)
			)
			(polygon
				(pts
					(xy 83.2866 -106.0958) (xy 83.7438 -106.0958) (xy 83.7438 -107.3658) (xy 83.2866 -107.3658)
				)
			)
		)
	)
	(footprint ""
		(layer "F.Cu")
		(at 84.5312 -98.7298 180)
		(property "Reference" "C52"
			(at 4.6482 -6.18617 0)
			(unlocked yes)
			(layer "F.SilkS")
			(effects
				(font
					(size 0.7874 0.5842)
					(thickness 0.1524)
				)
			)
		)
		(property "Value" "VAL*"
			(at 0.0762 2.067306 180)
			(unlocked yes)
			(layer "F.Fab")
			(hide yes)
			(effects
				(font
					(size 0.7874 0.5842)
					(thickness 0.1524)
				)
			)
		)
		(property "Tolerance" "TOL*"
			(at 0.0762 3.032506 180)
			(unlocked yes)
			(layer "Cmts.User")
			(hide yes)
			(effects
				(font
					(size 0.7874 0.5842)
					(thickness 0.1524)
				)
			)
		)
		(property "User Part Number" "PARTNUM*"
			(at 0.1016 4.023106 180)
			(unlocked yes)
			(layer "Cmts.User")
			(hide yes)
			(effects
				(font
					(size 0.7874 0.5842)
					(thickness 0.1524)
				)
			)
		)
		(property "Device Type" "CAPACITOR-G105-0B104-EK,0.1UF,A"
			(at 0.0508 1.127506 180)
			(unlocked yes)
			(layer "F.Fab")
			(hide yes)
			(effects
				(font
					(size 0.7874 0.5842)
					(thickness 0.1524)
				)
			)
		)
		(duplicate_pad_numbers_are_jumpers no)
		(fp_line
			(start 1.143 0.5588)
			(end 1.143 -0.5588)
			(stroke
				(width 0.1)
				(type default)
			)
			(layer "F.SilkS")
		)
		(fp_line
			(start 1.143 -0.5588)
			(end -1.143 -0.5588)
			(stroke
				(width 0.1)
				(type default)
			)
			(layer "F.SilkS")
		)
		(fp_line
			(start -1.143 0.5588)
			(end 1.143 0.5588)
			(stroke
				(width 0.1)
				(type default)
			)
			(layer "F.SilkS")
		)
		(fp_line
			(start -1.143 -0.5588)
			(end -1.143 0.5588)
			(stroke
				(width 0.1)
				(type default)
			)
			(layer "F.SilkS")
		)
		(fp_rect
			(start 1.143 -0.5588)
			(end -1.143 0.5588)
			(stroke
				(width 0)
				(type default)
			)
			(fill no)
			(layer "F.CrtYd")
		)
		(fp_line
			(start 0.508 0.3048)
			(end 0.508 -0.3048)
			(stroke
				(width 0.1)
				(type default)
			)
			(layer "F.Fab")
		)
		(fp_line
			(start 0.508 -0.3048)
			(end -0.508 -0.3048)
			(stroke
				(width 0.1)
				(type default)
			)
			(layer "F.Fab")
		)
		(fp_line
			(start -0.508 0.3048)
			(end 0.508 0.3048)
			(stroke
				(width 0.1)
				(type default)
			)
			(layer "F.Fab")
		)
		(fp_line
			(start -0.508 -0.3048)
			(end -0.508 0.3048)
			(stroke
				(width 0.1)
				(type default)
			)
			(layer "F.Fab")
		)
		(pad "1" smd rect
			(at -0.5334 0 180)
			(size 0.7112 0.6096)
			(layers "F.Cu" "F.Mask" "F.Paste")
			(net "VIN_XP3R3")
		)
		(pad "2" smd rect
			(at 0.5334 0 180)
			(size 0.7112 0.6096)
			(layers "F.Cu" "F.Mask" "F.Paste")
			(net "SG")
		)
		(zone
			(layer "F.Cu")
			(hatch none 0.5)
			(connect_pads
				(clearance 0)
			)
			(min_thickness 0.25)
			(keepout
				(tracks allowed)
				(vias not_allowed)
				(pads allowed)
				(copperpour not_allowed)
				(footprints allowed)
			)
			(placement
				(enabled no)
				(sheetname "")
			)
			(fill
				(thermal_gap 0.5)
				(thermal_bridge_width 0.5)
				(island_removal_mode 0)
			)
			(polygon
				(pts
					(xy 84.455 -98.425) (xy 84.6074 -98.425) (xy 84.6074 -99.0346) (xy 84.455 -99.0346)
				)
			)
		)
	)
	(footprint ""
		(layer "F.Cu")
		(at 110.6424 -73.0504 180)
		(property "Reference" "U22"
			(at 0.4064 2.47523 0)
			(unlocked yes)
			(layer "F.SilkS")
			(effects
				(font
					(size 0.7874 0.5842)
					(thickness 0.1524)
				)
			)
		)
		(property "Value" ""
			(at 0 0 180)
			(layer "F.Fab")
			(effects
				(font
					(size 1.27 1.27)
				)
			)
		)
		(property "Device Type" "NCP45560IMNTWG_H_DFN12-G222-10A"
			(at 0.074168 3.118866 180)
			(unlocked yes)
			(layer "F.Fab")
			(hide yes)
			(effects
				(font
					(size 0.7874 0.5842)
					(thickness 0.1524)
				)
			)
		)
		(property "User Part Number" "PARTNUM*"
			(at 0.074168 4.312666 180)
			(unlocked yes)
			(layer "Cmts.User")
			(hide yes)
			(effects
				(font
					(size 0.7874 0.5842)
					(thickness 0.1524)
				)
			)
		)
		(duplicate_pad_numbers_are_jumpers no)
		(fp_line
			(start 2.29235 1.754124)
			(end -2.29235 1.754124)
			(stroke
				(width 0.1)
				(type default)
			)
			(layer "F.SilkS")
		)
		(fp_line
			(start 2.29235 -1.783334)
			(end 2.29235 1.754124)
			(stroke
				(width 0.1)
				(type default)
			)
			(layer "F.SilkS")
		)
		(fp_line
			(start -2.29235 1.754124)
			(end -2.29235 -1.783334)
			(stroke
				(width 0.1)
				(type default)
			)
			(layer "F.SilkS")
		)
		(fp_line
			(start -2.29235 -1.783334)
			(end 2.29235 -1.783334)
			(stroke
				(width 0.1)
				(type default)
			)
			(layer "F.SilkS")
		)
		(fp_poly
			(pts
				(arc
					(start -3.7846 -1.930146)
					(mid -2.769108 -1.930146)
					(end -3.7846 -1.930146)
				)
			)
			(stroke
				(width 0)
				(type default)
			)
			(fill yes)
			(layer "F.SilkS")
		)
		(fp_rect
			(start 0.1016 -0.1016)
			(end 0.9017 -1.2192)
			(stroke
				(width 0)
				(type default)
			)
			(fill yes)
			(layer "F.Paste")
		)
		(fp_rect
			(start -0.9017 1.2192)
			(end -0.1016 0.1016)
			(stroke
				(width 0)
				(type default)
			)
			(fill yes)
			(layer "F.Paste")
		)
		(fp_poly
			(pts
				(xy 0.9017 0.1016)
				(arc
					(start 0.9017 0.9652)
					(mid 0.468095 0.785595)
					(end 0.6477 1.2192)
				)
				(xy 0.1016 1.2192) (xy 0.1016 0.1016)
			)
			(stroke
				(width 0)
				(type default)
			)
			(fill yes)
			(layer "F.Paste")
		)
		(fp_poly
			(pts
				(xy -0.9017 -0.1016)
				(arc
					(start -0.9017 -0.9652)
					(mid -0.468095 -0.785595)
					(end -0.6477 -1.2192)
				)
				(xy -0.1016 -1.2192) (xy -0.1016 -0.1016)
			)
			(stroke
				(width 0)
				(type default)
			)
			(fill yes)
			(layer "F.Paste")
		)
		(fp_poly
			(pts
				(xy -2.54635 2.008124) (xy 2.54635 2.008124) (xy 2.54635 -2.037334) (xy -2.54635 -2.037334)
			)
			(stroke
				(width 0)
				(type default)
			)
			(fill no)
			(layer "F.CrtYd")
		)
		(fp_line
			(start 1.500124 1.500124)
			(end 1.500124 -1.500124)
			(stroke
				(width 0.1)
				(type default)
			)
			(layer "F.Fab")
		)
		(fp_line
			(start 1.500124 -1.500124)
			(end -1.500124 -1.500124)
			(stroke
				(width 0.1)
				(type default)
			)
			(layer "F.Fab")
		)
		(fp_line
			(start -1.500124 1.500124)
			(end 1.500124 1.500124)
			(stroke
				(width 0.1)
				(type default)
			)
			(layer "F.Fab")
		)
		(fp_line
			(start -1.500124 -1.500124)
			(end -1.500124 1.500124)
			(stroke
				(width 0.1)
				(type default)
			)
			(layer "F.Fab")
		)
		(fp_poly
			(pts
				(arc
					(start -3.2766 -1.803146)
					(mid -2.261108 -1.803146)
					(end -3.2766 -1.803146)
				)
			)
			(stroke
				(width 0)
				(type default)
			)
			(fill yes)
			(layer "F.Fab")
		)
		(fp_text user "7"
			(at 2.8194 2.02565 0)
			(unlocked yes)
			(layer "F.SilkS")
			(effects
				(font
					(size 0.635 0.4064)
					(thickness 0.1524)
				)
			)
		)
		(fp_text user "12"
			(at 2.3114 -2.34315 0)
			(unlocked yes)
			(layer "F.SilkS")
			(effects
				(font
					(size 0.635 0.4064)
					(thickness 0.1524)
				)
			)
		)
		(fp_text user "6"
			(at -3.1496 1.21285 0)
			(unlocked yes)
			(layer "F.SilkS")
			(effects
				(font
					(size 0.635 0.4064)
					(thickness 0.1524)
				)
			)
		)
		(fp_text user "12"
			(at 2.6924 -1.96977 0)
			(unlocked yes)
			(layer "F.Fab")
			(effects
				(font
					(size 0.7874 0.5842)
					(thickness 0.1524)
				)
			)
		)
		(fp_text user "7"
			(at 2.5654 1.58623 0)
			(unlocked yes)
			(layer "F.Fab")
			(effects
				(font
					(size 0.7874 0.5842)
					(thickness 0.1524)
				)
			)
		)
		(fp_text user "6"
			(at -2.758948 1.418336 0)
			(unlocked yes)
			(layer "F.Fab")
			(effects
				(font
					(size 0.7874 0.5842)
					(thickness 0.1524)
				)
			)
		)
		(pad "1" smd rect
			(at -1.61925 -1.313434 180)
			(size 0.8382 0.4318)
			(layers "F.Cu" "F.Mask" "F.Paste")
			(net "XP3R3V")
		)
		(pad "2" smd rect
			(at -1.61925 -0.750062 180)
			(size 0.8382 0.3048)
			(layers "F.Cu" "F.Mask" "F.Paste")
			(net "XP3R3V_FPGA_EN_R")
		)
		(pad "3" smd rect
			(at -1.61925 -0.249936 180)
			(size 0.8382 0.3048)
			(layers "F.Cu" "F.Mask" "F.Paste")
			(net "XP3R3V")
		)
		(pad "4" smd rect
			(at -1.61925 0.249936 180)
			(size 0.8382 0.3048)
			(layers "F.Cu" "F.Mask" "F.Paste")
			(net "SG")
		)
		(pad "5" smd rect
			(at -1.61925 0.750062 180)
			(size 0.8382 0.3048)
			(layers "F.Cu" "F.Mask" "F.Paste")
			(net "XP3R3V_FPGA_SR")
		)
		(pad "6" smd rect
			(at -1.61925 1.249934 180)
			(size 0.8382 0.3048)
			(layers "F.Cu" "F.Mask" "F.Paste")
			(net "UNNAMED_515_NCP45560IMNTWGHDFN1")
		)
		(pad "7" smd rect
			(at 1.61925 1.249934 180)
			(size 0.8382 0.3048)
			(layers "F.Cu" "F.Mask" "F.Paste")
			(net "XP3R3V_FPGA")
		)
		(pad "8" smd rect
			(at 1.61925 0.750062 180)
			(size 0.8382 0.3048)
			(layers "F.Cu" "F.Mask" "F.Paste")
			(net "XP3R3V_FPGA")
		)
		(pad "9" smd rect
			(at 1.61925 0.249936 180)
			(size 0.8382 0.3048)
			(layers "F.Cu" "F.Mask" "F.Paste")
			(net "XP3R3V_FPGA")
		)
		(pad "10" smd rect
			(at 1.61925 -0.249936 180)
			(size 0.8382 0.3048)
			(layers "F.Cu" "F.Mask" "F.Paste")
			(net "XP3R3V_FPGA")
		)
		(pad "11" smd rect
			(at 1.61925 -0.750062 180)
			(size 0.8382 0.3048)
			(layers "F.Cu" "F.Mask" "F.Paste")
			(net "XP3R3V_FPGA")
		)
		(pad "12" smd rect
			(at 1.61925 -1.249934 180)
			(size 0.8382 0.3048)
			(layers "F.Cu" "F.Mask" "F.Paste")
			(net "XP3R3V_FPGA")
		)
		(pad "13" smd rect
			(at 0 0 180)
			(size 1.8034 2.4384)
			(layers "F.Cu" "F.Mask" "F.Paste")
			(net "XP3R3V")
		)
	)
	(footprint ""
		(layer "F.Cu")
		(at 90.805 -40.64 90)
		(property "Reference" "C148"
			(at -3.048 -0.59563 90)
			(unlocked yes)
			(layer "F.SilkS")
			(effects
				(font
					(size 0.7874 0.5842)
					(thickness 0.1524)
				)
			)
		)
		(property "Value" "VAL*"
			(at 0.0762 2.067306 90)
			(unlocked yes)
			(layer "F.Fab")
			(hide yes)
			(effects
				(font
					(size 0.7874 0.5842)
					(thickness 0.1524)
				)
			)
		)
		(property "Tolerance" "TOL*"
			(at 0.0762 3.032506 90)
			(unlocked yes)
			(layer "Cmts.User")
			(hide yes)
			(effects
				(font
					(size 0.7874 0.5842)
					(thickness 0.1524)
				)
			)
		)
		(property "User Part Number" "PARTNUM*"
			(at 0.1016 4.023106 90)
			(unlocked yes)
			(layer "Cmts.User")
			(hide yes)
			(effects
				(font
					(size 0.7874 0.5842)
					(thickness 0.1524)
				)
			)
		)
		(property "Device Type" "CAPACITOR-G105-0B104-CK,0.1UF,A"
			(at 0.0508 1.127506 90)
			(unlocked yes)
			(layer "F.Fab")
			(hide yes)
			(effects
				(font
					(size 0.7874 0.5842)
					(thickness 0.1524)
				)
			)
		)
		(duplicate_pad_numbers_are_jumpers no)
		(fp_line
			(start 1.143 -0.5588)
			(end -1.143 -0.5588)
			(stroke
				(width 0.1)
				(type default)
			)
			(layer "F.SilkS")
		)
		(fp_line
			(start -1.143 -0.5588)
			(end -1.143 0.5588)
			(stroke
				(width 0.1)
				(type default)
			)
			(layer "F.SilkS")
		)
		(fp_line
			(start 1.143 0.5588)
			(end 1.143 -0.5588)
			(stroke
				(width 0.1)
				(type default)
			)
			(layer "F.SilkS")
		)
		(fp_line
			(start -1.143 0.5588)
			(end 1.143 0.5588)
			(stroke
				(width 0.1)
				(type default)
			)
			(layer "F.SilkS")
		)
		(fp_rect
			(start -1.143 0.5588)
			(end 1.143 -0.5588)
			(stroke
				(width 0)
				(type default)
			)
			(fill no)
			(layer "F.CrtYd")
		)
		(fp_line
			(start 0.508 -0.3048)
			(end -0.508 -0.3048)
			(stroke
				(width 0.1)
				(type default)
			)
			(layer "F.Fab")
		)
		(fp_line
			(start -0.508 -0.3048)
			(end -0.508 0.3048)
			(stroke
				(width 0.1)
				(type default)
			)
			(layer "F.Fab")
		)
		(fp_line
			(start 0.508 0.3048)
			(end 0.508 -0.3048)
			(stroke
				(width 0.1)
				(type default)
			)
			(layer "F.Fab")
		)
		(fp_line
			(start -0.508 0.3048)
			(end 0.508 0.3048)
			(stroke
				(width 0.1)
				(type default)
			)
			(layer "F.Fab")
		)
		(pad "1" smd rect
			(at -0.5334 0 90)
			(size 0.7112 0.6096)
			(layers "F.Cu" "F.Mask" "F.Paste")
			(net "XP1R0V_FPGA")
		)
		(pad "2" smd rect
			(at 0.5334 0 90)
			(size 0.7112 0.6096)
			(layers "F.Cu" "F.Mask" "F.Paste")
			(net "SG")
		)
		(zone
			(layer "F.Cu")
			(hatch none 0.5)
			(connect_pads
				(clearance 0)
			)
			(min_thickness 0.25)
			(keepout
				(tracks allowed)
				(vias not_allowed)
				(pads allowed)
				(copperpour not_allowed)
				(footprints allowed)
			)
			(placement
				(enabled no)
				(sheetname "")
			)
			(fill
				(thermal_gap 0.5)
				(thermal_bridge_width 0.5)
				(island_removal_mode 0)
			)
			(polygon
				(pts
					(xy 91.1098 -40.5638) (xy 91.1098 -40.7162) (xy 90.5002 -40.7162) (xy 90.5002 -40.5638)
				)
			)
		)
	)
	(footprint ""
		(layer "F.Cu")
		(at 101.219 -24.638 180)
		(property "Reference" "R240"
			(at 10.795 -0.16637 0)
			(unlocked yes)
			(layer "F.SilkS")
			(effects
				(font
					(size 0.7874 0.5842)
					(thickness 0.1524)
				)
			)
		)
		(property "Value" "VAL*"
			(at 0.02032 2.13233 180)
			(unlocked yes)
			(layer "F.Fab")
			(hide yes)
			(effects
				(font
					(size 0.7874 0.5842)
					(thickness 0.1524)
				)
			)
		)
		(property "Tolerance" "TOL*"
			(at 0.044704 3.05435 180)
			(unlocked yes)
			(layer "Cmts.User")
			(hide yes)
			(effects
				(font
					(size 0.7874 0.5842)
					(thickness 0.1524)
				)
			)
		)
		(property "User Part Number" "PARTNUM*"
			(at 0.02032 4.024884 180)
			(unlocked yes)
			(layer "Cmts.User")
			(hide yes)
			(effects
				(font
					(size 0.7874 0.5842)
					(thickness 0.1524)
				)
			)
		)
		(property "Device Type" "RESISTOR-G155-11500-01,150OHM,A"
			(at 0.008382 1.210564 180)
			(unlocked yes)
			(layer "F.Fab")
			(hide yes)
			(effects
				(font
					(size 0.7874 0.5842)
					(thickness 0.1524)
				)
			)
		)
		(duplicate_pad_numbers_are_jumpers no)
		(fp_line
			(start 1.143 0.5588)
			(end 1.143 -0.5588)
			(stroke
				(width 0.1)
				(type default)
			)
			(layer "F.SilkS")
		)
		(fp_line
			(start 1.143 -0.5588)
			(end -1.143 -0.5588)
			(stroke
				(width 0.1)
				(type default)
			)
			(layer "F.SilkS")
		)
		(fp_line
			(start -1.143 0.5588)
			(end 1.143 0.5588)
			(stroke
				(width 0.1)
				(type default)
			)
			(layer "F.SilkS")
		)
		(fp_line
			(start -1.143 -0.5588)
			(end -1.143 0.5588)
			(stroke
				(width 0.1)
				(type default)
			)
			(layer "F.SilkS")
		)
		(fp_rect
			(start 1.143 -0.5588)
			(end -1.143 0.5588)
			(stroke
				(width 0)
				(type default)
			)
			(fill no)
			(layer "F.CrtYd")
		)
		(fp_line
			(start 0.508 0.3048)
			(end 0.508 -0.3048)
			(stroke
				(width 0.1)
				(type default)
			)
			(layer "F.Fab")
		)
		(fp_line
			(start 0.508 -0.3048)
			(end -0.508 -0.3048)
			(stroke
				(width 0.1)
				(type default)
			)
			(layer "F.Fab")
		)
		(fp_line
			(start -0.508 0.3048)
			(end 0.508 0.3048)
			(stroke
				(width 0.1)
				(type default)
			)
			(layer "F.Fab")
		)
		(fp_line
			(start -0.508 -0.3048)
			(end -0.508 0.3048)
			(stroke
				(width 0.1)
				(type default)
			)
			(layer "F.Fab")
		)
		(pad "1" smd rect
			(at -0.5334 0 180)
			(size 0.7112 0.6096)
			(layers "F.Cu" "F.Mask" "F.Paste")
			(net "OSC_125M_CLKN")
		)
		(pad "2" smd rect
			(at 0.5334 0 180)
			(size 0.7112 0.6096)
			(layers "F.Cu" "F.Mask" "F.Paste")
			(net "SG")
		)
		(zone
			(layer "F.Cu")
			(hatch none 0.5)
			(connect_pads
				(clearance 0)
			)
			(min_thickness 0.25)
			(keepout
				(tracks allowed)
				(vias not_allowed)
				(pads allowed)
				(copperpour not_allowed)
				(footprints allowed)
			)
			(placement
				(enabled no)
				(sheetname "")
			)
			(fill
				(thermal_gap 0.5)
				(thermal_bridge_width 0.5)
				(island_removal_mode 0)
			)
			(polygon
				(pts
					(xy 101.1428 -24.3332) (xy 101.2952 -24.3332) (xy 101.2952 -24.9428) (xy 101.1428 -24.9428)
				)
			)
		)
	)
	(footprint ""
		(layer "F.Cu")
		(at 90.017854 -48.653446 90)
		(property "Reference" "U11"
			(at 2.754884 3.581146 0)
			(unlocked yes)
			(layer "F.SilkS")
			(effects
				(font
					(size 0.7874 0.5842)
					(thickness 0.1524)
				)
			)
		)
		(property "Value" ""
			(at 0 0 90)
			(layer "F.Fab")
			(effects
				(font
					(size 1.27 1.27)
				)
			)
		)
		(property "Device Type" "TS3USB3031RMGR_WQFN12-G220-103A"
			(at 0 3.481324 90)
			(unlocked yes)
			(layer "F.Fab")
			(hide yes)
			(effects
				(font
					(size 0.7874 0.5842)
					(thickness 0.1524)
				)
			)
		)
		(property "User Part Number" "PARTNUM*"
			(at 0 4.675124 90)
			(unlocked yes)
			(layer "Cmts.User")
			(hide yes)
			(effects
				(font
					(size 0.7874 0.5842)
					(thickness 0.1524)
				)
			)
		)
		(duplicate_pad_numbers_are_jumpers no)
		(fp_line
			(start 1.690624 -1.690624)
			(end -1.690624 -1.690624)
			(stroke
				(width 0.1)
				(type default)
			)
			(layer "F.SilkS")
		)
		(fp_line
			(start -1.690624 -1.690624)
			(end -1.690624 1.690624)
			(stroke
				(width 0.1)
				(type default)
			)
			(layer "F.SilkS")
		)
		(fp_line
			(start 1.690624 1.690624)
			(end 1.690624 -1.690624)
			(stroke
				(width 0.1)
				(type default)
			)
			(layer "F.SilkS")
		)
		(fp_line
			(start -1.690624 1.690624)
			(end 1.690624 1.690624)
			(stroke
				(width 0.1)
				(type default)
			)
			(layer "F.SilkS")
		)
		(fp_poly
			(pts
				(arc
					(start -2.368296 -0.184658)
					(mid -2.368296 -0.946658)
					(end -2.368296 -0.184658)
				)
			)
			(stroke
				(width 0)
				(type default)
			)
			(fill yes)
			(layer "F.SilkS")
		)
		(fp_rect
			(start -1.944624 -1.944624)
			(end 1.944624 1.944624)
			(stroke
				(width 0)
				(type default)
			)
			(fill no)
			(layer "F.CrtYd")
		)
		(fp_line
			(start 0.94996 -0.94996)
			(end -0.94996 -0.94996)
			(stroke
				(width 0.1)
				(type default)
			)
			(layer "F.Fab")
		)
		(fp_line
			(start -0.94996 -0.94996)
			(end -0.94996 0.94996)
			(stroke
				(width 0.1)
				(type default)
			)
			(layer "F.Fab")
		)
		(fp_line
			(start 0.94996 0.94996)
			(end 0.94996 -0.94996)
			(stroke
				(width 0.1)
				(type default)
			)
			(layer "F.Fab")
		)
		(fp_line
			(start -0.94996 0.94996)
			(end 0.94996 0.94996)
			(stroke
				(width 0.1)
				(type default)
			)
			(layer "F.Fab")
		)
		(fp_poly
			(pts
				(arc
					(start -1.733296 -0.438658)
					(mid -1.733296 -1.200658)
					(end -1.733296 -0.438658)
				)
			)
			(stroke
				(width 0)
				(type default)
			)
			(fill yes)
			(layer "F.Fab")
		)
		(fp_text user "8"
			(at 2.1844 -0.455168 90)
			(unlocked yes)
			(layer "F.SilkS")
			(effects
				(font
					(size 0.635 0.4064)
					(thickness 0.1524)
				)
			)
		)
		(fp_text user "2"
			(at -2.203196 0.533146 0)
			(unlocked yes)
			(layer "F.SilkS")
			(effects
				(font
					(size 0.635 0.4064)
					(thickness 0.1524)
				)
			)
		)
		(fp_text user "7"
			(at 2.207006 0.53848 90)
			(unlocked yes)
			(layer "F.SilkS")
			(effects
				(font
					(size 0.635 0.4064)
					(thickness 0.1524)
				)
			)
		)
		(fp_text user "3"
			(at -1.390396 2.057146 0)
			(unlocked yes)
			(layer "F.SilkS")
			(effects
				(font
					(size 0.635 0.4064)
					(thickness 0.1524)
				)
			)
		)
		(fp_text user "6"
			(at 1.479804 2.692146 0)
			(unlocked yes)
			(layer "F.SilkS")
			(effects
				(font
					(size 0.635 0.4064)
					(thickness 0.1524)
				)
			)
		)
		(fp_text user "12"
			(at -0.674116 -2.006854 0)
			(unlocked yes)
			(layer "F.Fab")
			(effects
				(font
					(size 0.7874 0.5842)
					(thickness 0.1524)
				)
			)
		)
		(fp_text user "9"
			(at 0.722884 -1.752854 0)
			(unlocked yes)
			(layer "F.Fab")
			(effects
				(font
					(size 0.7874 0.5842)
					(thickness 0.1524)
				)
			)
		)
		(fp_text user "8"
			(at 1.77673 -0.677418 0)
			(unlocked yes)
			(layer "F.Fab")
			(effects
				(font
					(size 0.7874 0.5842)
					(thickness 0.1524)
				)
			)
		)
		(fp_text user "7"
			(at 1.798828 0.316484 0)
			(unlocked yes)
			(layer "F.Fab")
			(effects
				(font
					(size 0.7874 0.5842)
					(thickness 0.1524)
				)
			)
		)
		(fp_text user "2"
			(at -1.563116 0.914146 0)
			(unlocked yes)
			(layer "F.Fab")
			(effects
				(font
					(size 0.7874 0.5842)
					(thickness 0.1524)
				)
			)
		)
		(fp_text user "6"
			(at 1.103884 1.549146 0)
			(unlocked yes)
			(layer "F.Fab")
			(effects
				(font
					(size 0.7874 0.5842)
					(thickness 0.1524)
				)
			)
		)
		(fp_text user "3"
			(at -0.420116 1.549146 0)
			(unlocked yes)
			(layer "F.Fab")
			(effects
				(font
					(size 0.7874 0.5842)
					(thickness 0.1524)
				)
			)
		)
		(pad "1" smd rect
			(at -0.763524 -0.199898 90)
			(size 1.3462 0.2032)
			(layers "F.Cu" "F.Mask" "F.Paste")
			(net "XP5R0V_USB_CONN_DET")
		)
		(pad "2" smd rect
			(at -0.763524 0.200152 90)
			(size 1.3462 0.2032)
			(layers "F.Cu" "F.Mask" "F.Paste")
			(net "UNNAMED_527_RESISTOR_I126_1")
		)
		(pad "3" smd rect
			(at -0.599948 0.966724 90)
			(size 0.2032 0.9398)
			(layers "F.Cu" "F.Mask" "F.Paste")
			(net "MAC_USB_DP")
		)
		(pad "4" smd rect
			(at -0.199898 0.966724 90)
			(size 0.2032 0.9398)
			(layers "F.Cu" "F.Mask" "F.Paste")
			(net "MAC_USB_DM")
		)
		(pad "5" smd rect
			(at 0.199898 0.966724 90)
			(size 0.2032 0.9398)
			(layers "F.Cu" "F.Mask" "F.Paste")
			(net "CONN_MICRO_USB_DP")
		)
		(pad "6" smd rect
			(at 0.599948 0.966724 90)
			(size 0.2032 0.9398)
			(layers "F.Cu" "F.Mask" "F.Paste")
			(net "CONN_MICRO_USB_DM")
		)
		(pad "7" smd rect
			(at 0.763524 0.200152 90)
			(size 1.3462 0.2032)
			(layers "F.Cu" "F.Mask" "F.Paste")
			(net "Net_759")
		)
		(pad "8" smd rect
			(at 0.763524 -0.199898 90)
			(size 1.3462 0.2032)
			(layers "F.Cu" "F.Mask" "F.Paste")
			(net "Net_760")
		)
		(pad "9" smd rect
			(at 0.599948 -0.966724 90)
			(size 0.2032 0.9398)
			(layers "F.Cu" "F.Mask" "F.Paste")
			(net "SG")
		)
		(pad "10" smd rect
			(at 0.199898 -0.966724 90)
			(size 0.2032 0.9398)
			(layers "F.Cu" "F.Mask" "F.Paste")
			(net "MUX_USB_DM")
		)
		(pad "11" smd rect
			(at -0.199898 -0.966724 90)
			(size 0.2032 0.9398)
			(layers "F.Cu" "F.Mask" "F.Paste")
			(net "MUX_USB_DP")
		)
		(pad "12" smd rect
			(at -0.599948 -0.966724 90)
			(size 0.2032 0.9398)
			(layers "F.Cu" "F.Mask" "F.Paste")
			(net "XP3R3V_FPGA")
		)
	)
	(footprint ""
		(layer "F.Cu")
		(at 133.4516 -94.107 90)
		(property "Reference" "C10"
			(at -2.921 0.44577 90)
			(unlocked yes)
			(layer "F.SilkS")
			(effects
				(font
					(size 0.7874 0.5842)
					(thickness 0.1524)
				)
			)
		)
		(property "Value" "VAL*"
			(at 0.0762 3.134106 90)
			(unlocked yes)
			(layer "F.Fab")
			(hide yes)
			(effects
				(font
					(size 0.7874 0.5842)
					(thickness 0.1524)
				)
			)
		)
		(property "Device Type" "CAPACITOR-G107-0F106-EM,10UF,2A"
			(at 0.0508 2.194306 90)
			(unlocked yes)
			(layer "F.Fab")
			(hide yes)
			(effects
				(font
					(size 0.7874 0.5842)
					(thickness 0.1524)
				)
			)
		)
		(property "User Part Number" "PARTNUM*"
			(at 0.1016 5.013706 90)
			(unlocked yes)
			(layer "Cmts.User")
			(hide yes)
			(effects
				(font
					(size 0.7874 0.5842)
					(thickness 0.1524)
				)
			)
		)
		(property "Tolerance" "TOL*"
			(at 0.0762 4.048506 90)
			(unlocked yes)
			(layer "Cmts.User")
			(hide yes)
			(effects
				(font
					(size 0.7874 0.5842)
					(thickness 0.1524)
				)
			)
		)
		(duplicate_pad_numbers_are_jumpers no)
		(fp_line
			(start 1.5748 -0.9398)
			(end -1.5748 -0.9398)
			(stroke
				(width 0.1)
				(type default)
			)
			(layer "F.SilkS")
		)
		(fp_line
			(start -1.5748 -0.9398)
			(end -1.5748 0.9398)
			(stroke
				(width 0.1)
				(type default)
			)
			(layer "F.SilkS")
		)
		(fp_line
			(start 1.5748 0.9398)
			(end 1.5748 -0.9398)
			(stroke
				(width 0.1)
				(type default)
			)
			(layer "F.SilkS")
		)
		(fp_line
			(start -1.5748 0.9398)
			(end 1.5748 0.9398)
			(stroke
				(width 0.1)
				(type default)
			)
			(layer "F.SilkS")
		)
		(fp_rect
			(start -1.5748 -0.9398)
			(end 1.5748 0.9398)
			(stroke
				(width 0)
				(type default)
			)
			(fill no)
			(layer "F.CrtYd")
		)
		(fp_line
			(start 1.016 -0.635)
			(end -1.016 -0.635)
			(stroke
				(width 0.1)
				(type default)
			)
			(layer "F.Fab")
		)
		(fp_line
			(start -1.016 -0.635)
			(end -1.016 0.635)
			(stroke
				(width 0.1)
				(type default)
			)
			(layer "F.Fab")
		)
		(fp_line
			(start 1.016 0.635)
			(end 1.016 -0.635)
			(stroke
				(width 0.1)
				(type default)
			)
			(layer "F.Fab")
		)
		(fp_line
			(start -1.016 0.635)
			(end 1.016 0.635)
			(stroke
				(width 0.1)
				(type default)
			)
			(layer "F.Fab")
		)
		(pad "1" smd rect
			(at -0.8382 0 90)
			(size 0.9652 1.3716)
			(layers "F.Cu" "F.Mask" "F.Paste")
			(net "XP12R0V")
		)
		(pad "2" smd rect
			(at 0.8382 0 90)
			(size 0.9652 1.3716)
			(layers "F.Cu" "F.Mask" "F.Paste")
			(net "SG")
		)
		(zone
			(layer "F.Cu")
			(hatch none 0.5)
			(connect_pads
				(clearance 0)
			)
			(min_thickness 0.25)
			(keepout
				(tracks allowed)
				(vias not_allowed)
				(pads allowed)
				(copperpour not_allowed)
				(footprints allowed)
			)
			(placement
				(enabled no)
				(sheetname "")
			)
			(fill
				(thermal_gap 0.5)
				(thermal_bridge_width 0.5)
				(island_removal_mode 0)
			)
			(polygon
				(pts
					(xy 132.8166 -93.8784) (xy 134.0866 -93.8784) (xy 134.0866 -94.3356) (xy 132.8166 -94.3356)
				)
			)
		)
	)
	(footprint ""
		(layer "F.Cu")
		(at 42.672 -76.581)
		(property "Reference" "U41"
			(at -0.889 2.83337 0)
			(unlocked yes)
			(layer "F.SilkS")
			(effects
				(font
					(size 0.7874 0.5842)
					(thickness 0.1524)
				)
			)
		)
		(property "Value" ""
			(at 0 0 0)
			(layer "F.Fab")
			(effects
				(font
					(size 1.27 1.27)
				)
			)
		)
		(property "Device Type" "ISL80101IRAJZ_DFN10-G222-10136A"
			(at 0.276606 2.583688 0)
			(unlocked yes)
			(layer "F.Fab")
			(hide yes)
			(effects
				(font
					(size 0.7874 0.5842)
					(thickness 0.1524)
				)
			)
		)
		(property "User Part Number" "PARTNUM*"
			(at 0.276606 3.517646 0)
			(unlocked yes)
			(layer "Cmts.User")
			(hide yes)
			(effects
				(font
					(size 0.7874 0.5842)
					(thickness 0.1524)
				)
			)
		)
		(duplicate_pad_numbers_are_jumpers no)
		(fp_line
			(start -2.290318 -1.779016)
			(end 2.290318 -1.779016)
			(stroke
				(width 0.1)
				(type default)
			)
			(layer "F.SilkS")
		)
		(fp_line
			(start -2.290318 1.779016)
			(end -2.290318 -1.779016)
			(stroke
				(width 0.1)
				(type default)
			)
			(layer "F.SilkS")
		)
		(fp_line
			(start 2.290318 -1.779016)
			(end 2.290318 1.779016)
			(stroke
				(width 0.1)
				(type default)
			)
			(layer "F.SilkS")
		)
		(fp_line
			(start 2.290318 1.779016)
			(end -2.290318 1.779016)
			(stroke
				(width 0.1)
				(type default)
			)
			(layer "F.SilkS")
		)
		(fp_poly
			(pts
				(arc
					(start -2.553462 -1.023112)
					(mid -3.315462 -1.023112)
					(end -2.553462 -1.023112)
				)
			)
			(stroke
				(width 0)
				(type default)
			)
			(fill yes)
			(layer "F.SilkS")
		)
		(fp_poly
			(pts
				(xy -0.7239 -0.1016)
				(arc
					(start -0.7239 -0.6477)
					(mid -0.290295 -0.468095)
					(end -0.4699 -0.9017)
				)
				(xy 0.7239 -0.9017) (xy 0.7239 -0.1016)
			)
			(stroke
				(width 0)
				(type default)
			)
			(fill yes)
			(layer "F.Paste")
		)
		(fp_poly
			(pts
				(xy -0.7239 0.1016) (xy 0.7239 0.1016) (xy 0.7239 0.635)
				(arc
					(start 0.723646 0.635254)
					(mid 0.645086 0.463711)
					(end 0.4699 0.3937)
				)
				(arc
					(start 0.4699 0.3937)
					(mid 0.290295 0.468095)
					(end 0.2159 0.6477)
				)
				(arc
					(start 0.2159 0.6477)
					(mid 0.284118 0.820908)
					(end 0.45212 0.901192)
				)
				(xy 0.45212 0.9017) (xy -0.7239 0.9017)
			)
			(stroke
				(width 0)
				(type default)
			)
			(fill yes)
			(layer "F.Paste")
		)
		(fp_poly
			(pts
				(xy -2.544318 2.033016) (xy 2.544318 2.033016) (xy 2.544318 -2.033016) (xy -2.544318 -2.033016)
			)
			(stroke
				(width 0)
				(type default)
			)
			(fill no)
			(layer "F.CrtYd")
		)
		(fp_line
			(start -1.525016 -1.525016)
			(end 1.525016 -1.525016)
			(stroke
				(width 0.1)
				(type default)
			)
			(layer "F.Fab")
		)
		(fp_line
			(start -1.525016 1.525016)
			(end -1.525016 -1.525016)
			(stroke
				(width 0.1)
				(type default)
			)
			(layer "F.Fab")
		)
		(fp_line
			(start 1.525016 -1.525016)
			(end 1.525016 1.525016)
			(stroke
				(width 0.1)
				(type default)
			)
			(layer "F.Fab")
		)
		(fp_line
			(start 1.525016 1.525016)
			(end -1.525016 1.525016)
			(stroke
				(width 0.1)
				(type default)
			)
			(layer "F.Fab")
		)
		(fp_poly
			(pts
				(arc
					(start -2.553462 -1.023112)
					(mid -3.315462 -1.023112)
					(end -2.553462 -1.023112)
				)
			)
			(stroke
				(width 0)
				(type default)
			)
			(fill yes)
			(layer "F.Fab")
		)
		(fp_text user "5"
			(at -2.825496 1.184402 0)
			(unlocked yes)
			(layer "F.SilkS")
			(effects
				(font
					(size 0.635 0.4064)
					(thickness 0.1524)
				)
			)
		)
		(fp_text user "6"
			(at 2.667 1.04775 0)
			(unlocked yes)
			(layer "F.SilkS")
			(effects
				(font
					(size 0.635 0.4064)
					(thickness 0.1524)
				)
			)
		)
		(fp_text user "10"
			(at 2.69875 -0.762 90)
			(unlocked yes)
			(layer "F.SilkS")
			(effects
				(font
					(size 0.635 0.4064)
					(thickness 0.1524)
				)
			)
		)
		(fp_text user "5"
			(at -2.54 1.25095 0)
			(unlocked yes)
			(layer "F.Fab")
			(effects
				(font
					(size 0.635 0.4064)
					(thickness 0.1524)
				)
			)
		)
		(fp_text user "10"
			(at 2.286 -1.67005 0)
			(unlocked yes)
			(layer "F.Fab")
			(effects
				(font
					(size 0.635 0.4064)
					(thickness 0.1524)
				)
			)
		)
		(fp_text user "6"
			(at 2.413 1.37795 0)
			(unlocked yes)
			(layer "F.Fab")
			(effects
				(font
					(size 0.635 0.4064)
					(thickness 0.1524)
				)
			)
		)
		(pad "1" smd circle
			(at -1.515618 -1.000252 180)
			(size 0 0)
			(layers "F.Cu" "F.Mask" "F.Paste")
			(net "XP3R3V_FT4232")
		)
		(pad "2" smd rect
			(at -1.515618 -0.500126)
			(size 1.0414 0.3048)
			(layers "F.Cu" "F.Mask" "F.Paste")
			(net "XP3R3V_FT4232")
		)
		(pad "3" smd rect
			(at -1.515618 0)
			(size 1.0414 0.3048)
			(layers "F.Cu" "F.Mask" "F.Paste")
			(net "UNNAMED_525_ISL80101IRAJZDFN10_")
		)
		(pad "4" smd rect
			(at -1.515618 0.500126)
			(size 1.0414 0.3048)
			(layers "F.Cu" "F.Mask" "F.Paste")
			(net "XP3R3V_FT_PG")
		)
		(pad "5" smd circle
			(at -1.515618 1.000252)
			(size 0 0)
			(layers "F.Cu" "F.Mask" "F.Paste")
			(net "SG")
		)
		(pad "6" smd circle
			(at 1.515618 1.000252)
			(size 0 0)
			(layers "F.Cu" "F.Mask" "F.Paste")
			(net "UNNAMED_525_CAPACITOR_I18_1")
		)
		(pad "7" smd rect
			(at 1.515618 0.500126)
			(size 1.0414 0.3048)
			(layers "F.Cu" "F.Mask" "F.Paste")
			(net "UNNAMED_525_CAPACITOR_I14_1")
		)
		(pad "8" smd rect
			(at 1.515618 0)
			(size 1.0414 0.3048)
			(layers "F.Cu" "F.Mask" "F.Paste")
			(net "Net_788")
		)
		(pad "9" smd rect
			(at 1.515618 -0.500126)
			(size 1.0414 0.3048)
			(layers "F.Cu" "F.Mask" "F.Paste")
			(net "UNNAMED_525_CAPACITOR_I16_1")
		)
		(pad "10" smd circle
			(at 1.515618 -1.000252 180)
			(size 0 0)
			(layers "F.Cu" "F.Mask" "F.Paste")
			(net "UNNAMED_525_CAPACITOR_I16_1")
		)
		(pad "11" smd rect
			(at 0 0)
			(size 1.4478 1.8034)
			(layers "F.Cu" "F.Mask" "F.Paste")
			(net "SG")
		)
	)
	(footprint ""
		(layer "F.Cu")
		(at 85.725 -67.31)
		(property "Reference" "TP18"
			(at -1.2954 -0.85725 0)
			(unlocked yes)
			(layer "F.SilkS")
			(effects
				(font
					(size 0.635 0.4064)
					(thickness 0.1524)
				)
				(justify left)
			)
		)
		(property "Value" ""
			(at 0 0 0)
			(layer "F.Fab")
			(effects
				(font
					(size 1.27 1.27)
				)
			)
		)
		(property "Device Type" "TP_PIONT-TP010CT020B030_PTH-TPA"
			(at -1.341882 0.996696 0)
			(unlocked yes)
			(layer "F.Fab")
			(hide yes)
			(effects
				(font
					(size 0.7874 0.5842)
					(thickness 0.000001)
				)
				(justify left)
			)
		)
		(duplicate_pad_numbers_are_jumpers no)
		(fp_poly
			(pts
				(arc
					(start 0.889 0)
					(mid -0.889 0)
					(end 0.889 0)
				)
			)
			(stroke
				(width 0)
				(type default)
			)
			(fill no)
			(layer "B.CrtYd")
		)
		(fp_poly
			(pts
				(arc
					(start 0.889 0)
					(mid -0.889 0)
					(end 0.889 0)
				)
			)
			(stroke
				(width 0)
				(type default)
			)
			(fill no)
			(layer "F.CrtYd")
		)
		(pad "1" thru_hole circle
			(at 0 0)
			(size 0.508 0.508)
			(drill 0.254)
			(layers "*.Cu" "*.Mask")
			(remove_unused_layers no)
			(net "R_BNO080_BOOT_N")
			(clearance 0.1016)
			(padstack
				(mode front_inner_back)
				(layer "Inner"
					(shape circle)
					(size 0.508 0.508)
					(clearance 0.1016)
				)
				(layer "B.Cu"
					(shape circle)
					(size 0.762 0.762)
					(clearance -0.0254)
				)
			)
		)
	)
	(footprint ""
		(layer "F.Cu")
		(at 140.9192 -20.1168)
		(property "Reference" "C242"
			(at -3.8862 -1.30683 0)
			(unlocked yes)
			(layer "F.SilkS")
			(effects
				(font
					(size 0.7874 0.5842)
					(thickness 0.1524)
				)
			)
		)
		(property "Value" "VAL*"
			(at 0.0762 2.067306 0)
			(unlocked yes)
			(layer "F.Fab")
			(hide yes)
			(effects
				(font
					(size 0.7874 0.5842)
					(thickness 0.1524)
				)
			)
		)
		(property "Tolerance" "TOL*"
			(at 0.0762 3.032506 0)
			(unlocked yes)
			(layer "Cmts.User")
			(hide yes)
			(effects
				(font
					(size 0.7874 0.5842)
					(thickness 0.1524)
				)
			)
		)
		(property "User Part Number" "PARTNUM*"
			(at 0.1016 4.023106 0)
			(unlocked yes)
			(layer "Cmts.User")
			(hide yes)
			(effects
				(font
					(size 0.7874 0.5842)
					(thickness 0.1524)
				)
			)
		)
		(property "Device Type" "CAPACITOR-G105-0B104-EK,0.1UF,A"
			(at 0.0508 1.127506 0)
			(unlocked yes)
			(layer "F.Fab")
			(hide yes)
			(effects
				(font
					(size 0.7874 0.5842)
					(thickness 0.1524)
				)
			)
		)
		(duplicate_pad_numbers_are_jumpers no)
		(fp_line
			(start -1.143 -0.5588)
			(end -1.143 0.5588)
			(stroke
				(width 0.1)
				(type default)
			)
			(layer "F.SilkS")
		)
		(fp_line
			(start -1.143 0.5588)
			(end 1.143 0.5588)
			(stroke
				(width 0.1)
				(type default)
			)
			(layer "F.SilkS")
		)
		(fp_line
			(start 1.143 -0.5588)
			(end -1.143 -0.5588)
			(stroke
				(width 0.1)
				(type default)
			)
			(layer "F.SilkS")
		)
		(fp_line
			(start 1.143 0.5588)
			(end 1.143 -0.5588)
			(stroke
				(width 0.1)
				(type default)
			)
			(layer "F.SilkS")
		)
		(fp_rect
			(start 1.143 -0.5588)
			(end -1.143 0.5588)
			(stroke
				(width 0)
				(type default)
			)
			(fill no)
			(layer "F.CrtYd")
		)
		(fp_line
			(start -0.508 -0.3048)
			(end -0.508 0.3048)
			(stroke
				(width 0.1)
				(type default)
			)
			(layer "F.Fab")
		)
		(fp_line
			(start -0.508 0.3048)
			(end 0.508 0.3048)
			(stroke
				(width 0.1)
				(type default)
			)
			(layer "F.Fab")
		)
		(fp_line
			(start 0.508 -0.3048)
			(end -0.508 -0.3048)
			(stroke
				(width 0.1)
				(type default)
			)
			(layer "F.Fab")
		)
		(fp_line
			(start 0.508 0.3048)
			(end 0.508 -0.3048)
			(stroke
				(width 0.1)
				(type default)
			)
			(layer "F.Fab")
		)
		(pad "1" smd rect
			(at -0.5334 0)
			(size 0.7112 0.6096)
			(layers "F.Cu" "F.Mask" "F.Paste")
			(net "XP2R5V_FPGA")
		)
		(pad "2" smd rect
			(at 0.5334 0)
			(size 0.7112 0.6096)
			(layers "F.Cu" "F.Mask" "F.Paste")
			(net "SG")
		)
		(zone
			(layer "F.Cu")
			(hatch none 0.5)
			(connect_pads
				(clearance 0)
			)
			(min_thickness 0.25)
			(keepout
				(tracks allowed)
				(vias not_allowed)
				(pads allowed)
				(copperpour not_allowed)
				(footprints allowed)
			)
			(placement
				(enabled no)
				(sheetname "")
			)
			(fill
				(thermal_gap 0.5)
				(thermal_bridge_width 0.5)
				(island_removal_mode 0)
			)
			(polygon
				(pts
					(xy 140.9954 -20.4216) (xy 140.843 -20.4216) (xy 140.843 -19.812) (xy 140.9954 -19.812)
				)
			)
		)
	)
	(footprint ""
		(layer "F.Cu")
		(at 143.891 -21.8186 180)
		(property "Reference" "C228"
			(at -3.175 0.74803 0)
			(unlocked yes)
			(layer "F.SilkS")
			(effects
				(font
					(size 0.7874 0.5842)
					(thickness 0.1524)
				)
			)
		)
		(property "Value" "VAL*"
			(at 0.0762 3.134106 180)
			(unlocked yes)
			(layer "F.Fab")
			(hide yes)
			(effects
				(font
					(size 0.7874 0.5842)
					(thickness 0.1524)
				)
			)
		)
		(property "Tolerance" "TOL*"
			(at 0.0762 4.048506 180)
			(unlocked yes)
			(layer "Cmts.User")
			(hide yes)
			(effects
				(font
					(size 0.7874 0.5842)
					(thickness 0.1524)
				)
			)
		)
		(property "User Part Number" "PARTNUM*"
			(at 0.1016 5.013706 180)
			(unlocked yes)
			(layer "Cmts.User")
			(hide yes)
			(effects
				(font
					(size 0.7874 0.5842)
					(thickness 0.1524)
				)
			)
		)
		(property "Device Type" "CAPACITOR-G107-0F106-EM,10UF,2A"
			(at 0.0508 2.194306 180)
			(unlocked yes)
			(layer "F.Fab")
			(hide yes)
			(effects
				(font
					(size 0.7874 0.5842)
					(thickness 0.1524)
				)
			)
		)
		(duplicate_pad_numbers_are_jumpers no)
		(fp_line
			(start 1.5748 0.9398)
			(end 1.5748 -0.9398)
			(stroke
				(width 0.1)
				(type default)
			)
			(layer "F.SilkS")
		)
		(fp_line
			(start 1.5748 -0.9398)
			(end -1.5748 -0.9398)
			(stroke
				(width 0.1)
				(type default)
			)
			(layer "F.SilkS")
		)
		(fp_line
			(start -1.5748 0.9398)
			(end 1.5748 0.9398)
			(stroke
				(width 0.1)
				(type default)
			)
			(layer "F.SilkS")
		)
		(fp_line
			(start -1.5748 -0.9398)
			(end -1.5748 0.9398)
			(stroke
				(width 0.1)
				(type default)
			)
			(layer "F.SilkS")
		)
		(fp_rect
			(start -1.5748 0.9398)
			(end 1.5748 -0.9398)
			(stroke
				(width 0)
				(type default)
			)
			(fill no)
			(layer "F.CrtYd")
		)
		(fp_line
			(start 1.016 0.635)
			(end 1.016 -0.635)
			(stroke
				(width 0.1)
				(type default)
			)
			(layer "F.Fab")
		)
		(fp_line
			(start 1.016 -0.635)
			(end -1.016 -0.635)
			(stroke
				(width 0.1)
				(type default)
			)
			(layer "F.Fab")
		)
		(fp_line
			(start -1.016 0.635)
			(end 1.016 0.635)
			(stroke
				(width 0.1)
				(type default)
			)
			(layer "F.Fab")
		)
		(fp_line
			(start -1.016 -0.635)
			(end -1.016 0.635)
			(stroke
				(width 0.1)
				(type default)
			)
			(layer "F.Fab")
		)
		(pad "1" smd rect
			(at -0.8382 0 180)
			(size 0.9652 1.3716)
			(layers "F.Cu" "F.Mask" "F.Paste")
			(net "UNNAMED_515_CAPACITOR_I130_1")
		)
		(pad "2" smd rect
			(at 0.8382 0 180)
			(size 0.9652 1.3716)
			(layers "F.Cu" "F.Mask" "F.Paste")
			(net "SG")
		)
		(zone
			(layer "F.Cu")
			(hatch none 0.5)
			(connect_pads
				(clearance 0)
			)
			(min_thickness 0.25)
			(keepout
				(tracks allowed)
				(vias not_allowed)
				(pads allowed)
				(copperpour not_allowed)
				(footprints allowed)
			)
			(placement
				(enabled no)
				(sheetname "")
			)
			(fill
				(thermal_gap 0.5)
				(thermal_bridge_width 0.5)
				(island_removal_mode 0)
			)
			(polygon
				(pts
					(xy 144.1196 -22.4536) (xy 143.6624 -22.4536) (xy 143.6624 -21.1836) (xy 144.1196 -21.1836)
				)
			)
		)
	)
	(footprint ""
		(layer "F.Cu")
		(at 144.78 -24.384 -90)
		(property "Reference" "L13"
			(at -1.8415 0.08763 90)
			(unlocked yes)
			(layer "F.SilkS")
			(effects
				(font
					(size 0.7874 0.5842)
					(thickness 0.1524)
				)
				(justify left)
			)
		)
		(property "Value" "VAL*"
			(at -0.9398 3.70967 270)
			(unlocked yes)
			(layer "F.Fab")
			(hide yes)
			(effects
				(font
					(size 0.7874 0.5842)
					(thickness 0.1524)
				)
				(justify left)
			)
		)
		(property "Tolerance" "TOL*"
			(at -0.9906 5.00507 270)
			(unlocked yes)
			(layer "Cmts.User")
			(hide yes)
			(effects
				(font
					(size 0.7874 0.5842)
					(thickness 0.1524)
				)
				(justify left)
			)
		)
		(property "User Part Number" "PARTNUM*"
			(at -2.54 2.46507 270)
			(unlocked yes)
			(layer "Cmts.User")
			(hide yes)
			(effects
				(font
					(size 0.7874 0.5842)
					(thickness 0.1524)
				)
				(justify left)
			)
		)
		(property "Device Type" "FERRITEBEAD-G191-10101-01,26OHA"
			(at -0.9906 1.22047 270)
			(unlocked yes)
			(layer "F.Fab")
			(hide yes)
			(effects
				(font
					(size 0.7874 0.5842)
					(thickness 0.1524)
				)
				(justify left)
			)
		)
		(duplicate_pad_numbers_are_jumpers no)
		(fp_line
			(start -1.3208 0.7112)
			(end -1.3208 -0.7112)
			(stroke
				(width 0.1)
				(type default)
			)
			(layer "F.SilkS")
		)
		(fp_line
			(start 1.3208 0.7112)
			(end -1.3208 0.7112)
			(stroke
				(width 0.1)
				(type default)
			)
			(layer "F.SilkS")
		)
		(fp_line
			(start -1.3208 -0.7112)
			(end 1.3208 -0.7112)
			(stroke
				(width 0.1)
				(type default)
			)
			(layer "F.SilkS")
		)
		(fp_line
			(start 1.3208 -0.7112)
			(end 1.3208 0.7112)
			(stroke
				(width 0.1)
				(type default)
			)
			(layer "F.SilkS")
		)
		(fp_rect
			(start -1.3208 -0.7112)
			(end 1.3208 0.7112)
			(stroke
				(width 0)
				(type default)
			)
			(fill no)
			(layer "F.CrtYd")
		)
		(fp_line
			(start -0.8128 0.4572)
			(end -0.8128 -0.4572)
			(stroke
				(width 0.1)
				(type default)
			)
			(layer "F.Fab")
		)
		(fp_line
			(start 0.8128 0.4572)
			(end -0.8128 0.4572)
			(stroke
				(width 0.1)
				(type default)
			)
			(layer "F.Fab")
		)
		(fp_line
			(start -0.8128 -0.4572)
			(end 0.8128 -0.4572)
			(stroke
				(width 0.1)
				(type default)
			)
			(layer "F.Fab")
		)
		(fp_line
			(start 0.8128 -0.4572)
			(end 0.8128 0.4572)
			(stroke
				(width 0.1)
				(type default)
			)
			(layer "F.Fab")
		)
		(pad "1" smd rect
			(at -0.6858 0 270)
			(size 0.762 0.8636)
			(layers "F.Cu" "F.Mask" "F.Paste")
			(net "XP3R3V")
		)
		(pad "2" smd rect
			(at 0.6858 0 270)
			(size 0.762 0.8636)
			(layers "F.Cu" "F.Mask" "F.Paste")
			(net "UNNAMED_515_CAPACITOR_I130_1")
		)
		(zone
			(layer "F.Cu")
			(hatch none 0.5)
			(connect_pads
				(clearance 0)
			)
			(min_thickness 0.25)
			(keepout
				(tracks allowed)
				(vias not_allowed)
				(pads allowed)
				(copperpour not_allowed)
				(footprints allowed)
			)
			(placement
				(enabled no)
				(sheetname "")
			)
			(fill
				(thermal_gap 0.5)
				(thermal_bridge_width 0.5)
				(island_removal_mode 0)
			)
			(polygon
				(pts
					(xy 145.2372 -24.5364) (xy 144.3228 -24.5364) (xy 144.3228 -24.2316) (xy 145.2372 -24.2316)
				)
			)
		)
	)
	(footprint ""
		(layer "F.Cu")
		(at 89.281 -41.021 90)
		(property "Reference" "C155"
			(at -3.429 -0.21463 90)
			(unlocked yes)
			(layer "F.SilkS")
			(effects
				(font
					(size 0.7874 0.5842)
					(thickness 0.1524)
				)
			)
		)
		(property "Value" "VAL*"
			(at 0.0762 3.134106 90)
			(unlocked yes)
			(layer "F.Fab")
			(hide yes)
			(effects
				(font
					(size 0.7874 0.5842)
					(thickness 0.1524)
				)
			)
		)
		(property "Tolerance" "TOL*"
			(at 0.0762 4.048506 90)
			(unlocked yes)
			(layer "Cmts.User")
			(hide yes)
			(effects
				(font
					(size 0.7874 0.5842)
					(thickness 0.1524)
				)
			)
		)
		(property "User Part Number" "PARTNUM*"
			(at 0.1016 5.013706 90)
			(unlocked yes)
			(layer "Cmts.User")
			(hide yes)
			(effects
				(font
					(size 0.7874 0.5842)
					(thickness 0.1524)
				)
			)
		)
		(property "Device Type" "CAPACITOR-G107-0F476-AM,47UF,2A"
			(at 0.0508 2.194306 90)
			(unlocked yes)
			(layer "F.Fab")
			(hide yes)
			(effects
				(font
					(size 0.7874 0.5842)
					(thickness 0.1524)
				)
			)
		)
		(duplicate_pad_numbers_are_jumpers no)
		(fp_line
			(start 1.5748 -0.9398)
			(end -1.5748 -0.9398)
			(stroke
				(width 0.1)
				(type default)
			)
			(layer "F.SilkS")
		)
		(fp_line
			(start -1.5748 -0.9398)
			(end -1.5748 0.9398)
			(stroke
				(width 0.1)
				(type default)
			)
			(layer "F.SilkS")
		)
		(fp_line
			(start 1.5748 0.9398)
			(end 1.5748 -0.9398)
			(stroke
				(width 0.1)
				(type default)
			)
			(layer "F.SilkS")
		)
		(fp_line
			(start -1.5748 0.9398)
			(end 1.5748 0.9398)
			(stroke
				(width 0.1)
				(type default)
			)
			(layer "F.SilkS")
		)
		(fp_rect
			(start -1.5748 -0.9398)
			(end 1.5748 0.9398)
			(stroke
				(width 0)
				(type default)
			)
			(fill no)
			(layer "F.CrtYd")
		)
		(fp_line
			(start 1.016 -0.635)
			(end -1.016 -0.635)
			(stroke
				(width 0.1)
				(type default)
			)
			(layer "F.Fab")
		)
		(fp_line
			(start -1.016 -0.635)
			(end -1.016 0.635)
			(stroke
				(width 0.1)
				(type default)
			)
			(layer "F.Fab")
		)
		(fp_line
			(start 1.016 0.635)
			(end 1.016 -0.635)
			(stroke
				(width 0.1)
				(type default)
			)
			(layer "F.Fab")
		)
		(fp_line
			(start -1.016 0.635)
			(end 1.016 0.635)
			(stroke
				(width 0.1)
				(type default)
			)
			(layer "F.Fab")
		)
		(pad "1" smd rect
			(at -0.8382 0 90)
			(size 0.9652 1.3716)
			(layers "F.Cu" "F.Mask" "F.Paste")
			(net "XP1R0V_FPGA")
		)
		(pad "2" smd rect
			(at 0.8382 0 90)
			(size 0.9652 1.3716)
			(layers "F.Cu" "F.Mask" "F.Paste")
			(net "SG")
		)
		(zone
			(layer "F.Cu")
			(hatch none 0.5)
			(connect_pads
				(clearance 0)
			)
			(min_thickness 0.25)
			(keepout
				(tracks allowed)
				(vias not_allowed)
				(pads allowed)
				(copperpour not_allowed)
				(footprints allowed)
			)
			(placement
				(enabled no)
				(sheetname "")
			)
			(fill
				(thermal_gap 0.5)
				(thermal_bridge_width 0.5)
				(island_removal_mode 0)
			)
			(polygon
				(pts
					(xy 88.646 -40.7924) (xy 89.916 -40.7924) (xy 89.916 -41.2496) (xy 88.646 -41.2496)
				)
			)
		)
	)
	(footprint ""
		(layer "F.Cu")
		(at 83.947 -67.31)
		(property "Reference" "TP17"
			(at -1.8034 -0.85725 0)
			(unlocked yes)
			(layer "F.SilkS")
			(effects
				(font
					(size 0.635 0.4064)
					(thickness 0.1524)
				)
				(justify left)
			)
		)
		(property "Value" ""
			(at 0 0 0)
			(layer "F.Fab")
			(effects
				(font
					(size 1.27 1.27)
				)
			)
		)
		(property "Device Type" "TP_PIONT-TP010CT020B030_PTH-TPA"
			(at -1.341882 0.996696 0)
			(unlocked yes)
			(layer "F.Fab")
			(hide yes)
			(effects
				(font
					(size 0.7874 0.5842)
					(thickness 0.000001)
				)
				(justify left)
			)
		)
		(duplicate_pad_numbers_are_jumpers no)
		(fp_poly
			(pts
				(arc
					(start 0.889 0)
					(mid -0.889 0)
					(end 0.889 0)
				)
			)
			(stroke
				(width 0)
				(type default)
			)
			(fill no)
			(layer "B.CrtYd")
		)
		(fp_poly
			(pts
				(arc
					(start 0.889 0)
					(mid -0.889 0)
					(end 0.889 0)
				)
			)
			(stroke
				(width 0)
				(type default)
			)
			(fill no)
			(layer "F.CrtYd")
		)
		(pad "1" thru_hole circle
			(at 0 0)
			(size 0.508 0.508)
			(drill 0.254)
			(layers "*.Cu" "*.Mask")
			(remove_unused_layers no)
			(net "R_BNO080_INT_N")
			(clearance 0.1016)
			(padstack
				(mode front_inner_back)
				(layer "Inner"
					(shape circle)
					(size 0.508 0.508)
					(clearance 0.1016)
				)
				(layer "B.Cu"
					(shape circle)
					(size 0.762 0.762)
					(clearance -0.0254)
				)
			)
		)
	)
	(footprint ""
		(layer "F.Cu")
		(at 89.8652 -98.8568 180)
		(property "Reference" "C16"
			(at -1.905 -2.83337 0)
			(unlocked yes)
			(layer "F.SilkS")
			(effects
				(font
					(size 0.7874 0.5842)
					(thickness 0.1524)
				)
			)
		)
		(property "Value" "VAL*"
			(at 0.193548 2.13614 180)
			(unlocked yes)
			(layer "F.Fab")
			(hide yes)
			(effects
				(font
					(size 0.7874 0.5842)
					(thickness 0.1524)
				)
			)
		)
		(property "User Part Number" "PARTNUM*"
			(at 0.216154 4.185666 180)
			(unlocked yes)
			(layer "Cmts.User")
			(hide yes)
			(effects
				(font
					(size 0.7874 0.5842)
					(thickness 0.1524)
				)
			)
		)
		(property "Device Type" "CAPACITOR-G104-0B101-FK,100PF,A"
			(at 0.184404 1.180592 180)
			(unlocked yes)
			(layer "F.Fab")
			(hide yes)
			(effects
				(font
					(size 0.7874 0.5842)
					(thickness 0.1524)
				)
			)
		)
		(property "Tolerance" "TOL*"
			(at 0.216154 3.1496 180)
			(unlocked yes)
			(layer "Cmts.User")
			(hide yes)
			(effects
				(font
					(size 0.7874 0.5842)
					(thickness 0.1524)
				)
			)
		)
		(duplicate_pad_numbers_are_jumpers no)
		(fp_line
			(start 0.671322 0.4445)
			(end -0.671322 0.4445)
			(stroke
				(width 0.1)
				(type default)
			)
			(layer "F.SilkS")
		)
		(fp_line
			(start 0.671322 -0.4445)
			(end 0.671322 0.4445)
			(stroke
				(width 0.1)
				(type default)
			)
			(layer "F.SilkS")
		)
		(fp_line
			(start -0.671322 0.4445)
			(end -0.671322 -0.4445)
			(stroke
				(width 0.1)
				(type default)
			)
			(layer "F.SilkS")
		)
		(fp_line
			(start -0.671322 -0.4445)
			(end 0.671322 -0.4445)
			(stroke
				(width 0.1)
				(type default)
			)
			(layer "F.SilkS")
		)
		(fp_rect
			(start 0.671322 -0.4445)
			(end -0.671322 0.4445)
			(stroke
				(width 0)
				(type default)
			)
			(fill no)
			(layer "F.CrtYd")
		)
		(fp_line
			(start 0.31496 0.1651)
			(end 0.31496 -0.1651)
			(stroke
				(width 0.1)
				(type default)
			)
			(layer "F.Fab")
		)
		(fp_line
			(start 0.31496 -0.1651)
			(end -0.31496 -0.1651)
			(stroke
				(width 0.1)
				(type default)
			)
			(layer "F.Fab")
		)
		(fp_line
			(start -0.31496 0.1651)
			(end 0.31496 0.1651)
			(stroke
				(width 0.1)
				(type default)
			)
			(layer "F.Fab")
		)
		(fp_line
			(start -0.31496 -0.1651)
			(end -0.31496 0.1651)
			(stroke
				(width 0.1)
				(type default)
			)
			(layer "F.Fab")
		)
		(pad "1" smd rect
			(at -0.264922 0 180)
			(size 0.3048 0.381)
			(layers "F.Cu" "F.Mask" "F.Paste")
			(net "UNNAMED_517_CAPACITOR_I30_1")
		)
		(pad "2" smd rect
			(at 0.264922 0 180)
			(size 0.3048 0.381)
			(layers "F.Cu" "F.Mask" "F.Paste")
			(net "XP3R3V_FB_R_TO_AGND")
		)
		(zone
			(layer "F.Cu")
			(hatch none 0.5)
			(connect_pads
				(clearance 0)
			)
			(min_thickness 0.25)
			(keepout
				(tracks allowed)
				(vias not_allowed)
				(pads allowed)
				(copperpour not_allowed)
				(footprints allowed)
			)
			(placement
				(enabled no)
				(sheetname "")
			)
			(fill
				(thermal_gap 0.5)
				(thermal_bridge_width 0.5)
				(island_removal_mode 0)
			)
			(polygon
				(pts
					(xy 89.752678 -98.6663) (xy 89.977722 -98.6663) (xy 89.977722 -99.0473) (xy 89.752678 -99.0473)
				)
			)
		)
	)
	(footprint ""
		(layer "F.Cu")
		(at 16.3576 -17.78)
		(property "Reference" "TP31"
			(at 0.38735 3.6322 90)
			(unlocked yes)
			(layer "F.SilkS")
			(effects
				(font
					(size 0.635 0.4064)
					(thickness 0.1524)
				)
				(justify left)
			)
		)
		(property "Value" ""
			(at 0 0 0)
			(layer "F.Fab")
			(effects
				(font
					(size 1.27 1.27)
				)
			)
		)
		(property "Device Type" "TP_PIONT-TP010CT020B030_PTH-TPA"
			(at -1.341882 0.996696 0)
			(unlocked yes)
			(layer "F.Fab")
			(hide yes)
			(effects
				(font
					(size 0.7874 0.5842)
					(thickness 0.000001)
				)
				(justify left)
			)
		)
		(duplicate_pad_numbers_are_jumpers no)
		(fp_poly
			(pts
				(arc
					(start 0.889 0)
					(mid -0.889 0)
					(end 0.889 0)
				)
			)
			(stroke
				(width 0)
				(type default)
			)
			(fill no)
			(layer "B.CrtYd")
		)
		(fp_poly
			(pts
				(arc
					(start 0.889 0)
					(mid -0.889 0)
					(end 0.889 0)
				)
			)
			(stroke
				(width 0)
				(type default)
			)
			(fill no)
			(layer "F.CrtYd")
		)
		(pad "1" thru_hole circle
			(at 0 0)
			(size 0.508 0.508)
			(drill 0.254)
			(layers "*.Cu" "*.Mask")
			(remove_unused_layers no)
			(net "SMA4_SIG_IN_BF_EN_N")
			(clearance 0.1016)
			(padstack
				(mode front_inner_back)
				(layer "Inner"
					(shape circle)
					(size 0.508 0.508)
					(clearance 0.1016)
				)
				(layer "B.Cu"
					(shape circle)
					(size 0.762 0.762)
					(clearance -0.0254)
				)
			)
		)
	)
	(footprint ""
		(layer "F.Cu")
		(at 127.127 -21.082)
		(property "Reference" "U37"
			(at -0.889 -3.64363 0)
			(unlocked yes)
			(layer "F.SilkS")
			(effects
				(font
					(size 0.7874 0.5842)
					(thickness 0.1524)
				)
			)
		)
		(property "Value" ""
			(at 0 0 0)
			(layer "F.Fab")
			(effects
				(font
					(size 1.27 1.27)
				)
			)
		)
		(property "Device Type" "TS3A5018PWR_TSSOP16-G220-10324A"
			(at 0 0.924306 0)
			(unlocked yes)
			(layer "F.Fab")
			(hide yes)
			(effects
				(font
					(size 0.7874 0.5842)
					(thickness 0.000001)
				)
			)
		)
		(property "User Part Number" "PARTNUM*"
			(at 0.254 1.940306 0)
			(unlocked yes)
			(layer "Cmts.User")
			(hide yes)
			(effects
				(font
					(size 0.7874 0.5842)
					(thickness 0.000001)
				)
			)
		)
		(duplicate_pad_numbers_are_jumpers no)
		(fp_line
			(start -4.0767 -2.7559)
			(end 4.0767 -2.7559)
			(stroke
				(width 0.1)
				(type default)
			)
			(layer "F.SilkS")
		)
		(fp_line
			(start -4.0767 2.7559)
			(end -4.0767 -2.7559)
			(stroke
				(width 0.1)
				(type default)
			)
			(layer "F.SilkS")
		)
		(fp_line
			(start 4.0767 -2.7559)
			(end 4.0767 2.7559)
			(stroke
				(width 0.1)
				(type default)
			)
			(layer "F.SilkS")
		)
		(fp_line
			(start 4.0767 2.7559)
			(end -4.0767 2.7559)
			(stroke
				(width 0.1)
				(type default)
			)
			(layer "F.SilkS")
		)
		(fp_poly
			(pts
				(arc
					(start -3.937 -3.175)
					(mid -4.699 -3.175)
					(end -3.937 -3.175)
				)
			)
			(stroke
				(width 0)
				(type default)
			)
			(fill yes)
			(layer "F.SilkS")
		)
		(fp_rect
			(start -4.3307 3.0099)
			(end 4.3307 -3.0099)
			(stroke
				(width 0)
				(type default)
			)
			(fill no)
			(layer "F.CrtYd")
		)
		(fp_line
			(start -2.1971 -2.5019)
			(end 2.1971 -2.5019)
			(stroke
				(width 0.1)
				(type default)
			)
			(layer "F.Fab")
		)
		(fp_line
			(start -2.1971 2.5019)
			(end -2.1971 -2.5019)
			(stroke
				(width 0.1)
				(type default)
			)
			(layer "F.Fab")
		)
		(fp_line
			(start 2.1971 -2.5019)
			(end 2.1971 2.5019)
			(stroke
				(width 0.1)
				(type default)
			)
			(layer "F.Fab")
		)
		(fp_line
			(start 2.1971 2.5019)
			(end -2.1971 2.5019)
			(stroke
				(width 0.1)
				(type default)
			)
			(layer "F.Fab")
		)
		(fp_poly
			(pts
				(arc
					(start -1.114298 -1.942084)
					(mid -1.914398 -1.942084)
					(end -1.114298 -1.942084)
				)
			)
			(stroke
				(width 0)
				(type default)
			)
			(fill yes)
			(layer "F.Fab")
		)
		(fp_text user "8"
			(at -4.572 2.18567 0)
			(unlocked yes)
			(layer "F.SilkS")
			(effects
				(font
					(size 0.7874 0.5842)
					(thickness 0.1524)
				)
			)
		)
		(fp_text user "16"
			(at 4.064 -3.64363 0)
			(unlocked yes)
			(layer "F.SilkS")
			(effects
				(font
					(size 0.7874 0.5842)
					(thickness 0.1524)
				)
			)
		)
		(fp_text user "9"
			(at 4.699 2.96037 0)
			(unlocked yes)
			(layer "F.SilkS")
			(effects
				(font
					(size 0.7874 0.5842)
					(thickness 0.1524)
				)
			)
		)
		(fp_text user "8"
			(at -4.572 2.18567 0)
			(unlocked yes)
			(layer "F.Fab")
			(effects
				(font
					(size 0.7874 0.5842)
					(thickness 0.1524)
				)
			)
		)
		(fp_text user "9"
			(at 4.5466 2.31267 0)
			(unlocked yes)
			(layer "F.Fab")
			(effects
				(font
					(size 0.7874 0.5842)
					(thickness 0.1524)
				)
			)
		)
		(fp_text user "16"
			(at 4.8768 -2.38633 0)
			(unlocked yes)
			(layer "F.Fab")
			(effects
				(font
					(size 0.7874 0.5842)
					(thickness 0.1524)
				)
			)
		)
		(pad "1" smd rect
			(at -3.0353 -2.275078 90)
			(size 0.3556 1.5748)
			(layers "F.Cu" "F.Mask" "F.Paste")
			(net "MUX3_SEL")
		)
		(pad "2" smd rect
			(at -3.0353 -1.625092 90)
			(size 0.3556 1.5748)
			(layers "F.Cu" "F.Mask" "F.Paste")
			(net "FPGA_PCA9546_I2C_SDA")
		)
		(pad "3" smd rect
			(at -3.0353 -0.975106 90)
			(size 0.3556 1.5748)
			(layers "F.Cu" "F.Mask" "F.Paste")
			(net "FT4232_I2C_SDA")
		)
		(pad "4" smd rect
			(at -3.0353 -0.32512 90)
			(size 0.3556 1.5748)
			(layers "F.Cu" "F.Mask" "F.Paste")
			(net "PCA9546_I2C_SDA")
		)
		(pad "5" smd rect
			(at -3.0353 0.32512 90)
			(size 0.3556 1.5748)
			(layers "F.Cu" "F.Mask" "F.Paste")
			(net "FPGA_PCA9546_I2C_SCL")
		)
		(pad "6" smd rect
			(at -3.0353 0.975106 90)
			(size 0.3556 1.5748)
			(layers "F.Cu" "F.Mask" "F.Paste")
			(net "FT4232_I2C_SCL")
		)
		(pad "7" smd rect
			(at -3.0353 1.625092 90)
			(size 0.3556 1.5748)
			(layers "F.Cu" "F.Mask" "F.Paste")
			(net "PCA9546_I2C_SCL")
		)
		(pad "8" smd rect
			(at -3.0353 2.275078 90)
			(size 0.3556 1.5748)
			(layers "F.Cu" "F.Mask" "F.Paste")
			(net "SG")
		)
		(pad "9" smd rect
			(at 3.0353 2.275078 90)
			(size 0.3556 1.5748)
			(layers "F.Cu" "F.Mask" "F.Paste")
			(net "EEPROM_I2C_SDA")
		)
		(pad "10" smd rect
			(at 3.0353 1.625092 90)
			(size 0.3556 1.5748)
			(layers "F.Cu" "F.Mask" "F.Paste")
			(net "FT4232_I2C_SDA")
		)
		(pad "11" smd rect
			(at 3.0353 0.975106 90)
			(size 0.3556 1.5748)
			(layers "F.Cu" "F.Mask" "F.Paste")
			(net "FPGA_EEPROM_I2C_SDA")
		)
		(pad "12" smd rect
			(at 3.0353 0.32512 90)
			(size 0.3556 1.5748)
			(layers "F.Cu" "F.Mask" "F.Paste")
			(net "EEPROM_I2C_SCL")
		)
		(pad "13" smd rect
			(at 3.0353 -0.32512 90)
			(size 0.3556 1.5748)
			(layers "F.Cu" "F.Mask" "F.Paste")
			(net "FT4232_I2C_SCL")
		)
		(pad "14" smd rect
			(at 3.0353 -0.975106 90)
			(size 0.3556 1.5748)
			(layers "F.Cu" "F.Mask" "F.Paste")
			(net "FPGA_EEPROM_I2C_SCL")
		)
		(pad "15" smd rect
			(at 3.0353 -1.625092 90)
			(size 0.3556 1.5748)
			(layers "F.Cu" "F.Mask" "F.Paste")
			(net "UNNAMED_524_RESISTOR_I463_2")
		)
		(pad "16" smd rect
			(at 3.0353 -2.275078 90)
			(size 0.3556 1.5748)
			(layers "F.Cu" "F.Mask" "F.Paste")
			(net "XP3R3V_FPGA")
		)
	)
	(footprint ""
		(layer "F.Cu")
		(at 121.1072 -30.6578 90)
		(property "Reference" "TP193"
			(at -1.35255 0 0)
			(unlocked yes)
			(layer "F.SilkS")
			(effects
				(font
					(size 0.635 0.4064)
					(thickness 0.1524)
				)
				(justify left)
			)
		)
		(property "Value" ""
			(at 0 0 90)
			(layer "F.Fab")
			(effects
				(font
					(size 1.27 1.27)
				)
			)
		)
		(property "Device Type" "TP_PIONT-TP010CT020B030_PTH-TPA"
			(at -1.341882 0.996696 90)
			(unlocked yes)
			(layer "F.Fab")
			(hide yes)
			(effects
				(font
					(size 0.7874 0.5842)
					(thickness 0.1524)
				)
				(justify left)
			)
		)
		(duplicate_pad_numbers_are_jumpers no)
		(fp_poly
			(pts
				(arc
					(start 0 0.889)
					(mid 0 -0.889)
					(end 0 0.889)
				)
			)
			(stroke
				(width 0)
				(type default)
			)
			(fill no)
			(layer "B.CrtYd")
		)
		(fp_poly
			(pts
				(arc
					(start 0 0.889)
					(mid 0 -0.889)
					(end 0 0.889)
				)
			)
			(stroke
				(width 0)
				(type default)
			)
			(fill no)
			(layer "F.CrtYd")
		)
		(pad "1" thru_hole circle
			(at 0 0 90)
			(size 0.508 0.508)
			(drill 0.254)
			(layers "*.Cu" "*.Mask")
			(remove_unused_layers no)
			(net "IO_L21P_35")
			(clearance 0.1016)
			(padstack
				(mode front_inner_back)
				(layer "Inner"
					(shape circle)
					(size 0.508 0.508)
					(clearance 0.1016)
				)
				(layer "B.Cu"
					(shape circle)
					(size 0.762 0.762)
					(clearance -0.0254)
				)
			)
		)
	)
	(footprint ""
		(layer "F.Cu")
		(at 158.115 -50.894996 -90)
		(property "Reference" "C61"
			(at -0.794004 2.50063 90)
			(unlocked yes)
			(layer "F.SilkS")
			(effects
				(font
					(size 0.7874 0.5842)
					(thickness 0.1524)
				)
			)
		)
		(property "Value" "VAL*"
			(at 0.0762 3.134106 270)
			(unlocked yes)
			(layer "F.Fab")
			(hide yes)
			(effects
				(font
					(size 0.7874 0.5842)
					(thickness 0.1524)
				)
			)
		)
		(property "Tolerance" "TOL*"
			(at 0.0762 4.048506 270)
			(unlocked yes)
			(layer "Cmts.User")
			(hide yes)
			(effects
				(font
					(size 0.7874 0.5842)
					(thickness 0.1524)
				)
			)
		)
		(property "User Part Number" "PARTNUM*"
			(at 0.1016 5.013706 270)
			(unlocked yes)
			(layer "Cmts.User")
			(hide yes)
			(effects
				(font
					(size 0.7874 0.5842)
					(thickness 0.1524)
				)
			)
		)
		(property "Device Type" "CAPACITOR-G107-0F106-EM,10UF,2A"
			(at 0.0508 2.194306 270)
			(unlocked yes)
			(layer "F.Fab")
			(hide yes)
			(effects
				(font
					(size 0.7874 0.5842)
					(thickness 0.1524)
				)
			)
		)
		(duplicate_pad_numbers_are_jumpers no)
		(fp_line
			(start -1.5748 0.9398)
			(end 1.5748 0.9398)
			(stroke
				(width 0.1)
				(type default)
			)
			(layer "F.SilkS")
		)
		(fp_line
			(start 1.5748 0.9398)
			(end 1.5748 -0.9398)
			(stroke
				(width 0.1)
				(type default)
			)
			(layer "F.SilkS")
		)
		(fp_line
			(start -1.5748 -0.9398)
			(end -1.5748 0.9398)
			(stroke
				(width 0.1)
				(type default)
			)
			(layer "F.SilkS")
		)
		(fp_line
			(start 1.5748 -0.9398)
			(end -1.5748 -0.9398)
			(stroke
				(width 0.1)
				(type default)
			)
			(layer "F.SilkS")
		)
		(fp_rect
			(start 1.5748 -0.9398)
			(end -1.5748 0.9398)
			(stroke
				(width 0)
				(type default)
			)
			(fill no)
			(layer "F.CrtYd")
		)
		(fp_line
			(start -1.016 0.635)
			(end 1.016 0.635)
			(stroke
				(width 0.1)
				(type default)
			)
			(layer "F.Fab")
		)
		(fp_line
			(start 1.016 0.635)
			(end 1.016 -0.635)
			(stroke
				(width 0.1)
				(type default)
			)
			(layer "F.Fab")
		)
		(fp_line
			(start -1.016 -0.635)
			(end -1.016 0.635)
			(stroke
				(width 0.1)
				(type default)
			)
			(layer "F.Fab")
		)
		(fp_line
			(start 1.016 -0.635)
			(end -1.016 -0.635)
			(stroke
				(width 0.1)
				(type default)
			)
			(layer "F.Fab")
		)
		(pad "1" smd rect
			(at -0.8382 0 270)
			(size 0.9652 1.3716)
			(layers "F.Cu" "F.Mask" "F.Paste")
			(net "XP5R0V_USB_CONN")
		)
		(pad "2" smd rect
			(at 0.8382 0 270)
			(size 0.9652 1.3716)
			(layers "F.Cu" "F.Mask" "F.Paste")
			(net "SG")
		)
		(zone
			(layer "F.Cu")
			(hatch none 0.5)
			(connect_pads
				(clearance 0)
			)
			(min_thickness 0.25)
			(keepout
				(tracks allowed)
				(vias not_allowed)
				(pads allowed)
				(copperpour not_allowed)
				(footprints allowed)
			)
			(placement
				(enabled no)
				(sheetname "")
			)
			(fill
				(thermal_gap 0.5)
				(thermal_bridge_width 0.5)
				(island_removal_mode 0)
			)
			(polygon
				(pts
					(xy 158.75 -50.666396) (xy 158.75 -51.123596) (xy 157.48 -51.123596) (xy 157.48 -50.666396)
				)
			)
		)
	)
	(footprint ""
		(layer "F.Cu")
		(at 105.41 -31.369 90)
		(property "Reference" "TP195"
			(at 0 0 90)
			(layer "F.SilkS")
			(hide yes)
			(effects
				(font
					(size 1.27 1.27)
				)
			)
		)
		(property "Value" ""
			(at 0 0 90)
			(layer "F.Fab")
			(effects
				(font
					(size 1.27 1.27)
				)
			)
		)
		(property "Device Type" "TP_PIONT-TP010CT020B030_PTH-TPA"
			(at -1.341882 0.996696 90)
			(unlocked yes)
			(layer "F.Fab")
			(hide yes)
			(effects
				(font
					(size 0.7874 0.5842)
					(thickness 0.1524)
				)
				(justify left)
			)
		)
		(duplicate_pad_numbers_are_jumpers no)
		(fp_poly
			(pts
				(arc
					(start 0 0.889)
					(mid 0 -0.889)
					(end 0 0.889)
				)
			)
			(stroke
				(width 0)
				(type default)
			)
			(fill no)
			(layer "B.CrtYd")
		)
		(fp_poly
			(pts
				(arc
					(start 0 0.889)
					(mid 0 -0.889)
					(end 0 0.889)
				)
			)
			(stroke
				(width 0)
				(type default)
			)
			(fill no)
			(layer "F.CrtYd")
		)
		(pad "1" thru_hole circle
			(at 0 0 90)
			(size 0.508 0.508)
			(drill 0.254)
			(layers "*.Cu" "*.Mask")
			(remove_unused_layers no)
			(net "IO_L23P_35")
			(clearance 0.1016)
			(padstack
				(mode front_inner_back)
				(layer "Inner"
					(shape circle)
					(size 0.508 0.508)
					(clearance 0.1016)
				)
				(layer "B.Cu"
					(shape circle)
					(size 0.762 0.762)
					(clearance -0.0254)
				)
			)
		)
	)
	(footprint ""
		(layer "F.Cu")
		(at 96.8756 -78.5368)
		(property "Reference" "R140"
			(at 0.0254 -1.17983 0)
			(unlocked yes)
			(layer "F.SilkS")
			(effects
				(font
					(size 0.7874 0.5842)
					(thickness 0.1524)
				)
			)
		)
		(property "Value" "VAL*"
			(at 0.02032 2.13233 0)
			(unlocked yes)
			(layer "F.Fab")
			(hide yes)
			(effects
				(font
					(size 0.7874 0.5842)
					(thickness 0.1524)
				)
			)
		)
		(property "Device Type" "RESISTOR-G155-100R0-J0,0OHM,-"
			(at 0.008382 1.210564 0)
			(unlocked yes)
			(layer "F.Fab")
			(hide yes)
			(effects
				(font
					(size 0.7874 0.5842)
					(thickness 0.1524)
				)
			)
		)
		(property "User Part Number" "PARTNUM*"
			(at 0.02032 4.024884 0)
			(unlocked yes)
			(layer "Cmts.User")
			(hide yes)
			(effects
				(font
					(size 0.7874 0.5842)
					(thickness 0.1524)
				)
			)
		)
		(property "Tolerance" "TOL*"
			(at 0.044704 3.05435 0)
			(unlocked yes)
			(layer "Cmts.User")
			(hide yes)
			(effects
				(font
					(size 0.7874 0.5842)
					(thickness 0.1524)
				)
			)
		)
		(duplicate_pad_numbers_are_jumpers no)
		(fp_line
			(start -1.143 -0.5588)
			(end -1.143 0.5588)
			(stroke
				(width 0.1)
				(type default)
			)
			(layer "F.SilkS")
		)
		(fp_line
			(start -1.143 0.5588)
			(end 1.143 0.5588)
			(stroke
				(width 0.1)
				(type default)
			)
			(layer "F.SilkS")
		)
		(fp_line
			(start 1.143 -0.5588)
			(end -1.143 -0.5588)
			(stroke
				(width 0.1)
				(type default)
			)
			(layer "F.SilkS")
		)
		(fp_line
			(start 1.143 0.5588)
			(end 1.143 -0.5588)
			(stroke
				(width 0.1)
				(type default)
			)
			(layer "F.SilkS")
		)
		(fp_rect
			(start -1.143 -0.5588)
			(end 1.143 0.5588)
			(stroke
				(width 0)
				(type default)
			)
			(fill no)
			(layer "F.CrtYd")
		)
		(fp_line
			(start -0.508 -0.3048)
			(end -0.508 0.3048)
			(stroke
				(width 0.1)
				(type default)
			)
			(layer "F.Fab")
		)
		(fp_line
			(start -0.508 0.3048)
			(end 0.508 0.3048)
			(stroke
				(width 0.1)
				(type default)
			)
			(layer "F.Fab")
		)
		(fp_line
			(start 0.508 -0.3048)
			(end -0.508 -0.3048)
			(stroke
				(width 0.1)
				(type default)
			)
			(layer "F.Fab")
		)
		(fp_line
			(start 0.508 0.3048)
			(end 0.508 -0.3048)
			(stroke
				(width 0.1)
				(type default)
			)
			(layer "F.Fab")
		)
		(pad "1" smd rect
			(at -0.5334 0)
			(size 0.7112 0.6096)
			(layers "F.Cu" "F.Mask" "F.Paste")
			(net "XP1R0V_FPGA_PG")
		)
		(pad "2" smd rect
			(at 0.5334 0)
			(size 0.7112 0.6096)
			(layers "F.Cu" "F.Mask" "F.Paste")
			(net "XP1R2V_EN_R")
		)
		(zone
			(layer "F.Cu")
			(hatch none 0.5)
			(connect_pads
				(clearance 0)
			)
			(min_thickness 0.25)
			(keepout
				(tracks allowed)
				(vias not_allowed)
				(pads allowed)
				(copperpour not_allowed)
				(footprints allowed)
			)
			(placement
				(enabled no)
				(sheetname "")
			)
			(fill
				(thermal_gap 0.5)
				(thermal_bridge_width 0.5)
				(island_removal_mode 0)
			)
			(polygon
				(pts
					(xy 96.7994 -78.8416) (xy 96.7994 -78.232) (xy 96.9518 -78.232) (xy 96.9518 -78.8416)
				)
			)
		)
	)
	(footprint ""
		(layer "F.Cu")
		(at 98.044 -95.4532 180)
		(property "Reference" "R449"
			(at 1.143 3.05943 0)
			(unlocked yes)
			(layer "F.SilkS")
			(effects
				(font
					(size 0.7874 0.5842)
					(thickness 0.1524)
				)
			)
		)
		(property "Value" "VAL*"
			(at 0.02032 2.13233 180)
			(unlocked yes)
			(layer "F.Fab")
			(hide yes)
			(effects
				(font
					(size 0.7874 0.5842)
					(thickness 0.1524)
				)
			)
		)
		(property "Tolerance" "TOL*"
			(at 0.044704 3.05435 180)
			(unlocked yes)
			(layer "Cmts.User")
			(hide yes)
			(effects
				(font
					(size 0.7874 0.5842)
					(thickness 0.1524)
				)
			)
		)
		(property "User Part Number" "PARTNUM*"
			(at 0.02032 4.024884 180)
			(unlocked yes)
			(layer "Cmts.User")
			(hide yes)
			(effects
				(font
					(size 0.7874 0.5842)
					(thickness 0.1524)
				)
			)
		)
		(property "Device Type" "RESISTOR-G155-133R0-01,33OHM,1%"
			(at 0.008382 1.210564 180)
			(unlocked yes)
			(layer "F.Fab")
			(hide yes)
			(effects
				(font
					(size 0.7874 0.5842)
					(thickness 0.1524)
				)
			)
		)
		(duplicate_pad_numbers_are_jumpers no)
		(fp_line
			(start 1.143 0.5588)
			(end 1.143 -0.5588)
			(stroke
				(width 0.1)
				(type default)
			)
			(layer "F.SilkS")
		)
		(fp_line
			(start 1.143 -0.5588)
			(end -1.143 -0.5588)
			(stroke
				(width 0.1)
				(type default)
			)
			(layer "F.SilkS")
		)
		(fp_line
			(start -1.143 0.5588)
			(end 1.143 0.5588)
			(stroke
				(width 0.1)
				(type default)
			)
			(layer "F.SilkS")
		)
		(fp_line
			(start -1.143 -0.5588)
			(end -1.143 0.5588)
			(stroke
				(width 0.1)
				(type default)
			)
			(layer "F.SilkS")
		)
		(fp_poly
			(pts
				(xy -1.143 0.5588) (xy 1.143 0.5588) (xy 1.143 -0.5588) (xy -1.143 -0.5588)
			)
			(stroke
				(width 0)
				(type default)
			)
			(fill no)
			(layer "F.CrtYd")
		)
		(fp_line
			(start 0.508 0.3048)
			(end 0.508 -0.3048)
			(stroke
				(width 0.1)
				(type default)
			)
			(layer "F.Fab")
		)
		(fp_line
			(start 0.508 -0.3048)
			(end -0.508 -0.3048)
			(stroke
				(width 0.1)
				(type default)
			)
			(layer "F.Fab")
		)
		(fp_line
			(start -0.508 0.3048)
			(end 0.508 0.3048)
			(stroke
				(width 0.1)
				(type default)
			)
			(layer "F.Fab")
		)
		(fp_line
			(start -0.508 -0.3048)
			(end -0.508 0.3048)
			(stroke
				(width 0.1)
				(type default)
			)
			(layer "F.Fab")
		)
		(pad "1" smd rect
			(at -0.5334 0 180)
			(size 0.7112 0.6096)
			(layers "F.Cu" "F.Mask" "F.Paste")
			(net "MUX1_SEL")
		)
		(pad "2" smd rect
			(at 0.5334 0 180)
			(size 0.7112 0.6096)
			(layers "F.Cu" "F.Mask" "F.Paste")
			(net "FT4232_MUX1_SEL")
		)
		(zone
			(layer "F.Cu")
			(hatch none 0.5)
			(connect_pads
				(clearance 0)
			)
			(min_thickness 0.25)
			(keepout
				(tracks allowed)
				(vias not_allowed)
				(pads allowed)
				(copperpour not_allowed)
				(footprints allowed)
			)
			(placement
				(enabled no)
				(sheetname "")
			)
			(fill
				(thermal_gap 0.5)
				(thermal_bridge_width 0.5)
				(island_removal_mode 0)
			)
			(polygon
				(pts
					(xy 98.1202 -95.758) (xy 97.9678 -95.758) (xy 97.9678 -95.1484) (xy 98.1202 -95.1484)
				)
			)
		)
		(zone
			(layer "F.Cu")
			(hatch none 0.5)
			(connect_pads
				(clearance 0)
			)
			(min_thickness 0.25)
			(keepout
				(tracks not_allowed)
				(vias allowed)
				(pads allowed)
				(copperpour not_allowed)
				(footprints allowed)
			)
			(placement
				(enabled no)
				(sheetname "")
			)
			(fill
				(thermal_gap 0.5)
				(thermal_bridge_width 0.5)
				(island_removal_mode 0)
			)
			(polygon
				(pts
					(xy 98.1202 -95.758) (xy 97.9678 -95.758) (xy 97.9678 -95.1484) (xy 98.1202 -95.1484)
				)
			)
		)
	)
	(footprint ""
		(layer "F.Cu")
		(at 82.169 -66.802)
		(property "Reference" "TP16"
			(at -2.3114 -0.73025 0)
			(unlocked yes)
			(layer "F.SilkS")
			(effects
				(font
					(size 0.635 0.4064)
					(thickness 0.1524)
				)
				(justify left)
			)
		)
		(property "Value" ""
			(at 0 0 0)
			(layer "F.Fab")
			(effects
				(font
					(size 1.27 1.27)
				)
			)
		)
		(property "Device Type" "TP_PIONT-TP010CT020B030_PTH-TPA"
			(at -1.341882 0.996696 0)
			(unlocked yes)
			(layer "F.Fab")
			(hide yes)
			(effects
				(font
					(size 0.7874 0.5842)
					(thickness 0.000001)
				)
				(justify left)
			)
		)
		(duplicate_pad_numbers_are_jumpers no)
		(fp_poly
			(pts
				(arc
					(start 0.889 0)
					(mid -0.889 0)
					(end 0.889 0)
				)
			)
			(stroke
				(width 0)
				(type default)
			)
			(fill no)
			(layer "B.CrtYd")
		)
		(fp_poly
			(pts
				(arc
					(start 0.889 0)
					(mid -0.889 0)
					(end 0.889 0)
				)
			)
			(stroke
				(width 0)
				(type default)
			)
			(fill no)
			(layer "F.CrtYd")
		)
		(pad "1" thru_hole circle
			(at 0 0)
			(size 0.508 0.508)
			(drill 0.254)
			(layers "*.Cu" "*.Mask")
			(remove_unused_layers no)
			(net "R_BNO080_RST_N")
			(clearance 0.1016)
			(padstack
				(mode front_inner_back)
				(layer "Inner"
					(shape circle)
					(size 0.508 0.508)
					(clearance 0.1016)
				)
				(layer "B.Cu"
					(shape circle)
					(size 0.762 0.762)
					(clearance -0.0254)
				)
			)
		)
	)
	(footprint ""
		(layer "F.Cu")
		(at 73.787 -124.46)
		(property "Reference" "SP39"
			(at 0 0 0)
			(layer "F.SilkS")
			(hide yes)
			(effects
				(font
					(size 1.27 1.27)
				)
			)
		)
		(property "Value" ""
			(at 0 0 0)
			(layer "F.Fab")
			(effects
				(font
					(size 1.27 1.27)
				)
			)
		)
		(duplicate_pad_numbers_are_jumpers no)
	)
	(footprint ""
		(layer "F.Cu")
		(at 105.537 -93.345)
		(property "Reference" "U30"
			(at -0.254 -3.26263 0)
			(unlocked yes)
			(layer "F.SilkS")
			(effects
				(font
					(size 0.7874 0.5842)
					(thickness 0.1524)
				)
			)
		)
		(property "Value" ""
			(at 0 0 0)
			(layer "F.Fab")
			(effects
				(font
					(size 1.27 1.27)
				)
			)
		)
		(property "Device Type" "TS3A5018PWR_TSSOP16-G220-10324A"
			(at 0 0.924306 0)
			(unlocked yes)
			(layer "F.Fab")
			(hide yes)
			(effects
				(font
					(size 0.7874 0.5842)
					(thickness 0.000001)
				)
			)
		)
		(property "User Part Number" "PARTNUM*"
			(at 0.254 1.940306 0)
			(unlocked yes)
			(layer "Cmts.User")
			(hide yes)
			(effects
				(font
					(size 0.7874 0.5842)
					(thickness 0.000001)
				)
			)
		)
		(duplicate_pad_numbers_are_jumpers no)
		(fp_line
			(start -4.0767 -2.7559)
			(end 4.0767 -2.7559)
			(stroke
				(width 0.1)
				(type default)
			)
			(layer "F.SilkS")
		)
		(fp_line
			(start -4.0767 2.7559)
			(end -4.0767 -2.7559)
			(stroke
				(width 0.1)
				(type default)
			)
			(layer "F.SilkS")
		)
		(fp_line
			(start 4.0767 -2.7559)
			(end 4.0767 2.7559)
			(stroke
				(width 0.1)
				(type default)
			)
			(layer "F.SilkS")
		)
		(fp_line
			(start 4.0767 2.7559)
			(end -4.0767 2.7559)
			(stroke
				(width 0.1)
				(type default)
			)
			(layer "F.SilkS")
		)
		(fp_poly
			(pts
				(arc
					(start -4.3815 -2.2225)
					(mid -5.1435 -2.2225)
					(end -4.3815 -2.2225)
				)
			)
			(stroke
				(width 0)
				(type default)
			)
			(fill yes)
			(layer "F.SilkS")
		)
		(fp_rect
			(start -4.3307 3.0099)
			(end 4.3307 -3.0099)
			(stroke
				(width 0)
				(type default)
			)
			(fill no)
			(layer "F.CrtYd")
		)
		(fp_line
			(start -2.1971 -2.5019)
			(end 2.1971 -2.5019)
			(stroke
				(width 0.1)
				(type default)
			)
			(layer "F.Fab")
		)
		(fp_line
			(start -2.1971 2.5019)
			(end -2.1971 -2.5019)
			(stroke
				(width 0.1)
				(type default)
			)
			(layer "F.Fab")
		)
		(fp_line
			(start 2.1971 -2.5019)
			(end 2.1971 2.5019)
			(stroke
				(width 0.1)
				(type default)
			)
			(layer "F.Fab")
		)
		(fp_line
			(start 2.1971 2.5019)
			(end -2.1971 2.5019)
			(stroke
				(width 0.1)
				(type default)
			)
			(layer "F.Fab")
		)
		(fp_poly
			(pts
				(arc
					(start -1.114298 -1.942084)
					(mid -1.914398 -1.942084)
					(end -1.114298 -1.942084)
				)
			)
			(stroke
				(width 0)
				(type default)
			)
			(fill yes)
			(layer "F.Fab")
		)
		(fp_text user "8"
			(at -4.699 2.57937 0)
			(unlocked yes)
			(layer "F.SilkS")
			(effects
				(font
					(size 0.7874 0.5842)
					(thickness 0.1524)
				)
			)
		)
		(fp_text user "16"
			(at 4.572 -2.50825 0)
			(unlocked yes)
			(layer "F.SilkS")
			(effects
				(font
					(size 0.635 0.4064)
					(thickness 0.1524)
				)
			)
		)
		(fp_text user "9"
			(at 4.699 2.83337 0)
			(unlocked yes)
			(layer "F.SilkS")
			(effects
				(font
					(size 0.7874 0.5842)
					(thickness 0.1524)
				)
			)
		)
		(fp_text user "8"
			(at -4.572 2.18567 0)
			(unlocked yes)
			(layer "F.Fab")
			(effects
				(font
					(size 0.7874 0.5842)
					(thickness 0.1524)
				)
			)
		)
		(fp_text user "9"
			(at 4.5466 2.31267 0)
			(unlocked yes)
			(layer "F.Fab")
			(effects
				(font
					(size 0.7874 0.5842)
					(thickness 0.1524)
				)
			)
		)
		(fp_text user "16"
			(at 4.572 -3.00863 0)
			(unlocked yes)
			(layer "F.Fab")
			(effects
				(font
					(size 0.7874 0.5842)
					(thickness 0.1524)
				)
			)
		)
		(pad "1" smd rect
			(at -3.0353 -2.275078 90)
			(size 0.3556 1.5748)
			(layers "F.Cu" "F.Mask" "F.Paste")
			(net "MUX1_SEL")
		)
		(pad "2" smd rect
			(at -3.0353 -1.625092 90)
			(size 0.3556 1.5748)
			(layers "F.Cu" "F.Mask" "F.Paste")
			(net "FT4232_FPGA_TCK")
		)
		(pad "3" smd rect
			(at -3.0353 -0.975106 90)
			(size 0.3556 1.5748)
			(layers "F.Cu" "F.Mask" "F.Paste")
			(net "FT4232_SPI_CLK")
		)
		(pad "4" smd rect
			(at -3.0353 -0.32512 90)
			(size 0.3556 1.5748)
			(layers "F.Cu" "F.Mask" "F.Paste")
			(net "FT4232_TCK_SCLK")
		)
		(pad "5" smd rect
			(at -3.0353 0.32512 90)
			(size 0.3556 1.5748)
			(layers "F.Cu" "F.Mask" "F.Paste")
			(net "FT4232_FPGA_TDI")
		)
		(pad "6" smd rect
			(at -3.0353 0.975106 90)
			(size 0.3556 1.5748)
			(layers "F.Cu" "F.Mask" "F.Paste")
			(net "FT4232_SPI_MOSI")
		)
		(pad "7" smd rect
			(at -3.0353 1.625092 90)
			(size 0.3556 1.5748)
			(layers "F.Cu" "F.Mask" "F.Paste")
			(net "FT4232_TDI_MOSI")
		)
		(pad "8" smd rect
			(at -3.0353 2.275078 90)
			(size 0.3556 1.5748)
			(layers "F.Cu" "F.Mask" "F.Paste")
			(net "SG")
		)
		(pad "9" smd rect
			(at 3.0353 2.275078 90)
			(size 0.3556 1.5748)
			(layers "F.Cu" "F.Mask" "F.Paste")
			(net "FT4232_TDO_MISO")
		)
		(pad "10" smd rect
			(at 3.0353 1.625092 90)
			(size 0.3556 1.5748)
			(layers "F.Cu" "F.Mask" "F.Paste")
			(net "FT4232_SPI_MISO")
		)
		(pad "11" smd rect
			(at 3.0353 0.975106 90)
			(size 0.3556 1.5748)
			(layers "F.Cu" "F.Mask" "F.Paste")
			(net "FT4232_FPGA_TDO")
		)
		(pad "12" smd rect
			(at 3.0353 0.32512 90)
			(size 0.3556 1.5748)
			(layers "F.Cu" "F.Mask" "F.Paste")
			(net "FT4232_TMS_SPICS_N")
		)
		(pad "13" smd rect
			(at 3.0353 -0.32512 90)
			(size 0.3556 1.5748)
			(layers "F.Cu" "F.Mask" "F.Paste")
			(net "FT4232_SPI_CS_N")
		)
		(pad "14" smd rect
			(at 3.0353 -0.975106 90)
			(size 0.3556 1.5748)
			(layers "F.Cu" "F.Mask" "F.Paste")
			(net "FT4232_FPGA_TMS")
		)
		(pad "15" smd rect
			(at 3.0353 -1.625092 90)
			(size 0.3556 1.5748)
			(layers "F.Cu" "F.Mask" "F.Paste")
			(net "UNNAMED_524_POWERMOS3PNCHV1_I44")
		)
		(pad "16" smd rect
			(at 3.0353 -2.275078 90)
			(size 0.3556 1.5748)
			(layers "F.Cu" "F.Mask" "F.Paste")
			(net "XP3R3V_FPGA")
		)
	)
	(footprint ""
		(layer "F.Cu")
		(at 97.4598 -70.485)
		(property "Reference" "R185"
			(at -28.1178 -18.75663 0)
			(unlocked yes)
			(layer "F.SilkS")
			(effects
				(font
					(size 0.7874 0.5842)
					(thickness 0.1524)
				)
			)
		)
		(property "Value" "VAL*"
			(at 0.0508 2.245106 0)
			(unlocked yes)
			(layer "F.Fab")
			(hide yes)
			(effects
				(font
					(size 0.7874 0.5842)
					(thickness 0.1524)
				)
			)
		)
		(property "User Part Number" "PARTNUM*"
			(at 0.0762 4.302506 0)
			(unlocked yes)
			(layer "Cmts.User")
			(hide yes)
			(effects
				(font
					(size 0.7874 0.5842)
					(thickness 0.1524)
				)
			)
		)
		(property "Device Type" "RESISTOR-G155-04221-01,4.22KOHA"
			(at 0.0762 1.254506 0)
			(unlocked yes)
			(layer "F.Fab")
			(hide yes)
			(effects
				(font
					(size 0.7874 0.5842)
					(thickness 0.1524)
				)
			)
		)
		(property "Tolerance" "TOL*"
			(at 0.0508 3.261106 0)
			(unlocked yes)
			(layer "Cmts.User")
			(hide yes)
			(effects
				(font
					(size 0.7874 0.5842)
					(thickness 0.1524)
				)
			)
		)
		(duplicate_pad_numbers_are_jumpers no)
		(fp_line
			(start -1.143 -0.5588)
			(end -1.143 0.5588)
			(stroke
				(width 0.1)
				(type default)
			)
			(layer "F.SilkS")
		)
		(fp_line
			(start -1.143 0.5588)
			(end 1.143 0.5588)
			(stroke
				(width 0.1)
				(type default)
			)
			(layer "F.SilkS")
		)
		(fp_line
			(start 1.143 -0.5588)
			(end -1.143 -0.5588)
			(stroke
				(width 0.1)
				(type default)
			)
			(layer "F.SilkS")
		)
		(fp_line
			(start 1.143 0.5588)
			(end 1.143 -0.5588)
			(stroke
				(width 0.1)
				(type default)
			)
			(layer "F.SilkS")
		)
		(fp_rect
			(start -1.143 -0.5588)
			(end 1.143 0.5588)
			(stroke
				(width 0)
				(type default)
			)
			(fill no)
			(layer "F.CrtYd")
		)
		(fp_line
			(start -0.508 -0.3048)
			(end -0.508 0.3048)
			(stroke
				(width 0.1)
				(type default)
			)
			(layer "F.Fab")
		)
		(fp_line
			(start -0.508 0.3048)
			(end 0.508 0.3048)
			(stroke
				(width 0.1)
				(type default)
			)
			(layer "F.Fab")
		)
		(fp_line
			(start 0.508 -0.3048)
			(end -0.508 -0.3048)
			(stroke
				(width 0.1)
				(type default)
			)
			(layer "F.Fab")
		)
		(fp_line
			(start 0.508 0.3048)
			(end 0.508 -0.3048)
			(stroke
				(width 0.1)
				(type default)
			)
			(layer "F.Fab")
		)
		(pad "1" smd rect
			(at -0.5334 0)
			(size 0.7112 0.6096)
			(layers "F.Cu" "F.Mask" "F.Paste")
			(net "XP1R2V_FPGA")
		)
		(pad "2" smd rect
			(at 0.5334 0)
			(size 0.7112 0.6096)
			(layers "F.Cu" "F.Mask" "F.Paste")
			(net "XP1R2V_FB")
		)
		(zone
			(layer "F.Cu")
			(hatch none 0.5)
			(connect_pads
				(clearance 0)
			)
			(min_thickness 0.25)
			(keepout
				(tracks allowed)
				(vias not_allowed)
				(pads allowed)
				(copperpour not_allowed)
				(footprints allowed)
			)
			(placement
				(enabled no)
				(sheetname "")
			)
			(fill
				(thermal_gap 0.5)
				(thermal_bridge_width 0.5)
				(island_removal_mode 0)
			)
			(polygon
				(pts
					(xy 97.3836 -70.7898) (xy 97.3836 -70.1802) (xy 97.536 -70.1802) (xy 97.536 -70.7898)
				)
			)
		)
	)
	(footprint ""
		(layer "F.Cu")
		(at 115.062 -61.976 90)
		(property "Reference" "R339"
			(at 3.302 0.29337 90)
			(unlocked yes)
			(layer "F.SilkS")
			(effects
				(font
					(size 0.7874 0.5842)
					(thickness 0.1524)
				)
			)
		)
		(property "Value" "VAL*"
			(at 0.02032 2.13233 90)
			(unlocked yes)
			(layer "F.Fab")
			(hide yes)
			(effects
				(font
					(size 0.7874 0.5842)
					(thickness 0.1524)
				)
			)
		)
		(property "Tolerance" "TOL*"
			(at 0.044704 3.05435 90)
			(unlocked yes)
			(layer "Cmts.User")
			(hide yes)
			(effects
				(font
					(size 0.7874 0.5842)
					(thickness 0.1524)
				)
			)
		)
		(property "User Part Number" "PARTNUM*"
			(at 0.02032 4.024884 90)
			(unlocked yes)
			(layer "Cmts.User")
			(hide yes)
			(effects
				(font
					(size 0.7874 0.5842)
					(thickness 0.1524)
				)
			)
		)
		(property "Device Type" "RESISTOR-G155-133R0-01,33OHM,1%"
			(at 0.008382 1.210564 90)
			(unlocked yes)
			(layer "F.Fab")
			(hide yes)
			(effects
				(font
					(size 0.7874 0.5842)
					(thickness 0.1524)
				)
			)
		)
		(duplicate_pad_numbers_are_jumpers no)
		(fp_line
			(start 1.143 -0.5588)
			(end -1.143 -0.5588)
			(stroke
				(width 0.1)
				(type default)
			)
			(layer "F.SilkS")
		)
		(fp_line
			(start -1.143 -0.5588)
			(end -1.143 0.5588)
			(stroke
				(width 0.1)
				(type default)
			)
			(layer "F.SilkS")
		)
		(fp_line
			(start 1.143 0.5588)
			(end 1.143 -0.5588)
			(stroke
				(width 0.1)
				(type default)
			)
			(layer "F.SilkS")
		)
		(fp_line
			(start -1.143 0.5588)
			(end 1.143 0.5588)
			(stroke
				(width 0.1)
				(type default)
			)
			(layer "F.SilkS")
		)
		(fp_poly
			(pts
				(xy -1.143 0.5588) (xy 1.143 0.5588) (xy 1.143 -0.5588) (xy -1.143 -0.5588)
			)
			(stroke
				(width 0)
				(type default)
			)
			(fill no)
			(layer "F.CrtYd")
		)
		(fp_line
			(start 0.508 -0.3048)
			(end -0.508 -0.3048)
			(stroke
				(width 0.1)
				(type default)
			)
			(layer "F.Fab")
		)
		(fp_line
			(start -0.508 -0.3048)
			(end -0.508 0.3048)
			(stroke
				(width 0.1)
				(type default)
			)
			(layer "F.Fab")
		)
		(fp_line
			(start 0.508 0.3048)
			(end 0.508 -0.3048)
			(stroke
				(width 0.1)
				(type default)
			)
			(layer "F.Fab")
		)
		(fp_line
			(start -0.508 0.3048)
			(end 0.508 0.3048)
			(stroke
				(width 0.1)
				(type default)
			)
			(layer "F.Fab")
		)
		(pad "1" smd rect
			(at -0.5334 0 90)
			(size 0.7112 0.6096)
			(layers "F.Cu" "F.Mask" "F.Paste")
			(net "FPGA_D02")
		)
		(pad "2" smd rect
			(at 0.5334 0 90)
			(size 0.7112 0.6096)
			(layers "F.Cu" "F.Mask" "F.Paste")
			(net "FPGA_FLASH_DQ2")
		)
		(zone
			(layer "F.Cu")
			(hatch none 0.5)
			(connect_pads
				(clearance 0)
			)
			(min_thickness 0.25)
			(keepout
				(tracks not_allowed)
				(vias allowed)
				(pads allowed)
				(copperpour not_allowed)
				(footprints allowed)
			)
			(placement
				(enabled no)
				(sheetname "")
			)
			(fill
				(thermal_gap 0.5)
				(thermal_bridge_width 0.5)
				(island_removal_mode 0)
			)
			(polygon
				(pts
					(xy 115.3668 -61.8998) (xy 115.3668 -62.0522) (xy 114.7572 -62.0522) (xy 114.7572 -61.8998)
				)
			)
		)
		(zone
			(layer "F.Cu")
			(hatch none 0.5)
			(connect_pads
				(clearance 0)
			)
			(min_thickness 0.25)
			(keepout
				(tracks allowed)
				(vias not_allowed)
				(pads allowed)
				(copperpour not_allowed)
				(footprints allowed)
			)
			(placement
				(enabled no)
				(sheetname "")
			)
			(fill
				(thermal_gap 0.5)
				(thermal_bridge_width 0.5)
				(island_removal_mode 0)
			)
			(polygon
				(pts
					(xy 115.3668 -61.8998) (xy 115.3668 -62.0522) (xy 114.7572 -62.0522) (xy 114.7572 -61.8998)
				)
			)
		)
	)
	(footprint ""
		(layer "F.Cu")
		(at 141.605 -24.511 -90)
		(property "Reference" "C224"
			(at -3.556 -0.16637 90)
			(unlocked yes)
			(layer "F.SilkS")
			(effects
				(font
					(size 0.7874 0.5842)
					(thickness 0.1524)
				)
			)
		)
		(property "Value" "VAL*"
			(at 0.0762 3.134106 270)
			(unlocked yes)
			(layer "F.Fab")
			(hide yes)
			(effects
				(font
					(size 0.7874 0.5842)
					(thickness 0.1524)
				)
			)
		)
		(property "Tolerance" "TOL*"
			(at 0.0762 4.048506 270)
			(unlocked yes)
			(layer "Cmts.User")
			(hide yes)
			(effects
				(font
					(size 0.7874 0.5842)
					(thickness 0.1524)
				)
			)
		)
		(property "User Part Number" "PARTNUM*"
			(at 0.1016 5.013706 270)
			(unlocked yes)
			(layer "Cmts.User")
			(hide yes)
			(effects
				(font
					(size 0.7874 0.5842)
					(thickness 0.1524)
				)
			)
		)
		(property "Device Type" "CAPACITOR-G107-0F226-CM,22UF,2A"
			(at 0.0508 2.194306 270)
			(unlocked yes)
			(layer "F.Fab")
			(hide yes)
			(effects
				(font
					(size 0.7874 0.5842)
					(thickness 0.1524)
				)
			)
		)
		(duplicate_pad_numbers_are_jumpers no)
		(fp_line
			(start -1.5748 0.9398)
			(end 1.5748 0.9398)
			(stroke
				(width 0.1)
				(type default)
			)
			(layer "F.SilkS")
		)
		(fp_line
			(start 1.5748 0.9398)
			(end 1.5748 -0.9398)
			(stroke
				(width 0.1)
				(type default)
			)
			(layer "F.SilkS")
		)
		(fp_line
			(start -1.5748 -0.9398)
			(end -1.5748 0.9398)
			(stroke
				(width 0.1)
				(type default)
			)
			(layer "F.SilkS")
		)
		(fp_line
			(start 1.5748 -0.9398)
			(end -1.5748 -0.9398)
			(stroke
				(width 0.1)
				(type default)
			)
			(layer "F.SilkS")
		)
		(fp_rect
			(start -1.5748 -0.9398)
			(end 1.5748 0.9398)
			(stroke
				(width 0)
				(type default)
			)
			(fill no)
			(layer "F.CrtYd")
		)
		(fp_line
			(start -1.016 0.635)
			(end 1.016 0.635)
			(stroke
				(width 0.1)
				(type default)
			)
			(layer "F.Fab")
		)
		(fp_line
			(start 1.016 0.635)
			(end 1.016 -0.635)
			(stroke
				(width 0.1)
				(type default)
			)
			(layer "F.Fab")
		)
		(fp_line
			(start -1.016 -0.635)
			(end -1.016 0.635)
			(stroke
				(width 0.1)
				(type default)
			)
			(layer "F.Fab")
		)
		(fp_line
			(start 1.016 -0.635)
			(end -1.016 -0.635)
			(stroke
				(width 0.1)
				(type default)
			)
			(layer "F.Fab")
		)
		(pad "1" smd rect
			(at -0.8382 0 270)
			(size 0.9652 1.3716)
			(layers "F.Cu" "F.Mask" "F.Paste")
			(net "XP3R3V")
		)
		(pad "2" smd rect
			(at 0.8382 0 270)
			(size 0.9652 1.3716)
			(layers "F.Cu" "F.Mask" "F.Paste")
			(net "SG")
		)
		(zone
			(layer "F.Cu")
			(hatch none 0.5)
			(connect_pads
				(clearance 0)
			)
			(min_thickness 0.25)
			(keepout
				(tracks allowed)
				(vias not_allowed)
				(pads allowed)
				(copperpour not_allowed)
				(footprints allowed)
			)
			(placement
				(enabled no)
				(sheetname "")
			)
			(fill
				(thermal_gap 0.5)
				(thermal_bridge_width 0.5)
				(island_removal_mode 0)
			)
			(polygon
				(pts
					(xy 142.24 -24.7396) (xy 140.97 -24.7396) (xy 140.97 -24.2824) (xy 142.24 -24.2824)
				)
			)
		)
	)
	(footprint ""
		(layer "F.Cu")
		(at 117.3734 -99.7458 180)
		(property "Reference" "C79"
			(at -0.2286 1.68783 0)
			(unlocked yes)
			(layer "F.SilkS")
			(effects
				(font
					(size 0.7874 0.5842)
					(thickness 0.1524)
				)
			)
		)
		(property "Value" "VAL*"
			(at 0.0762 3.134106 180)
			(unlocked yes)
			(layer "F.Fab")
			(hide yes)
			(effects
				(font
					(size 0.7874 0.5842)
					(thickness 0.1524)
				)
			)
		)
		(property "Tolerance" "TOL*"
			(at 0.0762 4.048506 180)
			(unlocked yes)
			(layer "Cmts.User")
			(hide yes)
			(effects
				(font
					(size 0.7874 0.5842)
					(thickness 0.1524)
				)
			)
		)
		(property "User Part Number" "PARTNUM*"
			(at 0.1016 5.013706 180)
			(unlocked yes)
			(layer "Cmts.User")
			(hide yes)
			(effects
				(font
					(size 0.7874 0.5842)
					(thickness 0.1524)
				)
			)
		)
		(property "Device Type" "CAPACITOR-G107-0F106-EM,10UF,2A"
			(at 0.0508 2.194306 180)
			(unlocked yes)
			(layer "F.Fab")
			(hide yes)
			(effects
				(font
					(size 0.7874 0.5842)
					(thickness 0.1524)
				)
			)
		)
		(duplicate_pad_numbers_are_jumpers no)
		(fp_line
			(start 1.5748 0.9398)
			(end 1.5748 -0.9398)
			(stroke
				(width 0.1)
				(type default)
			)
			(layer "F.SilkS")
		)
		(fp_line
			(start 1.5748 -0.9398)
			(end -1.5748 -0.9398)
			(stroke
				(width 0.1)
				(type default)
			)
			(layer "F.SilkS")
		)
		(fp_line
			(start -1.5748 0.9398)
			(end 1.5748 0.9398)
			(stroke
				(width 0.1)
				(type default)
			)
			(layer "F.SilkS")
		)
		(fp_line
			(start -1.5748 -0.9398)
			(end -1.5748 0.9398)
			(stroke
				(width 0.1)
				(type default)
			)
			(layer "F.SilkS")
		)
		(fp_poly
			(pts
				(xy 1.5748 0.9398) (xy -1.5748 0.9398) (xy -1.5748 -0.9398) (xy 1.5748 -0.9398)
			)
			(stroke
				(width 0)
				(type default)
			)
			(fill no)
			(layer "F.CrtYd")
		)
		(fp_line
			(start 1.016 0.635)
			(end 1.016 -0.635)
			(stroke
				(width 0.1)
				(type default)
			)
			(layer "F.Fab")
		)
		(fp_line
			(start 1.016 -0.635)
			(end -1.016 -0.635)
			(stroke
				(width 0.1)
				(type default)
			)
			(layer "F.Fab")
		)
		(fp_line
			(start -1.016 0.635)
			(end 1.016 0.635)
			(stroke
				(width 0.1)
				(type default)
			)
			(layer "F.Fab")
		)
		(fp_line
			(start -1.016 -0.635)
			(end -1.016 0.635)
			(stroke
				(width 0.1)
				(type default)
			)
			(layer "F.Fab")
		)
		(pad "1" smd rect
			(at -0.8382 0 180)
			(size 0.9652 1.3716)
			(layers "F.Cu" "F.Mask" "F.Paste")
			(net "XP3R3V_GPS")
		)
		(pad "2" smd rect
			(at 0.8382 0 180)
			(size 0.9652 1.3716)
			(layers "F.Cu" "F.Mask" "F.Paste")
			(net "SG")
		)
		(zone
			(layer "F.Cu")
			(hatch none 0.5)
			(connect_pads
				(clearance 0)
			)
			(min_thickness 0.25)
			(keepout
				(tracks allowed)
				(vias not_allowed)
				(pads allowed)
				(copperpour not_allowed)
				(footprints allowed)
			)
			(placement
				(enabled no)
				(sheetname "")
			)
			(fill
				(thermal_gap 0.5)
				(thermal_bridge_width 0.5)
				(island_removal_mode 0)
			)
			(polygon
				(pts
					(xy 117.1448 -100.3808) (xy 117.1448 -99.1108) (xy 117.602 -99.1108) (xy 117.602 -100.3808)
				)
			)
		)
	)
	(footprint ""
		(layer "F.Cu")
		(at 57.023 -126.746)
		(property "Reference" "SP80"
			(at 0 0 0)
			(layer "F.SilkS")
			(hide yes)
			(effects
				(font
					(size 1.27 1.27)
				)
			)
		)
		(property "Value" ""
			(at 0 0 0)
			(layer "F.Fab")
			(effects
				(font
					(size 1.27 1.27)
				)
			)
		)
		(duplicate_pad_numbers_are_jumpers no)
	)
	(footprint ""
		(layer "F.Cu")
		(at 144.526 -40.894)
		(property "Reference" "C269"
			(at 0.127 1.56337 0)
			(unlocked yes)
			(layer "F.SilkS")
			(effects
				(font
					(size 0.7874 0.5842)
					(thickness 0.1524)
				)
			)
		)
		(property "Value" "VAL*"
			(at 0.0762 3.134106 0)
			(unlocked yes)
			(layer "F.Fab")
			(hide yes)
			(effects
				(font
					(size 0.7874 0.5842)
					(thickness 0.1524)
				)
			)
		)
		(property "Tolerance" "TOL*"
			(at 0.0762 4.048506 0)
			(unlocked yes)
			(layer "Cmts.User")
			(hide yes)
			(effects
				(font
					(size 0.7874 0.5842)
					(thickness 0.1524)
				)
			)
		)
		(property "User Part Number" "PARTNUM*"
			(at 0.1016 5.013706 0)
			(unlocked yes)
			(layer "Cmts.User")
			(hide yes)
			(effects
				(font
					(size 0.7874 0.5842)
					(thickness 0.1524)
				)
			)
		)
		(property "Device Type" "CAPACITOR-G107-0F476-AM,47UF,2A"
			(at 0.0508 2.194306 0)
			(unlocked yes)
			(layer "F.Fab")
			(hide yes)
			(effects
				(font
					(size 0.7874 0.5842)
					(thickness 0.1524)
				)
			)
		)
		(duplicate_pad_numbers_are_jumpers no)
		(fp_line
			(start -1.5748 -0.9398)
			(end -1.5748 0.9398)
			(stroke
				(width 0.1)
				(type default)
			)
			(layer "F.SilkS")
		)
		(fp_line
			(start -1.5748 0.9398)
			(end 1.5748 0.9398)
			(stroke
				(width 0.1)
				(type default)
			)
			(layer "F.SilkS")
		)
		(fp_line
			(start 1.5748 -0.9398)
			(end -1.5748 -0.9398)
			(stroke
				(width 0.1)
				(type default)
			)
			(layer "F.SilkS")
		)
		(fp_line
			(start 1.5748 0.9398)
			(end 1.5748 -0.9398)
			(stroke
				(width 0.1)
				(type default)
			)
			(layer "F.SilkS")
		)
		(fp_rect
			(start -1.5748 0.9398)
			(end 1.5748 -0.9398)
			(stroke
				(width 0)
				(type default)
			)
			(fill no)
			(layer "F.CrtYd")
		)
		(fp_line
			(start -1.016 -0.635)
			(end -1.016 0.635)
			(stroke
				(width 0.1)
				(type default)
			)
			(layer "F.Fab")
		)
		(fp_line
			(start -1.016 0.635)
			(end 1.016 0.635)
			(stroke
				(width 0.1)
				(type default)
			)
			(layer "F.Fab")
		)
		(fp_line
			(start 1.016 -0.635)
			(end -1.016 -0.635)
			(stroke
				(width 0.1)
				(type default)
			)
			(layer "F.Fab")
		)
		(fp_line
			(start 1.016 0.635)
			(end 1.016 -0.635)
			(stroke
				(width 0.1)
				(type default)
			)
			(layer "F.Fab")
		)
		(pad "1" smd rect
			(at -0.8382 0)
			(size 0.9652 1.3716)
			(layers "F.Cu" "F.Mask" "F.Paste")
			(net "XP1R0V_FPGA")
		)
		(pad "2" smd rect
			(at 0.8382 0)
			(size 0.9652 1.3716)
			(layers "F.Cu" "F.Mask" "F.Paste")
			(net "SG")
		)
		(zone
			(layer "F.Cu")
			(hatch none 0.5)
			(connect_pads
				(clearance 0)
			)
			(min_thickness 0.25)
			(keepout
				(tracks not_allowed)
				(vias allowed)
				(pads allowed)
				(copperpour not_allowed)
				(footprints allowed)
			)
			(placement
				(enabled no)
				(sheetname "")
			)
			(fill
				(thermal_gap 0.5)
				(thermal_bridge_width 0.5)
				(island_removal_mode 0)
			)
			(polygon
				(pts
					(xy 144.2974 -40.259) (xy 144.7546 -40.259) (xy 144.7546 -41.529) (xy 144.2974 -41.529)
				)
			)
		)
		(zone
			(layer "F.Cu")
			(hatch none 0.5)
			(connect_pads
				(clearance 0)
			)
			(min_thickness 0.25)
			(keepout
				(tracks allowed)
				(vias not_allowed)
				(pads allowed)
				(copperpour not_allowed)
				(footprints allowed)
			)
			(placement
				(enabled no)
				(sheetname "")
			)
			(fill
				(thermal_gap 0.5)
				(thermal_bridge_width 0.5)
				(island_removal_mode 0)
			)
			(polygon
				(pts
					(xy 144.2974 -40.259) (xy 144.7546 -40.259) (xy 144.7546 -41.529) (xy 144.2974 -41.529)
				)
			)
		)
	)
	(footprint ""
		(layer "F.Cu")
		(at 142.1638 -46.6852 -90)
		(property "Reference" "L5"
			(at 5.32257 3.7846 0)
			(unlocked yes)
			(layer "F.SilkS")
			(effects
				(font
					(size 0.7874 0.5842)
					(thickness 0.1524)
				)
				(justify left)
			)
		)
		(property "Value" "VALUE*"
			(at -3.56489 13.891006 270)
			(unlocked yes)
			(layer "F.Fab")
			(hide yes)
			(effects
				(font
					(size 1.6002 1.1938)
					(thickness 0.000001)
				)
				(justify left)
			)
		)
		(property "Device Type" "INDUCTOR_2-G190-10418-01,1.0UHA"
			(at -2.219706 11.425936 270)
			(unlocked yes)
			(layer "F.Fab")
			(hide yes)
			(effects
				(font
					(size 1.6002 1.1938)
					(thickness 0.000001)
				)
				(justify left)
			)
		)
		(property "User Part Number" "PARTNUM*"
			(at -5.249926 16.101314 270)
			(unlocked yes)
			(layer "Cmts.User")
			(hide yes)
			(effects
				(font
					(size 1.6002 1.1938)
					(thickness 0.000001)
				)
				(justify left)
			)
		)
		(property "Tolerance" "TOL*"
			(at -2.304542 9.300718 270)
			(unlocked yes)
			(layer "Cmts.User")
			(hide yes)
			(effects
				(font
					(size 1.6002 1.1938)
					(thickness 0.000001)
				)
				(justify left)
			)
		)
		(duplicate_pad_numbers_are_jumpers no)
		(fp_line
			(start -4.452366 3.704082)
			(end -4.452366 -3.704082)
			(stroke
				(width 0.1)
				(type default)
			)
			(layer "F.SilkS")
		)
		(fp_line
			(start 4.452112 3.704082)
			(end -4.452366 3.704082)
			(stroke
				(width 0.1)
				(type default)
			)
			(layer "F.SilkS")
		)
		(fp_line
			(start -4.452366 -3.704082)
			(end 4.452112 -3.704082)
			(stroke
				(width 0.1)
				(type default)
			)
			(layer "F.SilkS")
		)
		(fp_line
			(start 4.452112 -3.704082)
			(end 4.452112 3.704082)
			(stroke
				(width 0.1)
				(type default)
			)
			(layer "F.SilkS")
		)
		(fp_rect
			(start -4.706366 3.958082)
			(end 4.706112 -3.958082)
			(stroke
				(width 0)
				(type default)
			)
			(fill no)
			(layer "F.CrtYd")
		)
		(fp_line
			(start -3.79984 3.450082)
			(end 3.79984 3.450082)
			(stroke
				(width 0.1)
				(type default)
			)
			(layer "F.Fab")
		)
		(fp_line
			(start 3.79984 3.450082)
			(end 3.79984 -3.450082)
			(stroke
				(width 0.1)
				(type default)
			)
			(layer "F.Fab")
		)
		(fp_line
			(start -3.79984 -3.450082)
			(end -3.79984 3.450082)
			(stroke
				(width 0.1)
				(type default)
			)
			(layer "F.Fab")
		)
		(fp_line
			(start 3.79984 -3.450082)
			(end -3.79984 -3.450082)
			(stroke
				(width 0.1)
				(type default)
			)
			(layer "F.Fab")
		)
		(fp_text user "1"
			(at -3.44805 -4.0132 0)
			(unlocked yes)
			(layer "F.SilkS")
			(effects
				(font
					(size 0.635 0.4064)
					(thickness 0.1524)
				)
			)
		)
		(fp_text user "2"
			(at 3.79857 -4.5212 0)
			(unlocked yes)
			(layer "F.SilkS")
			(effects
				(font
					(size 0.7874 0.5842)
					(thickness 0.1524)
				)
			)
		)
		(fp_text user "1"
			(at -5.19049 0.16891 90)
			(unlocked yes)
			(layer "F.Fab")
			(effects
				(font
					(size 0.7874 0.5842)
					(thickness 0.1524)
				)
			)
		)
		(fp_text user "2"
			(at 5.190236 0.084074 90)
			(unlocked yes)
			(layer "F.Fab")
			(effects
				(font
					(size 0.7874 0.5842)
					(thickness 0.1524)
				)
			)
		)
		(pad "1" smd rect
			(at -2.725166 0 270)
			(size 2.9464 3.5052)
			(layers "F.Cu" "F.Mask" "F.Paste")
			(net "XP1R0V_SW")
		)
		(pad "2" smd rect
			(at 2.724912 0 270)
			(size 2.9464 3.5052)
			(layers "F.Cu" "F.Mask" "F.Paste")
			(net "XP1R0V_FPGA")
		)
	)
	(footprint ""
		(layer "F.Cu")
		(at 159.255206 -57.361836 -90)
		(property "Reference" "U9"
			(at -3.812794 -0.129794 0)
			(unlocked yes)
			(layer "F.SilkS")
			(effects
				(font
					(size 0.7874 0.5842)
					(thickness 0.1524)
				)
			)
		)
		(property "Value" ""
			(at 0 0 270)
			(layer "F.Fab")
			(effects
				(font
					(size 1.27 1.27)
				)
			)
		)
		(property "User Part Number" "PARTNUM*"
			(at 0.1016 3.45567 270)
			(unlocked yes)
			(layer "Cmts.User")
			(hide yes)
			(effects
				(font
					(size 0.7874 0.5842)
					(thickness 0.1524)
				)
			)
		)
		(property "Device Type" "CL1001485A-G122-00019-01"
			(at 0.1016 2.54127 270)
			(unlocked yes)
			(layer "F.Fab")
			(hide yes)
			(effects
				(font
					(size 0.7874 0.5842)
					(thickness 0.1524)
				)
			)
		)
		(duplicate_pad_numbers_are_jumpers no)
		(fp_line
			(start -1.0541 1.704086)
			(end 1.0541 1.704086)
			(stroke
				(width 0.1)
				(type default)
			)
			(layer "F.SilkS")
		)
		(fp_line
			(start 1.0541 1.704086)
			(end 1.0541 1.45796)
			(stroke
				(width 0.1)
				(type default)
			)
			(layer "F.SilkS")
		)
		(fp_line
			(start -2.286 1.45796)
			(end -1.0541 1.45796)
			(stroke
				(width 0.1)
				(type default)
			)
			(layer "F.SilkS")
		)
		(fp_line
			(start -1.0541 1.45796)
			(end -1.0541 1.704086)
			(stroke
				(width 0.1)
				(type default)
			)
			(layer "F.SilkS")
		)
		(fp_line
			(start 1.0541 1.45796)
			(end 2.286 1.45796)
			(stroke
				(width 0.1)
				(type default)
			)
			(layer "F.SilkS")
		)
		(fp_line
			(start 2.286 1.45796)
			(end 2.286 -1.45796)
			(stroke
				(width 0.1)
				(type default)
			)
			(layer "F.SilkS")
		)
		(fp_line
			(start -2.286 -1.45796)
			(end -2.286 1.45796)
			(stroke
				(width 0.1)
				(type default)
			)
			(layer "F.SilkS")
		)
		(fp_line
			(start -1.0541 -1.45796)
			(end -2.286 -1.45796)
			(stroke
				(width 0.1)
				(type default)
			)
			(layer "F.SilkS")
		)
		(fp_line
			(start 1.0541 -1.45796)
			(end 1.0541 -1.704086)
			(stroke
				(width 0.1)
				(type default)
			)
			(layer "F.SilkS")
		)
		(fp_line
			(start 2.286 -1.45796)
			(end 1.0541 -1.45796)
			(stroke
				(width 0.1)
				(type default)
			)
			(layer "F.SilkS")
		)
		(fp_line
			(start -1.0541 -1.704086)
			(end -1.0541 -1.45796)
			(stroke
				(width 0.1)
				(type default)
			)
			(layer "F.SilkS")
		)
		(fp_line
			(start 1.0541 -1.704086)
			(end -1.0541 -1.704086)
			(stroke
				(width 0.1)
				(type default)
			)
			(layer "F.SilkS")
		)
		(fp_poly
			(pts
				(arc
					(start -2.06756 -2.314194)
					(mid -2.06756 -1.552194)
					(end -2.06756 -2.314194)
				)
			)
			(stroke
				(width 0)
				(type default)
			)
			(fill yes)
			(layer "F.SilkS")
		)
		(fp_rect
			(start 2.54 1.9558)
			(end -2.54 -1.9558)
			(stroke
				(width 0)
				(type default)
			)
			(fill no)
			(layer "F.CrtYd")
		)
		(fp_line
			(start -0.8001 1.450086)
			(end 0.8001 1.450086)
			(stroke
				(width 0.1)
				(type default)
			)
			(layer "F.Fab")
		)
		(fp_line
			(start -0.8001 1.450086)
			(end -0.599948 1.249934)
			(stroke
				(width 0.1)
				(type default)
			)
			(layer "F.Fab")
		)
		(fp_line
			(start 0.8001 1.450086)
			(end 0.599948 1.249934)
			(stroke
				(width 0.1)
				(type default)
			)
			(layer "F.Fab")
		)
		(fp_line
			(start 0.8001 1.450086)
			(end 0.8001 1.199896)
			(stroke
				(width 0.1)
				(type default)
			)
			(layer "F.Fab")
		)
		(fp_line
			(start -0.599948 1.249934)
			(end -0.599948 -1.249934)
			(stroke
				(width 0.1)
				(type default)
			)
			(layer "F.Fab")
		)
		(fp_line
			(start 0.599948 1.249934)
			(end -0.599948 1.249934)
			(stroke
				(width 0.1)
				(type default)
			)
			(layer "F.Fab")
		)
		(fp_line
			(start -1.500124 1.199896)
			(end -1.500124 0.700024)
			(stroke
				(width 0.1)
				(type default)
			)
			(layer "F.Fab")
		)
		(fp_line
			(start -0.8001 1.199896)
			(end -0.8001 1.450086)
			(stroke
				(width 0.1)
				(type default)
			)
			(layer "F.Fab")
		)
		(fp_line
			(start -0.700024 1.199896)
			(end -1.500124 1.199896)
			(stroke
				(width 0.1)
				(type default)
			)
			(layer "F.Fab")
		)
		(fp_line
			(start 0.700024 1.199896)
			(end 0.700024 0.700024)
			(stroke
				(width 0.1)
				(type default)
			)
			(layer "F.Fab")
		)
		(fp_line
			(start 1.500124 1.199896)
			(end 0.700024 1.199896)
			(stroke
				(width 0.1)
				(type default)
			)
			(layer "F.Fab")
		)
		(fp_line
			(start -1.500124 0.700024)
			(end -0.700024 0.700024)
			(stroke
				(width 0.1)
				(type default)
			)
			(layer "F.Fab")
		)
		(fp_line
			(start -0.700024 0.700024)
			(end -0.700024 1.199896)
			(stroke
				(width 0.1)
				(type default)
			)
			(layer "F.Fab")
		)
		(fp_line
			(start 0.700024 0.700024)
			(end 1.500124 0.700024)
			(stroke
				(width 0.1)
				(type default)
			)
			(layer "F.Fab")
		)
		(fp_line
			(start 1.500124 0.700024)
			(end 1.500124 1.199896)
			(stroke
				(width 0.1)
				(type default)
			)
			(layer "F.Fab")
		)
		(fp_line
			(start -1.500124 0.249936)
			(end -1.500124 -0.249936)
			(stroke
				(width 0.1)
				(type default)
			)
			(layer "F.Fab")
		)
		(fp_line
			(start -0.8001 0.249936)
			(end -0.8001 0.700024)
			(stroke
				(width 0.1)
				(type default)
			)
			(layer "F.Fab")
		)
		(fp_line
			(start -0.700024 0.249936)
			(end -1.500124 0.249936)
			(stroke
				(width 0.1)
				(type default)
			)
			(layer "F.Fab")
		)
		(fp_line
			(start 0.700024 0.249936)
			(end 0.8001 0.249936)
			(stroke
				(width 0.1)
				(type default)
			)
			(layer "F.Fab")
		)
		(fp_line
			(start 0.700024 0.249936)
			(end 0.700024 -0.249936)
			(stroke
				(width 0.1)
				(type default)
			)
			(layer "F.Fab")
		)
		(fp_line
			(start 0.8001 0.249936)
			(end 0.8001 0.700024)
			(stroke
				(width 0.1)
				(type default)
			)
			(layer "F.Fab")
		)
		(fp_line
			(start 1.500124 0.249936)
			(end 0.700024 0.249936)
			(stroke
				(width 0.1)
				(type default)
			)
			(layer "F.Fab")
		)
		(fp_line
			(start -1.500124 -0.249936)
			(end -0.700024 -0.249936)
			(stroke
				(width 0.1)
				(type default)
			)
			(layer "F.Fab")
		)
		(fp_line
			(start -0.700024 -0.249936)
			(end -0.700024 0.249936)
			(stroke
				(width 0.1)
				(type default)
			)
			(layer "F.Fab")
		)
		(fp_line
			(start 0.700024 -0.249936)
			(end 0.700024 0.249936)
			(stroke
				(width 0.1)
				(type default)
			)
			(layer "F.Fab")
		)
		(fp_line
			(start 0.700024 -0.249936)
			(end 1.500124 -0.249936)
			(stroke
				(width 0.1)
				(type default)
			)
			(layer "F.Fab")
		)
		(fp_line
			(start 0.8001 -0.249936)
			(end 0.700024 -0.249936)
			(stroke
				(width 0.1)
				(type default)
			)
			(layer "F.Fab")
		)
		(fp_line
			(start 1.500124 -0.249936)
			(end 1.500124 0.249936)
			(stroke
				(width 0.1)
				(type default)
			)
			(layer "F.Fab")
		)
		(fp_line
			(start -1.500124 -0.700024)
			(end -1.500124 -1.199896)
			(stroke
				(width 0.1)
				(type default)
			)
			(layer "F.Fab")
		)
		(fp_line
			(start -0.8001 -0.700024)
			(end -0.8001 -0.249936)
			(stroke
				(width 0.1)
				(type default)
			)
			(layer "F.Fab")
		)
		(fp_line
			(start -0.700024 -0.700024)
			(end -1.500124 -0.700024)
			(stroke
				(width 0.1)
				(type default)
			)
			(layer "F.Fab")
		)
		(fp_line
			(start 0.700024 -0.700024)
			(end 0.700024 -1.199896)
			(stroke
				(width 0.1)
				(type default)
			)
			(layer "F.Fab")
		)
		(fp_line
			(start 0.8001 -0.700024)
			(end 0.8001 -0.249936)
			(stroke
				(width 0.1)
				(type default)
			)
			(layer "F.Fab")
		)
		(fp_line
			(start 1.500124 -0.700024)
			(end 0.700024 -0.700024)
			(stroke
				(width 0.1)
				(type default)
			)
			(layer "F.Fab")
		)
		(fp_line
			(start -1.500124 -1.199896)
			(end -0.700024 -1.199896)
			(stroke
				(width 0.1)
				(type default)
			)
			(layer "F.Fab")
		)
		(fp_line
			(start -0.8001 -1.199896)
			(end -0.8001 -1.450086)
			(stroke
				(width 0.1)
				(type default)
			)
			(layer "F.Fab")
		)
		(fp_line
			(start -0.700024 -1.199896)
			(end -0.700024 -0.700024)
			(stroke
				(width 0.1)
				(type default)
			)
			(layer "F.Fab")
		)
		(fp_line
			(start 0.700024 -1.199896)
			(end 1.500124 -1.199896)
			(stroke
				(width 0.1)
				(type default)
			)
			(layer "F.Fab")
		)
		(fp_line
			(start 1.500124 -1.199896)
			(end 1.500124 -0.700024)
			(stroke
				(width 0.1)
				(type default)
			)
			(layer "F.Fab")
		)
		(fp_line
			(start -0.599948 -1.249934)
			(end 0.599948 -1.249934)
			(stroke
				(width 0.1)
				(type default)
			)
			(layer "F.Fab")
		)
		(fp_line
			(start -0.599948 -1.249934)
			(end -0.8001 -1.450086)
			(stroke
				(width 0.1)
				(type default)
			)
			(layer "F.Fab")
		)
		(fp_line
			(start 0.599948 -1.249934)
			(end 0.599948 1.249934)
			(stroke
				(width 0.1)
				(type default)
			)
			(layer "F.Fab")
		)
		(fp_line
			(start 0.599948 -1.249934)
			(end 0.8001 -1.450086)
			(stroke
				(width 0.1)
				(type default)
			)
			(layer "F.Fab")
		)
		(fp_line
			(start -0.8001 -1.450086)
			(end 0.8001 -1.450086)
			(stroke
				(width 0.1)
				(type default)
			)
			(layer "F.Fab")
		)
		(fp_line
			(start 0.8001 -1.450086)
			(end 0.8001 -1.199896)
			(stroke
				(width 0.1)
				(type default)
			)
			(layer "F.Fab")
		)
		(fp_poly
			(pts
				(arc
					(start -0.350012 -1.100074)
					(mid -0.350012 -0.799846)
					(end -0.350012 -1.100074)
				)
			)
			(stroke
				(width 0)
				(type default)
			)
			(fill yes)
			(layer "F.Fab")
		)
		(fp_text user "3"
			(at -2.25679 2.029206 0)
			(unlocked yes)
			(layer "F.SilkS")
			(effects
				(font
					(size 0.7874 0.5842)
					(thickness 0.1524)
				)
			)
		)
		(fp_text user "4"
			(at 3.07721 1.394206 0)
			(unlocked yes)
			(layer "F.SilkS")
			(effects
				(font
					(size 0.7874 0.5842)
					(thickness 0.1524)
				)
			)
		)
		(fp_text user "6"
			(at 3.045206 -1.145794 0)
			(unlocked yes)
			(layer "F.SilkS")
			(effects
				(font
					(size 0.7874 0.5842)
					(thickness 0.1524)
				)
			)
		)
		(fp_text user "3"
			(at -2.52349 1.140206 0)
			(unlocked yes)
			(layer "F.Fab")
			(effects
				(font
					(size 0.7874 0.5842)
					(thickness 0.1524)
				)
			)
		)
		(fp_text user "4"
			(at 2.43967 0.9906 0)
			(unlocked yes)
			(layer "F.Fab")
			(effects
				(font
					(size 0.7874 0.5842)
					(thickness 0.1524)
				)
			)
		)
		(fp_text user "6"
			(at 2.38887 -0.9398 0)
			(unlocked yes)
			(layer "F.Fab")
			(effects
				(font
					(size 0.7874 0.5842)
					(thickness 0.1524)
				)
			)
		)
		(pad "1" smd rect
			(at -1.4351 -0.94996)
			(size 0.508 1.1938)
			(layers "F.Cu" "F.Mask" "F.Paste")
			(net "Net_758")
		)
		(pad "2" smd rect
			(at -1.4351 0)
			(size 0.508 1.1938)
			(layers "F.Cu" "F.Mask" "F.Paste")
			(net "SG")
		)
		(pad "3" smd rect
			(at -1.4351 0.94996)
			(size 0.508 1.1938)
			(layers "F.Cu" "F.Mask" "F.Paste")
			(net "Net_757")
		)
		(pad "4" smd rect
			(at 1.4351 0.94996)
			(size 0.508 1.1938)
			(layers "F.Cu" "F.Mask" "F.Paste")
			(net "CONN_MICRO_USB_DM")
		)
		(pad "5" smd rect
			(at 1.4351 0)
			(size 0.508 1.1938)
			(layers "F.Cu" "F.Mask" "F.Paste")
			(net "XP5R0V_USB_CONN")
		)
		(pad "6" smd rect
			(at 1.4351 -0.94996)
			(size 0.508 1.1938)
			(layers "F.Cu" "F.Mask" "F.Paste")
			(net "CONN_MICRO_USB_DP")
		)
	)
	(footprint ""
		(layer "F.Cu")
		(at 68.216018 -28.484322)
		(property "Reference" "ME8"
			(at 3.157982 -3.607308 0)
			(unlocked yes)
			(layer "F.SilkS")
			(effects
				(font
					(size 0.7874 0.5842)
					(thickness 0.1524)
				)
			)
		)
		(property "Value" ""
			(at 0 0 0)
			(layer "F.Fab")
			(effects
				(font
					(size 1.27 1.27)
				)
			)
		)
		(duplicate_pad_numbers_are_jumpers no)
		(fp_poly
			(pts
				(arc
					(start 3.556 0)
					(mid -3.556 0)
					(end 3.556 0)
				)
			)
			(stroke
				(width 0)
				(type default)
			)
			(fill no)
			(layer "B.CrtYd")
		)
		(fp_poly
			(pts
				(arc
					(start 3.556 0)
					(mid -3.556 0)
					(end 3.556 0)
				)
			)
			(stroke
				(width 0)
				(type default)
			)
			(fill no)
			(layer "F.CrtYd")
		)
		(fp_circle
			(center 0 0)
			(end 3.048 0)
			(stroke
				(width 0.1)
				(type default)
			)
			(fill no)
			(layer "B.Fab")
		)
		(fp_circle
			(center 0 0)
			(end 3.048 0)
			(stroke
				(width 0.1)
				(type default)
			)
			(fill no)
			(layer "F.Fab")
		)
		(pad "" np_thru_hole circle
			(at 0 0)
			(size 2.286 2.286)
			(drill 2.54)
			(layers "*.Cu" "*.Mask")
			(padstack
				(mode front_inner_back)
				(layer "Inner"
					(shape circle)
					(size 2.286 2.286)
					(clearance 0.4445)
				)
				(layer "B.Cu"
					(shape circle)
					(size 2.286 2.286)
				)
			)
		)
		(zone
			(layers "F.Cu" "B.Cu" "In1.Cu" "In2.Cu" "In3.Cu" "In4.Cu" "In5.Cu" "In6.Cu"
				"In7.Cu" "In8.Cu"
			)
			(hatch none 0.5)
			(connect_pads
				(clearance 0)
			)
			(min_thickness 0.25)
			(keepout
				(tracks not_allowed)
				(vias allowed)
				(pads allowed)
				(copperpour not_allowed)
				(footprints allowed)
			)
			(placement
				(enabled no)
				(sheetname "")
			)
			(fill
				(thermal_gap 0.5)
				(thermal_bridge_width 0.5)
				(island_removal_mode 0)
			)
			(polygon
				(pts
					(arc
						(start 69.790818 -28.484322)
						(mid 66.641218 -28.484322)
						(end 69.790818 -28.484322)
					)
				)
			)
		)
	)
	(footprint ""
		(layer "F.Cu")
		(at 156.04998 -104.350058 -90)
		(property "Reference" "DS12"
			(at 0.591058 -2.23139 90)
			(unlocked yes)
			(layer "F.SilkS")
			(effects
				(font
					(size 0.7874 0.5842)
					(thickness 0.1524)
				)
			)
		)
		(property "Value" ""
			(at 0 0 270)
			(layer "F.Fab")
			(effects
				(font
					(size 1.27 1.27)
				)
			)
		)
		(property "Device Type" "OPTICAL-G170-10143-01"
			(at 0.1778 1.483081 270)
			(unlocked yes)
			(layer "F.Fab")
			(hide yes)
			(effects
				(font
					(size 0.786892 0.583946)
					(thickness 0.000001)
				)
			)
		)
		(property "User Part Number" "PARTNUM*"
			(at 0.1778 2.422881 270)
			(unlocked yes)
			(layer "Cmts.User")
			(hide yes)
			(effects
				(font
					(size 0.786892 0.583946)
					(thickness 0.000001)
				)
			)
		)
		(duplicate_pad_numbers_are_jumpers no)
		(fp_line
			(start -0.9398 1.4732)
			(end -2.2098 1.4732)
			(stroke
				(width 0.1)
				(type default)
			)
			(layer "F.SilkS")
		)
		(fp_line
			(start -1.5748 0.8382)
			(end -1.5748 2.1082)
			(stroke
				(width 0.1)
				(type default)
			)
			(layer "F.SilkS")
		)
		(fp_line
			(start -1.397508 0.704088)
			(end -1.397508 -0.704088)
			(stroke
				(width 0.1)
				(type default)
			)
			(layer "F.SilkS")
		)
		(fp_line
			(start 1.397508 0.704088)
			(end -1.397508 0.704088)
			(stroke
				(width 0.1)
				(type default)
			)
			(layer "F.SilkS")
		)
		(fp_line
			(start -1.397508 -0.704088)
			(end 1.397508 -0.704088)
			(stroke
				(width 0.1)
				(type default)
			)
			(layer "F.SilkS")
		)
		(fp_line
			(start 1.397508 -0.704088)
			(end 1.397508 0.704088)
			(stroke
				(width 0.1)
				(type default)
			)
			(layer "F.SilkS")
		)
		(fp_poly
			(pts
				(xy 1.397508 0.704088) (xy 1.397508 -0.704088) (xy 1.905508 -0.704088) (xy 1.905508 0.704088)
			)
			(stroke
				(width 0)
				(type default)
			)
			(fill yes)
			(layer "F.SilkS")
		)
		(fp_poly
			(pts
				(xy -1.651508 0.958088) (xy 1.905508 0.958088) (xy 1.905508 -0.958088) (xy -1.651508 -0.958088)
			)
			(stroke
				(width 0)
				(type default)
			)
			(fill no)
			(layer "F.CrtYd")
		)
		(fp_line
			(start -0.9398 1.3462)
			(end -2.2098 1.3462)
			(stroke
				(width 0.1)
				(type default)
			)
			(layer "F.Fab")
		)
		(fp_line
			(start -1.5748 0.7112)
			(end -1.5748 1.9812)
			(stroke
				(width 0.1)
				(type default)
			)
			(layer "F.Fab")
		)
		(fp_line
			(start -0.850138 0.450088)
			(end 0.850138 0.450088)
			(stroke
				(width 0.1)
				(type default)
			)
			(layer "F.Fab")
		)
		(fp_line
			(start 0.850138 0.450088)
			(end 0.850138 -0.450088)
			(stroke
				(width 0.1)
				(type default)
			)
			(layer "F.Fab")
		)
		(fp_line
			(start -0.850138 -0.450088)
			(end -0.850138 0.450088)
			(stroke
				(width 0.1)
				(type default)
			)
			(layer "F.Fab")
		)
		(fp_line
			(start 0.850138 -0.450088)
			(end -0.850138 -0.450088)
			(stroke
				(width 0.1)
				(type default)
			)
			(layer "F.Fab")
		)
		(fp_poly
			(pts
				(xy 0.850138 -0.450088) (xy 0.850138 0.450088) (xy 0.342138 0.450088) (xy 0.342138 -0.450088)
			)
			(stroke
				(width 0)
				(type default)
			)
			(fill yes)
			(layer "F.Fab")
		)
		(fp_text user "C"
			(at 2.400808 -1.04902 0)
			(unlocked yes)
			(layer "F.SilkS")
			(effects
				(font
					(size 0.635 0.4064)
					(thickness 0.1524)
				)
			)
		)
		(fp_text user "A"
			(at -0.901192 -1.17602 0)
			(unlocked yes)
			(layer "F.SilkS")
			(effects
				(font
					(size 0.635 0.4064)
					(thickness 0.1524)
				)
			)
		)
		(fp_text user "A"
			(at -0.893572 0.85598 0)
			(unlocked yes)
			(layer "F.Fab")
			(effects
				(font
					(size 0.7874 0.5842)
					(thickness 0.1524)
				)
			)
		)
		(fp_text user "C"
			(at 1.900428 -1.30302 0)
			(unlocked yes)
			(layer "F.Fab")
			(effects
				(font
					(size 0.7874 0.5842)
					(thickness 0.1524)
				)
			)
		)
		(pad "A" smd rect
			(at -0.749808 0 270)
			(size 0.7874 0.7874)
			(layers "F.Cu" "F.Mask" "F.Paste")
			(net "UNNAMED_14_OPTICAL_I289_A")
		)
		(pad "C" smd rect
			(at 0.749808 0 270)
			(size 0.7874 0.7874)
			(layers "F.Cu" "F.Mask" "F.Paste")
			(net "SG")
		)
	)
	(footprint ""
		(layer "F.Cu")
		(at 8.2804 -39.318692 90)
		(property "Reference" "R387"
			(at 2.337308 -0.04445 90)
			(unlocked yes)
			(layer "F.SilkS")
			(effects
				(font
					(size 0.635 0.4064)
					(thickness 0.1524)
				)
			)
		)
		(property "Value" "VAL*"
			(at 0.02032 2.13233 90)
			(unlocked yes)
			(layer "F.Fab")
			(hide yes)
			(effects
				(font
					(size 0.7874 0.5842)
					(thickness 0.1524)
				)
			)
		)
		(property "Tolerance" "TOL*"
			(at 0.044704 3.05435 90)
			(unlocked yes)
			(layer "Cmts.User")
			(hide yes)
			(effects
				(font
					(size 0.7874 0.5842)
					(thickness 0.1524)
				)
			)
		)
		(property "User Part Number" "PARTNUM*"
			(at 0.02032 4.024884 90)
			(unlocked yes)
			(layer "Cmts.User")
			(hide yes)
			(effects
				(font
					(size 0.7874 0.5842)
					(thickness 0.1524)
				)
			)
		)
		(property "Device Type" "RESISTOR-G155-133R0-01,33OHM,1%"
			(at 0.008382 1.210564 90)
			(unlocked yes)
			(layer "F.Fab")
			(hide yes)
			(effects
				(font
					(size 0.7874 0.5842)
					(thickness 0.1524)
				)
			)
		)
		(duplicate_pad_numbers_are_jumpers no)
		(fp_line
			(start 1.143 -0.5588)
			(end -1.143 -0.5588)
			(stroke
				(width 0.1)
				(type default)
			)
			(layer "F.SilkS")
		)
		(fp_line
			(start -1.143 -0.5588)
			(end -1.143 0.5588)
			(stroke
				(width 0.1)
				(type default)
			)
			(layer "F.SilkS")
		)
		(fp_line
			(start 1.143 0.5588)
			(end 1.143 -0.5588)
			(stroke
				(width 0.1)
				(type default)
			)
			(layer "F.SilkS")
		)
		(fp_line
			(start -1.143 0.5588)
			(end 1.143 0.5588)
			(stroke
				(width 0.1)
				(type default)
			)
			(layer "F.SilkS")
		)
		(fp_rect
			(start -1.143 -0.5588)
			(end 1.143 0.5588)
			(stroke
				(width 0)
				(type default)
			)
			(fill no)
			(layer "F.CrtYd")
		)
		(fp_line
			(start 0.508 -0.3048)
			(end -0.508 -0.3048)
			(stroke
				(width 0.1)
				(type default)
			)
			(layer "F.Fab")
		)
		(fp_line
			(start -0.508 -0.3048)
			(end -0.508 0.3048)
			(stroke
				(width 0.1)
				(type default)
			)
			(layer "F.Fab")
		)
		(fp_line
			(start 0.508 0.3048)
			(end 0.508 -0.3048)
			(stroke
				(width 0.1)
				(type default)
			)
			(layer "F.Fab")
		)
		(fp_line
			(start -0.508 0.3048)
			(end 0.508 0.3048)
			(stroke
				(width 0.1)
				(type default)
			)
			(layer "F.Fab")
		)
		(pad "1" smd rect
			(at -0.5334 0 90)
			(size 0.7112 0.6096)
			(layers "F.Cu" "F.Mask" "F.Paste")
			(net "SMA1_LED_RED_N")
		)
		(pad "2" smd rect
			(at 0.5334 0 90)
			(size 0.7112 0.6096)
			(layers "F.Cu" "F.Mask" "F.Paste")
			(net "UNNAMED_14_LED4PV14_I265_3")
		)
		(zone
			(layer "F.Cu")
			(hatch none 0.5)
			(connect_pads
				(clearance 0)
			)
			(min_thickness 0.25)
			(keepout
				(tracks not_allowed)
				(vias allowed)
				(pads allowed)
				(copperpour not_allowed)
				(footprints allowed)
			)
			(placement
				(enabled no)
				(sheetname "")
			)
			(fill
				(thermal_gap 0.5)
				(thermal_bridge_width 0.5)
				(island_removal_mode 0)
			)
			(polygon
				(pts
					(xy 7.9756 -39.242492) (xy 8.5852 -39.242492) (xy 8.5852 -39.394892) (xy 7.9756 -39.394892)
				)
			)
		)
		(zone
			(layer "F.Cu")
			(hatch none 0.5)
			(connect_pads
				(clearance 0)
			)
			(min_thickness 0.25)
			(keepout
				(tracks allowed)
				(vias not_allowed)
				(pads allowed)
				(copperpour not_allowed)
				(footprints allowed)
			)
			(placement
				(enabled no)
				(sheetname "")
			)
			(fill
				(thermal_gap 0.5)
				(thermal_bridge_width 0.5)
				(island_removal_mode 0)
			)
			(polygon
				(pts
					(xy 7.9756 -39.242492) (xy 8.5852 -39.242492) (xy 8.5852 -39.394892) (xy 7.9756 -39.394892)
				)
			)
		)
	)
	(footprint ""
		(layer "F.Cu")
		(at 81.0006 -51.181 180)
		(property "Reference" "R85"
			(at 0.9906 -14.88567 0)
			(unlocked yes)
			(layer "F.SilkS")
			(effects
				(font
					(size 0.7874 0.5842)
					(thickness 0.1524)
				)
			)
		)
		(property "Value" "VAL*"
			(at 0.02032 2.13233 180)
			(unlocked yes)
			(layer "F.Fab")
			(hide yes)
			(effects
				(font
					(size 0.7874 0.5842)
					(thickness 0.1524)
				)
			)
		)
		(property "Tolerance" "TOL*"
			(at 0.044704 3.05435 180)
			(unlocked yes)
			(layer "Cmts.User")
			(hide yes)
			(effects
				(font
					(size 0.7874 0.5842)
					(thickness 0.1524)
				)
			)
		)
		(property "User Part Number" "PARTNUM*"
			(at 0.02032 4.024884 180)
			(unlocked yes)
			(layer "Cmts.User")
			(hide yes)
			(effects
				(font
					(size 0.7874 0.5842)
					(thickness 0.1524)
				)
			)
		)
		(property "Device Type" "RESISTOR-G155-100R0-J0,0OHM,-"
			(at 0.008382 1.210564 180)
			(unlocked yes)
			(layer "F.Fab")
			(hide yes)
			(effects
				(font
					(size 0.7874 0.5842)
					(thickness 0.1524)
				)
			)
		)
		(duplicate_pad_numbers_are_jumpers no)
		(fp_line
			(start 1.143 0.5588)
			(end 1.143 -0.5588)
			(stroke
				(width 0.1)
				(type default)
			)
			(layer "F.SilkS")
		)
		(fp_line
			(start 1.143 -0.5588)
			(end -1.143 -0.5588)
			(stroke
				(width 0.1)
				(type default)
			)
			(layer "F.SilkS")
		)
		(fp_line
			(start -1.143 0.5588)
			(end 1.143 0.5588)
			(stroke
				(width 0.1)
				(type default)
			)
			(layer "F.SilkS")
		)
		(fp_line
			(start -1.143 -0.5588)
			(end -1.143 0.5588)
			(stroke
				(width 0.1)
				(type default)
			)
			(layer "F.SilkS")
		)
		(fp_rect
			(start 1.143 -0.5588)
			(end -1.143 0.5588)
			(stroke
				(width 0)
				(type default)
			)
			(fill no)
			(layer "F.CrtYd")
		)
		(fp_line
			(start 0.508 0.3048)
			(end 0.508 -0.3048)
			(stroke
				(width 0.1)
				(type default)
			)
			(layer "F.Fab")
		)
		(fp_line
			(start 0.508 -0.3048)
			(end -0.508 -0.3048)
			(stroke
				(width 0.1)
				(type default)
			)
			(layer "F.Fab")
		)
		(fp_line
			(start -0.508 0.3048)
			(end 0.508 0.3048)
			(stroke
				(width 0.1)
				(type default)
			)
			(layer "F.Fab")
		)
		(fp_line
			(start -0.508 -0.3048)
			(end -0.508 0.3048)
			(stroke
				(width 0.1)
				(type default)
			)
			(layer "F.Fab")
		)
		(pad "1" smd rect
			(at -0.5334 0 180)
			(size 0.7112 0.6096)
			(layers "F.Cu" "F.Mask" "F.Paste")
			(net "FPGA_OUT_MAC_PPS_IN0P")
		)
		(pad "2" smd rect
			(at 0.5334 0 180)
			(size 0.7112 0.6096)
			(layers "F.Cu" "F.Mask" "F.Paste")
			(net "R_MAC_PPS_IN0P")
		)
		(zone
			(layer "F.Cu")
			(hatch none 0.5)
			(connect_pads
				(clearance 0)
			)
			(min_thickness 0.25)
			(keepout
				(tracks allowed)
				(vias not_allowed)
				(pads allowed)
				(copperpour not_allowed)
				(footprints allowed)
			)
			(placement
				(enabled no)
				(sheetname "")
			)
			(fill
				(thermal_gap 0.5)
				(thermal_bridge_width 0.5)
				(island_removal_mode 0)
			)
			(polygon
				(pts
					(xy 80.9244 -50.8762) (xy 81.0768 -50.8762) (xy 81.0768 -51.4858) (xy 80.9244 -51.4858)
				)
			)
		)
	)
	(footprint ""
		(layer "F.Cu")
		(at 111.125 -103.251 180)
		(property "Reference" "R364"
			(at -3.175 3.26263 0)
			(unlocked yes)
			(layer "F.SilkS")
			(effects
				(font
					(size 0.7874 0.5842)
					(thickness 0.1524)
				)
			)
		)
		(property "Value" "VAL*"
			(at 0.02032 2.13233 180)
			(unlocked yes)
			(layer "F.Fab")
			(hide yes)
			(effects
				(font
					(size 0.7874 0.5842)
					(thickness 0.1524)
				)
			)
		)
		(property "Tolerance" "TOL*"
			(at 0.044704 3.05435 180)
			(unlocked yes)
			(layer "Cmts.User")
			(hide yes)
			(effects
				(font
					(size 0.7874 0.5842)
					(thickness 0.1524)
				)
			)
		)
		(property "User Part Number" "PARTNUM*"
			(at 0.02032 4.024884 180)
			(unlocked yes)
			(layer "Cmts.User")
			(hide yes)
			(effects
				(font
					(size 0.7874 0.5842)
					(thickness 0.1524)
				)
			)
		)
		(property "Device Type" "RESISTOR-G155-133R0-01,33OHM,1%"
			(at 0.008382 1.210564 180)
			(unlocked yes)
			(layer "F.Fab")
			(hide yes)
			(effects
				(font
					(size 0.7874 0.5842)
					(thickness 0.1524)
				)
			)
		)
		(duplicate_pad_numbers_are_jumpers no)
		(fp_line
			(start 1.143 0.5588)
			(end 1.143 -0.5588)
			(stroke
				(width 0.1)
				(type default)
			)
			(layer "F.SilkS")
		)
		(fp_line
			(start 1.143 -0.5588)
			(end -1.143 -0.5588)
			(stroke
				(width 0.1)
				(type default)
			)
			(layer "F.SilkS")
		)
		(fp_line
			(start -1.143 0.5588)
			(end 1.143 0.5588)
			(stroke
				(width 0.1)
				(type default)
			)
			(layer "F.SilkS")
		)
		(fp_line
			(start -1.143 -0.5588)
			(end -1.143 0.5588)
			(stroke
				(width 0.1)
				(type default)
			)
			(layer "F.SilkS")
		)
		(fp_poly
			(pts
				(xy -1.143 0.5588) (xy 1.143 0.5588) (xy 1.143 -0.5588) (xy -1.143 -0.5588)
			)
			(stroke
				(width 0)
				(type default)
			)
			(fill no)
			(layer "F.CrtYd")
		)
		(fp_line
			(start 0.508 0.3048)
			(end 0.508 -0.3048)
			(stroke
				(width 0.1)
				(type default)
			)
			(layer "F.Fab")
		)
		(fp_line
			(start 0.508 -0.3048)
			(end -0.508 -0.3048)
			(stroke
				(width 0.1)
				(type default)
			)
			(layer "F.Fab")
		)
		(fp_line
			(start -0.508 0.3048)
			(end 0.508 0.3048)
			(stroke
				(width 0.1)
				(type default)
			)
			(layer "F.Fab")
		)
		(fp_line
			(start -0.508 -0.3048)
			(end -0.508 0.3048)
			(stroke
				(width 0.1)
				(type default)
			)
			(layer "F.Fab")
		)
		(pad "1" smd rect
			(at -0.5334 0 180)
			(size 0.7112 0.6096)
			(layers "F.Cu" "F.Mask" "F.Paste")
			(net "RGB_LED_I2C_SDA")
		)
		(pad "2" smd rect
			(at 0.5334 0 180)
			(size 0.7112 0.6096)
			(layers "F.Cu" "F.Mask" "F.Paste")
			(net "R_RGB_LED_I2C_SDA")
		)
		(zone
			(layer "F.Cu")
			(hatch none 0.5)
			(connect_pads
				(clearance 0)
			)
			(min_thickness 0.25)
			(keepout
				(tracks allowed)
				(vias not_allowed)
				(pads allowed)
				(copperpour not_allowed)
				(footprints allowed)
			)
			(placement
				(enabled no)
				(sheetname "")
			)
			(fill
				(thermal_gap 0.5)
				(thermal_bridge_width 0.5)
				(island_removal_mode 0)
			)
			(polygon
				(pts
					(xy 111.2012 -103.5558) (xy 111.0488 -103.5558) (xy 111.0488 -102.9462) (xy 111.2012 -102.9462)
				)
			)
		)
		(zone
			(layer "F.Cu")
			(hatch none 0.5)
			(connect_pads
				(clearance 0)
			)
			(min_thickness 0.25)
			(keepout
				(tracks not_allowed)
				(vias allowed)
				(pads allowed)
				(copperpour not_allowed)
				(footprints allowed)
			)
			(placement
				(enabled no)
				(sheetname "")
			)
			(fill
				(thermal_gap 0.5)
				(thermal_bridge_width 0.5)
				(island_removal_mode 0)
			)
			(polygon
				(pts
					(xy 111.2012 -103.5558) (xy 111.0488 -103.5558) (xy 111.0488 -102.9462) (xy 111.2012 -102.9462)
				)
			)
		)
	)
	(footprint ""
		(layer "F.Cu")
		(at 33.7693 -15.5702 180)
		(property "Reference" "R183"
			(at -2.6543 -2.07137 0)
			(unlocked yes)
			(layer "F.SilkS")
			(effects
				(font
					(size 0.7874 0.5842)
					(thickness 0.1524)
				)
			)
		)
		(property "Value" "VAL*"
			(at 0.02032 2.13233 180)
			(unlocked yes)
			(layer "F.Fab")
			(hide yes)
			(effects
				(font
					(size 0.7874 0.5842)
					(thickness 0.1524)
				)
			)
		)
		(property "Tolerance" "TOL*"
			(at 0.044704 3.05435 180)
			(unlocked yes)
			(layer "Cmts.User")
			(hide yes)
			(effects
				(font
					(size 0.7874 0.5842)
					(thickness 0.1524)
				)
			)
		)
		(property "User Part Number" "PARTNUM*"
			(at 0.02032 4.024884 180)
			(unlocked yes)
			(layer "Cmts.User")
			(hide yes)
			(effects
				(font
					(size 0.7874 0.5842)
					(thickness 0.1524)
				)
			)
		)
		(property "Device Type" "RESISTOR-G155-133R0-01,33OHM,1%"
			(at 0.008382 1.210564 180)
			(unlocked yes)
			(layer "F.Fab")
			(hide yes)
			(effects
				(font
					(size 0.7874 0.5842)
					(thickness 0.1524)
				)
			)
		)
		(duplicate_pad_numbers_are_jumpers no)
		(fp_line
			(start 1.143 0.5588)
			(end 1.143 -0.5588)
			(stroke
				(width 0.1)
				(type default)
			)
			(layer "F.SilkS")
		)
		(fp_line
			(start 1.143 -0.5588)
			(end -1.143 -0.5588)
			(stroke
				(width 0.1)
				(type default)
			)
			(layer "F.SilkS")
		)
		(fp_line
			(start -1.143 0.5588)
			(end 1.143 0.5588)
			(stroke
				(width 0.1)
				(type default)
			)
			(layer "F.SilkS")
		)
		(fp_line
			(start -1.143 -0.5588)
			(end -1.143 0.5588)
			(stroke
				(width 0.1)
				(type default)
			)
			(layer "F.SilkS")
		)
		(fp_rect
			(start 1.143 -0.5588)
			(end -1.143 0.5588)
			(stroke
				(width 0)
				(type default)
			)
			(fill no)
			(layer "F.CrtYd")
		)
		(fp_line
			(start 0.508 0.3048)
			(end 0.508 -0.3048)
			(stroke
				(width 0.1)
				(type default)
			)
			(layer "F.Fab")
		)
		(fp_line
			(start 0.508 -0.3048)
			(end -0.508 -0.3048)
			(stroke
				(width 0.1)
				(type default)
			)
			(layer "F.Fab")
		)
		(fp_line
			(start -0.508 0.3048)
			(end 0.508 0.3048)
			(stroke
				(width 0.1)
				(type default)
			)
			(layer "F.Fab")
		)
		(fp_line
			(start -0.508 -0.3048)
			(end -0.508 0.3048)
			(stroke
				(width 0.1)
				(type default)
			)
			(layer "F.Fab")
		)
		(pad "1" smd rect
			(at -0.5334 0 180)
			(size 0.7112 0.6096)
			(layers "F.Cu" "F.Mask" "F.Paste")
			(net "EEPROM_I2C_SDA")
		)
		(pad "2" smd rect
			(at 0.5334 0 180)
			(size 0.7112 0.6096)
			(layers "F.Cu" "F.Mask" "F.Paste")
			(net "EEPROM_SDA")
		)
		(zone
			(layer "F.Cu")
			(hatch none 0.5)
			(connect_pads
				(clearance 0)
			)
			(min_thickness 0.25)
			(keepout
				(tracks allowed)
				(vias not_allowed)
				(pads allowed)
				(copperpour not_allowed)
				(footprints allowed)
			)
			(placement
				(enabled no)
				(sheetname "")
			)
			(fill
				(thermal_gap 0.5)
				(thermal_bridge_width 0.5)
				(island_removal_mode 0)
			)
			(polygon
				(pts
					(xy 33.6931 -15.2654) (xy 33.8455 -15.2654) (xy 33.8455 -15.875) (xy 33.6931 -15.875)
				)
			)
		)
	)
	(footprint ""
		(layer "F.Cu")
		(at 19.177 -38.735 180)
		(property "Reference" "J9"
			(at -3.556 1.61163 0)
			(unlocked yes)
			(layer "F.SilkS")
			(effects
				(font
					(size 0.7874 0.5842)
					(thickness 0.1524)
				)
			)
		)
		(property "Value" ""
			(at 0 0 180)
			(layer "F.Fab")
			(effects
				(font
					(size 1.27 1.27)
				)
			)
		)
		(property "User Part Number" "PARTNUM*"
			(at 0.069088 7.712456 180)
			(unlocked yes)
			(layer "Cmts.User")
			(hide yes)
			(effects
				(font
					(size 0.7874 0.5842)
					(thickness 0.000001)
				)
			)
		)
		(property "Device Type" "CONN_HDR_2X2_M_S_SMT-G200-1068A"
			(at 0.069088 6.518656 180)
			(unlocked yes)
			(layer "F.Fab")
			(hide yes)
			(effects
				(font
					(size 0.7874 0.5842)
					(thickness 0.000001)
				)
			)
		)
		(duplicate_pad_numbers_are_jumpers no)
		(fp_line
			(start 2.589022 4.637024)
			(end -2.589022 4.637024)
			(stroke
				(width 0.1)
				(type default)
			)
			(layer "F.SilkS")
		)
		(fp_line
			(start 2.589022 -4.637024)
			(end 2.589022 4.637024)
			(stroke
				(width 0.1)
				(type default)
			)
			(layer "F.SilkS")
		)
		(fp_line
			(start -2.589022 4.637024)
			(end -2.589022 -4.637024)
			(stroke
				(width 0.1)
				(type default)
			)
			(layer "F.SilkS")
		)
		(fp_line
			(start -2.589022 -4.637024)
			(end 2.589022 -4.637024)
			(stroke
				(width 0.1)
				(type default)
			)
			(layer "F.SilkS")
		)
		(fp_rect
			(start -2.843022 4.891024)
			(end 2.843022 -4.891024)
			(stroke
				(width 0)
				(type default)
			)
			(fill no)
			(layer "F.CrtYd")
		)
		(fp_line
			(start 2.335022 2.439924)
			(end 2.335022 -2.439924)
			(stroke
				(width 0.1)
				(type default)
			)
			(layer "F.Fab")
		)
		(fp_line
			(start 2.335022 -2.439924)
			(end -2.335022 -2.439924)
			(stroke
				(width 0.1)
				(type default)
			)
			(layer "F.Fab")
		)
		(fp_line
			(start -2.335022 2.439924)
			(end 2.335022 2.439924)
			(stroke
				(width 0.1)
				(type default)
			)
			(layer "F.Fab")
		)
		(fp_line
			(start -2.335022 -2.439924)
			(end -2.335022 2.439924)
			(stroke
				(width 0.1)
				(type default)
			)
			(layer "F.Fab")
		)
		(fp_text user "3"
			(at 1.8161 5.29463 0)
			(unlocked yes)
			(layer "F.SilkS")
			(effects
				(font
					(size 0.7874 0.5842)
					(thickness 0.1524)
				)
				(justify left)
			)
		)
		(fp_text user "4"
			(at 1.3081 -5.24637 0)
			(unlocked yes)
			(layer "F.SilkS")
			(effects
				(font
					(size 0.7874 0.5842)
					(thickness 0.1524)
				)
				(justify left)
			)
		)
		(fp_text user "1"
			(at -2.6289 4.27863 0)
			(unlocked yes)
			(layer "F.SilkS")
			(effects
				(font
					(size 0.7874 0.5842)
					(thickness 0.1524)
				)
				(justify left)
			)
		)
		(fp_text user "2"
			(at -2.8829 -3.34137 0)
			(unlocked yes)
			(layer "F.SilkS")
			(effects
				(font
					(size 0.7874 0.5842)
					(thickness 0.1524)
				)
				(justify left)
			)
		)
		(fp_text user "4"
			(at 1.770888 -3.285744 0)
			(unlocked yes)
			(layer "F.Fab")
			(effects
				(font
					(size 0.7874 0.5842)
					(thickness 0.1524)
				)
				(justify left)
			)
		)
		(fp_text user "3"
			(at 1.41478 3.674872 0)
			(unlocked yes)
			(layer "F.Fab")
			(effects
				(font
					(size 0.7874 0.5842)
					(thickness 0.1524)
				)
				(justify left)
			)
		)
		(fp_text user "2"
			(at -1.005332 -3.25247 0)
			(unlocked yes)
			(layer "F.Fab")
			(effects
				(font
					(size 0.7874 0.5842)
					(thickness 0.1524)
				)
				(justify left)
			)
		)
		(fp_text user "1"
			(at -1.22682 3.674872 0)
			(unlocked yes)
			(layer "F.Fab")
			(effects
				(font
					(size 0.7874 0.5842)
					(thickness 0.1524)
				)
				(justify left)
			)
		)
		(pad "1" smd rect
			(at -1.27 2.605024 180)
			(size 1.27 3.556)
			(layers "F.Cu" "F.Mask" "F.Paste")
			(net "UNNAMED_5_CONNHDR2X2MSSMT_I126_")
		)
		(pad "2" smd rect
			(at -1.27 -2.605024 180)
			(size 1.27 3.556)
			(layers "F.Cu" "F.Mask" "F.Paste")
			(net "EEPROM_SDA")
		)
		(pad "3" smd rect
			(at 1.27 2.605024 180)
			(size 1.27 3.556)
			(layers "F.Cu" "F.Mask" "F.Paste")
			(net "UNNAMED_5_CONNHDR2X2MSSMT_I12_1")
		)
		(pad "4" smd rect
			(at 1.27 -2.605024 180)
			(size 1.27 3.556)
			(layers "F.Cu" "F.Mask" "F.Paste")
			(net "EEPROM_SCL")
		)
	)
	(footprint ""
		(layer "F.Cu")
		(at 15.875 -28.067 -90)
		(property "Reference" "C83"
			(at 0.127 -1.81737 90)
			(unlocked yes)
			(layer "F.SilkS")
			(effects
				(font
					(size 0.7874 0.5842)
					(thickness 0.1524)
				)
			)
		)
		(property "Value" "VAL*"
			(at 0.0762 2.067306 270)
			(unlocked yes)
			(layer "F.Fab")
			(hide yes)
			(effects
				(font
					(size 0.7874 0.5842)
					(thickness 0.1524)
				)
			)
		)
		(property "Device Type" "CAPACITOR-G105-0B104-CK,0.1UF,A"
			(at 0.0508 1.127506 270)
			(unlocked yes)
			(layer "F.Fab")
			(hide yes)
			(effects
				(font
					(size 0.7874 0.5842)
					(thickness 0.1524)
				)
			)
		)
		(property "User Part Number" "PARTNUM*"
			(at 0.1016 4.023106 270)
			(unlocked yes)
			(layer "Cmts.User")
			(hide yes)
			(effects
				(font
					(size 0.7874 0.5842)
					(thickness 0.1524)
				)
			)
		)
		(property "Tolerance" "TOL*"
			(at 0.0762 3.032506 270)
			(unlocked yes)
			(layer "Cmts.User")
			(hide yes)
			(effects
				(font
					(size 0.7874 0.5842)
					(thickness 0.1524)
				)
			)
		)
		(duplicate_pad_numbers_are_jumpers no)
		(fp_line
			(start -1.143 0.5588)
			(end 1.143 0.5588)
			(stroke
				(width 0.1)
				(type default)
			)
			(layer "F.SilkS")
		)
		(fp_line
			(start 1.143 0.5588)
			(end 1.143 -0.5588)
			(stroke
				(width 0.1)
				(type default)
			)
			(layer "F.SilkS")
		)
		(fp_line
			(start -1.143 -0.5588)
			(end -1.143 0.5588)
			(stroke
				(width 0.1)
				(type default)
			)
			(layer "F.SilkS")
		)
		(fp_line
			(start 1.143 -0.5588)
			(end -1.143 -0.5588)
			(stroke
				(width 0.1)
				(type default)
			)
			(layer "F.SilkS")
		)
		(fp_rect
			(start -1.143 -0.5588)
			(end 1.143 0.5588)
			(stroke
				(width 0)
				(type default)
			)
			(fill no)
			(layer "F.CrtYd")
		)
		(fp_line
			(start -0.508 0.3048)
			(end 0.508 0.3048)
			(stroke
				(width 0.1)
				(type default)
			)
			(layer "F.Fab")
		)
		(fp_line
			(start 0.508 0.3048)
			(end 0.508 -0.3048)
			(stroke
				(width 0.1)
				(type default)
			)
			(layer "F.Fab")
		)
		(fp_line
			(start -0.508 -0.3048)
			(end -0.508 0.3048)
			(stroke
				(width 0.1)
				(type default)
			)
			(layer "F.Fab")
		)
		(fp_line
			(start 0.508 -0.3048)
			(end -0.508 -0.3048)
			(stroke
				(width 0.1)
				(type default)
			)
			(layer "F.Fab")
		)
		(pad "1" smd rect
			(at -0.5334 0 270)
			(size 0.7112 0.6096)
			(layers "F.Cu" "F.Mask" "F.Paste")
			(net "XP3R3V_FPGA")
		)
		(pad "2" smd rect
			(at 0.5334 0 270)
			(size 0.7112 0.6096)
			(layers "F.Cu" "F.Mask" "F.Paste")
			(net "SG")
		)
		(zone
			(layer "F.Cu")
			(hatch none 0.5)
			(connect_pads
				(clearance 0)
			)
			(min_thickness 0.25)
			(keepout
				(tracks allowed)
				(vias not_allowed)
				(pads allowed)
				(copperpour not_allowed)
				(footprints allowed)
			)
			(placement
				(enabled no)
				(sheetname "")
			)
			(fill
				(thermal_gap 0.5)
				(thermal_bridge_width 0.5)
				(island_removal_mode 0)
			)
			(polygon
				(pts
					(xy 16.1798 -28.1432) (xy 15.5702 -28.1432) (xy 15.5702 -27.9908) (xy 16.1798 -27.9908)
				)
			)
		)
	)
	(footprint ""
		(layer "F.Cu")
		(at 150.049992 -104.350058 -90)
		(property "Reference" "DS19"
			(at 0.845058 -1.424178 90)
			(unlocked yes)
			(layer "F.SilkS")
			(effects
				(font
					(size 0.7874 0.5842)
					(thickness 0.1524)
				)
			)
		)
		(property "Value" ""
			(at 0 0 270)
			(layer "F.Fab")
			(effects
				(font
					(size 1.27 1.27)
				)
			)
		)
		(property "Device Type" "OPTICAL-G170-10143-01"
			(at 0.1778 1.483081 270)
			(unlocked yes)
			(layer "F.Fab")
			(hide yes)
			(effects
				(font
					(size 0.786892 0.583946)
					(thickness 0.000001)
				)
			)
		)
		(property "User Part Number" "PARTNUM*"
			(at 0.1778 2.422881 270)
			(unlocked yes)
			(layer "Cmts.User")
			(hide yes)
			(effects
				(font
					(size 0.786892 0.583946)
					(thickness 0.000001)
				)
			)
		)
		(duplicate_pad_numbers_are_jumpers no)
		(fp_line
			(start -1.397508 0.704088)
			(end -1.397508 -0.704088)
			(stroke
				(width 0.1)
				(type default)
			)
			(layer "F.SilkS")
		)
		(fp_line
			(start 1.397508 0.704088)
			(end -1.397508 0.704088)
			(stroke
				(width 0.1)
				(type default)
			)
			(layer "F.SilkS")
		)
		(fp_line
			(start -2.3368 0.0762)
			(end -3.6068 0.0762)
			(stroke
				(width 0.1)
				(type default)
			)
			(layer "F.SilkS")
		)
		(fp_line
			(start -2.9718 -0.5588)
			(end -2.9718 0.7112)
			(stroke
				(width 0.1)
				(type default)
			)
			(layer "F.SilkS")
		)
		(fp_line
			(start -1.397508 -0.704088)
			(end 1.397508 -0.704088)
			(stroke
				(width 0.1)
				(type default)
			)
			(layer "F.SilkS")
		)
		(fp_line
			(start 1.397508 -0.704088)
			(end 1.397508 0.704088)
			(stroke
				(width 0.1)
				(type default)
			)
			(layer "F.SilkS")
		)
		(fp_poly
			(pts
				(xy 1.397508 0.704088) (xy 1.397508 -0.704088) (xy 1.905508 -0.704088) (xy 1.905508 0.704088)
			)
			(stroke
				(width 0)
				(type default)
			)
			(fill yes)
			(layer "F.SilkS")
		)
		(fp_poly
			(pts
				(xy -1.651508 0.958088) (xy 1.905508 0.958088) (xy 1.905508 -0.958088) (xy -1.651508 -0.958088)
			)
			(stroke
				(width 0)
				(type default)
			)
			(fill no)
			(layer "F.CrtYd")
		)
		(fp_line
			(start -0.850138 0.450088)
			(end 0.850138 0.450088)
			(stroke
				(width 0.1)
				(type default)
			)
			(layer "F.Fab")
		)
		(fp_line
			(start 0.850138 0.450088)
			(end 0.850138 -0.450088)
			(stroke
				(width 0.1)
				(type default)
			)
			(layer "F.Fab")
		)
		(fp_line
			(start -2.4638 0.0762)
			(end -3.7338 0.0762)
			(stroke
				(width 0.1)
				(type default)
			)
			(layer "F.Fab")
		)
		(fp_line
			(start -0.850138 -0.450088)
			(end -0.850138 0.450088)
			(stroke
				(width 0.1)
				(type default)
			)
			(layer "F.Fab")
		)
		(fp_line
			(start 0.850138 -0.450088)
			(end -0.850138 -0.450088)
			(stroke
				(width 0.1)
				(type default)
			)
			(layer "F.Fab")
		)
		(fp_line
			(start -3.0988 -0.5588)
			(end -3.0988 0.7112)
			(stroke
				(width 0.1)
				(type default)
			)
			(layer "F.Fab")
		)
		(fp_poly
			(pts
				(xy 0.850138 -0.450088) (xy 0.850138 0.450088) (xy 0.342138 0.450088) (xy 0.342138 -0.450088)
			)
			(stroke
				(width 0)
				(type default)
			)
			(fill yes)
			(layer "F.Fab")
		)
		(fp_text user "A"
			(at -2.044192 0.697992 0)
			(unlocked yes)
			(layer "F.SilkS")
			(effects
				(font
					(size 0.635 0.4064)
					(thickness 0.1524)
				)
			)
		)
		(fp_text user "C"
			(at 2.527808 0.189992 0)
			(unlocked yes)
			(layer "F.SilkS")
			(effects
				(font
					(size 0.635 0.4064)
					(thickness 0.1524)
				)
			)
		)
		(fp_text user "A"
			(at -1.9558 0.142748 90)
			(unlocked yes)
			(layer "F.Fab")
			(effects
				(font
					(size 0.7874 0.5842)
					(thickness 0.1524)
				)
			)
		)
		(fp_text user "C"
			(at 1.900428 -0.826008 0)
			(unlocked yes)
			(layer "F.Fab")
			(effects
				(font
					(size 0.7874 0.5842)
					(thickness 0.1524)
				)
			)
		)
		(pad "A" smd rect
			(at -0.749808 0 270)
			(size 0.7874 0.7874)
			(layers "F.Cu" "F.Mask" "F.Paste")
			(net "UNNAMED_14_OPTICAL_I191_A")
		)
		(pad "C" smd rect
			(at 0.749808 0 270)
			(size 0.7874 0.7874)
			(layers "F.Cu" "F.Mask" "F.Paste")
			(net "SG")
		)
	)
	(footprint ""
		(layer "F.Cu")
		(at 56.007 -127.635)
		(property "Reference" "SP50"
			(at 0 0 0)
			(layer "F.SilkS")
			(hide yes)
			(effects
				(font
					(size 1.27 1.27)
				)
			)
		)
		(property "Value" ""
			(at 0 0 0)
			(layer "F.Fab")
			(effects
				(font
					(size 1.27 1.27)
				)
			)
		)
		(duplicate_pad_numbers_are_jumpers no)
	)
	(footprint ""
		(layer "F.Cu")
		(at 96.5454 -64.2874 -90)
		(property "Reference" "R285"
			(at 2.6924 -0.77597 90)
			(unlocked yes)
			(layer "F.SilkS")
			(effects
				(font
					(size 0.7874 0.5842)
					(thickness 0.1524)
				)
			)
		)
		(property "Value" "VAL*"
			(at 0.02032 2.13233 270)
			(unlocked yes)
			(layer "F.Fab")
			(hide yes)
			(effects
				(font
					(size 0.7874 0.5842)
					(thickness 0.1524)
				)
			)
		)
		(property "Tolerance" "TOL*"
			(at 0.044704 3.05435 270)
			(unlocked yes)
			(layer "Cmts.User")
			(hide yes)
			(effects
				(font
					(size 0.7874 0.5842)
					(thickness 0.1524)
				)
			)
		)
		(property "User Part Number" "PARTNUM*"
			(at 0.02032 4.024884 270)
			(unlocked yes)
			(layer "Cmts.User")
			(hide yes)
			(effects
				(font
					(size 0.7874 0.5842)
					(thickness 0.1524)
				)
			)
		)
		(property "Device Type" "RESISTOR-G155-11002-01,10KOHM,A"
			(at 0.008382 1.210564 270)
			(unlocked yes)
			(layer "F.Fab")
			(hide yes)
			(effects
				(font
					(size 0.7874 0.5842)
					(thickness 0.1524)
				)
			)
		)
		(duplicate_pad_numbers_are_jumpers no)
		(fp_line
			(start -1.143 0.5588)
			(end 1.143 0.5588)
			(stroke
				(width 0.1)
				(type default)
			)
			(layer "F.SilkS")
		)
		(fp_line
			(start 1.143 0.5588)
			(end 1.143 -0.5588)
			(stroke
				(width 0.1)
				(type default)
			)
			(layer "F.SilkS")
		)
		(fp_line
			(start -1.143 -0.5588)
			(end -1.143 0.5588)
			(stroke
				(width 0.1)
				(type default)
			)
			(layer "F.SilkS")
		)
		(fp_line
			(start 1.143 -0.5588)
			(end -1.143 -0.5588)
			(stroke
				(width 0.1)
				(type default)
			)
			(layer "F.SilkS")
		)
		(fp_poly
			(pts
				(xy -1.143 0.5588) (xy 1.143 0.5588) (xy 1.143 -0.5588) (xy -1.143 -0.5588)
			)
			(stroke
				(width 0)
				(type default)
			)
			(fill no)
			(layer "F.CrtYd")
		)
		(fp_line
			(start -0.508 0.3048)
			(end 0.508 0.3048)
			(stroke
				(width 0.1)
				(type default)
			)
			(layer "F.Fab")
		)
		(fp_line
			(start 0.508 0.3048)
			(end 0.508 -0.3048)
			(stroke
				(width 0.1)
				(type default)
			)
			(layer "F.Fab")
		)
		(fp_line
			(start -0.508 -0.3048)
			(end -0.508 0.3048)
			(stroke
				(width 0.1)
				(type default)
			)
			(layer "F.Fab")
		)
		(fp_line
			(start 0.508 -0.3048)
			(end -0.508 -0.3048)
			(stroke
				(width 0.1)
				(type default)
			)
			(layer "F.Fab")
		)
		(pad "1" smd rect
			(at -0.5334 0 270)
			(size 0.7112 0.6096)
			(layers "F.Cu" "F.Mask" "F.Paste")
			(net "XP3R3V_FPGA")
		)
		(pad "2" smd rect
			(at 0.5334 0 270)
			(size 0.7112 0.6096)
			(layers "F.Cu" "F.Mask" "F.Paste")
			(net "FPGA_IO_3")
		)
		(zone
			(layer "F.Cu")
			(hatch none 0.5)
			(connect_pads
				(clearance 0)
			)
			(min_thickness 0.25)
			(keepout
				(tracks not_allowed)
				(vias allowed)
				(pads allowed)
				(copperpour not_allowed)
				(footprints allowed)
			)
			(placement
				(enabled no)
				(sheetname "")
			)
			(fill
				(thermal_gap 0.5)
				(thermal_bridge_width 0.5)
				(island_removal_mode 0)
			)
			(polygon
				(pts
					(xy 96.2406 -64.3636) (xy 96.2406 -64.2112) (xy 96.8502 -64.2112) (xy 96.8502 -64.3636)
				)
			)
		)
		(zone
			(layer "F.Cu")
			(hatch none 0.5)
			(connect_pads
				(clearance 0)
			)
			(min_thickness 0.25)
			(keepout
				(tracks allowed)
				(vias not_allowed)
				(pads allowed)
				(copperpour not_allowed)
				(footprints allowed)
			)
			(placement
				(enabled no)
				(sheetname "")
			)
			(fill
				(thermal_gap 0.5)
				(thermal_bridge_width 0.5)
				(island_removal_mode 0)
			)
			(polygon
				(pts
					(xy 96.2406 -64.3636) (xy 96.2406 -64.2112) (xy 96.8502 -64.2112) (xy 96.8502 -64.3636)
				)
			)
		)
	)
	(footprint ""
		(layer "F.Cu")
		(at 97.4598 -69.215)
		(property "Reference" "R189"
			(at -28.1178 -18.88363 0)
			(unlocked yes)
			(layer "F.SilkS")
			(effects
				(font
					(size 0.7874 0.5842)
					(thickness 0.1524)
				)
			)
		)
		(property "Value" "VAL*"
			(at 0.02032 2.13233 0)
			(unlocked yes)
			(layer "F.Fab")
			(hide yes)
			(effects
				(font
					(size 0.7874 0.5842)
					(thickness 0.1524)
				)
			)
		)
		(property "Tolerance" "TOL*"
			(at 0.044704 3.05435 0)
			(unlocked yes)
			(layer "Cmts.User")
			(hide yes)
			(effects
				(font
					(size 0.7874 0.5842)
					(thickness 0.1524)
				)
			)
		)
		(property "User Part Number" "PARTNUM*"
			(at 0.02032 4.024884 0)
			(unlocked yes)
			(layer "Cmts.User")
			(hide yes)
			(effects
				(font
					(size 0.7874 0.5842)
					(thickness 0.1524)
				)
			)
		)
		(property "Device Type" "RESISTOR-G155-03241-01,3.24KOHA"
			(at 0.008382 1.210564 0)
			(unlocked yes)
			(layer "F.Fab")
			(hide yes)
			(effects
				(font
					(size 0.7874 0.5842)
					(thickness 0.1524)
				)
			)
		)
		(duplicate_pad_numbers_are_jumpers no)
		(fp_line
			(start -1.143 -0.5588)
			(end -1.143 0.5588)
			(stroke
				(width 0.1)
				(type default)
			)
			(layer "F.SilkS")
		)
		(fp_line
			(start -1.143 0.5588)
			(end 1.143 0.5588)
			(stroke
				(width 0.1)
				(type default)
			)
			(layer "F.SilkS")
		)
		(fp_line
			(start 1.143 -0.5588)
			(end -1.143 -0.5588)
			(stroke
				(width 0.1)
				(type default)
			)
			(layer "F.SilkS")
		)
		(fp_line
			(start 1.143 0.5588)
			(end 1.143 -0.5588)
			(stroke
				(width 0.1)
				(type default)
			)
			(layer "F.SilkS")
		)
		(fp_rect
			(start -1.143 -0.5588)
			(end 1.143 0.5588)
			(stroke
				(width 0)
				(type default)
			)
			(fill no)
			(layer "F.CrtYd")
		)
		(fp_line
			(start -0.508 -0.3048)
			(end -0.508 0.3048)
			(stroke
				(width 0.1)
				(type default)
			)
			(layer "F.Fab")
		)
		(fp_line
			(start -0.508 0.3048)
			(end 0.508 0.3048)
			(stroke
				(width 0.1)
				(type default)
			)
			(layer "F.Fab")
		)
		(fp_line
			(start 0.508 -0.3048)
			(end -0.508 -0.3048)
			(stroke
				(width 0.1)
				(type default)
			)
			(layer "F.Fab")
		)
		(fp_line
			(start 0.508 0.3048)
			(end 0.508 -0.3048)
			(stroke
				(width 0.1)
				(type default)
			)
			(layer "F.Fab")
		)
		(pad "1" smd rect
			(at -0.5334 0)
			(size 0.7112 0.6096)
			(layers "F.Cu" "F.Mask" "F.Paste")
			(net "SG")
		)
		(pad "2" smd rect
			(at 0.5334 0)
			(size 0.7112 0.6096)
			(layers "F.Cu" "F.Mask" "F.Paste")
			(net "XP1R2V_FB")
		)
		(zone
			(layer "F.Cu")
			(hatch none 0.5)
			(connect_pads
				(clearance 0)
			)
			(min_thickness 0.25)
			(keepout
				(tracks allowed)
				(vias not_allowed)
				(pads allowed)
				(copperpour not_allowed)
				(footprints allowed)
			)
			(placement
				(enabled no)
				(sheetname "")
			)
			(fill
				(thermal_gap 0.5)
				(thermal_bridge_width 0.5)
				(island_removal_mode 0)
			)
			(polygon
				(pts
					(xy 97.3836 -69.5198) (xy 97.3836 -68.9102) (xy 97.536 -68.9102) (xy 97.536 -69.5198)
				)
			)
		)
	)
	(footprint ""
		(layer "F.Cu")
		(at 59.69 -127.127)
		(property "Reference" "SP45"
			(at 0 0 0)
			(layer "F.SilkS")
			(hide yes)
			(effects
				(font
					(size 1.27 1.27)
				)
			)
		)
		(property "Value" ""
			(at 0 0 0)
			(layer "F.Fab")
			(effects
				(font
					(size 1.27 1.27)
				)
			)
		)
		(duplicate_pad_numbers_are_jumpers no)
	)
	(footprint ""
		(layer "F.Cu")
		(at 141.05001 -107.849924 -90)
		(property "Reference" "DS2"
			(at 0.026924 1.36906 90)
			(unlocked yes)
			(layer "F.SilkS")
			(effects
				(font
					(size 0.635 0.4064)
					(thickness 0.1524)
				)
			)
		)
		(property "Value" ""
			(at 0 0 270)
			(layer "F.Fab")
			(effects
				(font
					(size 1.27 1.27)
				)
			)
		)
		(property "User Part Number" "PARTNUM*"
			(at 0.1778 2.422881 270)
			(unlocked yes)
			(layer "Cmts.User")
			(hide yes)
			(effects
				(font
					(size 0.786892 0.583946)
					(thickness 0.000001)
				)
			)
		)
		(property "Device Type" "OPTICAL-G170-10143-01"
			(at 0.1778 1.483081 270)
			(unlocked yes)
			(layer "F.Fab")
			(hide yes)
			(effects
				(font
					(size 0.786892 0.583946)
					(thickness 0.000001)
				)
			)
		)
		(duplicate_pad_numbers_are_jumpers no)
		(fp_line
			(start -1.3208 1.0922)
			(end -2.5908 1.0922)
			(stroke
				(width 0.1)
				(type default)
			)
			(layer "F.SilkS")
		)
		(fp_line
			(start -1.397508 0.704088)
			(end -1.397508 -0.704088)
			(stroke
				(width 0.1)
				(type default)
			)
			(layer "F.SilkS")
		)
		(fp_line
			(start 1.397508 0.704088)
			(end -1.397508 0.704088)
			(stroke
				(width 0.1)
				(type default)
			)
			(layer "F.SilkS")
		)
		(fp_line
			(start -1.9558 0.4572)
			(end -1.9558 1.7272)
			(stroke
				(width 0.1)
				(type default)
			)
			(layer "F.SilkS")
		)
		(fp_line
			(start -1.397508 -0.704088)
			(end 1.397508 -0.704088)
			(stroke
				(width 0.1)
				(type default)
			)
			(layer "F.SilkS")
		)
		(fp_line
			(start 1.397508 -0.704088)
			(end 1.397508 0.704088)
			(stroke
				(width 0.1)
				(type default)
			)
			(layer "F.SilkS")
		)
		(fp_rect
			(start 1.905508 0.704088)
			(end 1.397508 -0.704088)
			(stroke
				(width 0)
				(type default)
			)
			(fill yes)
			(layer "F.SilkS")
		)
		(fp_rect
			(start 1.905508 0.958088)
			(end -1.651508 -0.958088)
			(stroke
				(width 0)
				(type default)
			)
			(fill no)
			(layer "F.CrtYd")
		)
		(fp_line
			(start -1.5748 1.0922)
			(end -2.8448 1.0922)
			(stroke
				(width 0.1)
				(type default)
			)
			(layer "F.Fab")
		)
		(fp_line
			(start -2.2098 0.4572)
			(end -2.2098 1.7272)
			(stroke
				(width 0.1)
				(type default)
			)
			(layer "F.Fab")
		)
		(fp_line
			(start -0.850138 0.450088)
			(end 0.850138 0.450088)
			(stroke
				(width 0.1)
				(type default)
			)
			(layer "F.Fab")
		)
		(fp_line
			(start 0.850138 0.450088)
			(end 0.850138 -0.450088)
			(stroke
				(width 0.1)
				(type default)
			)
			(layer "F.Fab")
		)
		(fp_line
			(start -0.850138 -0.450088)
			(end -0.850138 0.450088)
			(stroke
				(width 0.1)
				(type default)
			)
			(layer "F.Fab")
		)
		(fp_line
			(start 0.850138 -0.450088)
			(end -0.850138 -0.450088)
			(stroke
				(width 0.1)
				(type default)
			)
			(layer "F.Fab")
		)
		(fp_rect
			(start 0.850138 0.450088)
			(end 0.342138 -0.450088)
			(stroke
				(width 0)
				(type default)
			)
			(fill yes)
			(layer "F.Fab")
		)
		(fp_text user "C"
			(at 1.455674 1.60401 0)
			(unlocked yes)
			(layer "F.SilkS")
			(effects
				(font
					(size 0.635 0.4064)
					(thickness 0.1524)
				)
			)
		)
		(fp_text user "A"
			(at -1.846326 -0.68199 0)
			(unlocked yes)
			(layer "F.SilkS")
			(effects
				(font
					(size 0.635 0.4064)
					(thickness 0.1524)
				)
			)
		)
		(fp_text user "A"
			(at -1.700276 0.096012 0)
			(unlocked yes)
			(layer "F.Fab")
			(effects
				(font
					(size 0.7874 0.5842)
					(thickness 0.1524)
				)
			)
		)
		(fp_text user "C"
			(at 1.844294 -0.80899 0)
			(unlocked yes)
			(layer "F.Fab")
			(effects
				(font
					(size 0.7874 0.5842)
					(thickness 0.1524)
				)
			)
		)
		(pad "A" smd rect
			(at -0.749808 0 270)
			(size 0.7874 0.7874)
			(layers "F.Cu" "F.Mask" "F.Paste")
			(net "UNNAMED_14_OPTICAL_I11_A")
		)
		(pad "C" smd rect
			(at 0.749808 0 270)
			(size 0.7874 0.7874)
			(layers "F.Cu" "F.Mask" "F.Paste")
			(net "LED_DATOUT2")
		)
	)
	(footprint ""
		(layer "F.Cu")
		(at 36.9824 -101.3714 180)
		(property "Reference" "C31"
			(at 4.064 1.73863 0)
			(unlocked yes)
			(layer "F.SilkS")
			(effects
				(font
					(size 0.7874 0.5842)
					(thickness 0.1524)
				)
			)
		)
		(property "Value" "VAL*"
			(at 0.0762 2.067306 180)
			(unlocked yes)
			(layer "F.Fab")
			(hide yes)
			(effects
				(font
					(size 0.7874 0.5842)
					(thickness 0.1524)
				)
			)
		)
		(property "Device Type" "CAPACITOR-G105-0B223-EK,0.022UA"
			(at 0.0508 1.127506 180)
			(unlocked yes)
			(layer "F.Fab")
			(hide yes)
			(effects
				(font
					(size 0.7874 0.5842)
					(thickness 0.1524)
				)
			)
		)
		(property "User Part Number" "PARTNUM*"
			(at 0.1016 4.023106 180)
			(unlocked yes)
			(layer "Cmts.User")
			(hide yes)
			(effects
				(font
					(size 0.7874 0.5842)
					(thickness 0.1524)
				)
			)
		)
		(property "Tolerance" "TOL*"
			(at 0.0762 3.032506 180)
			(unlocked yes)
			(layer "Cmts.User")
			(hide yes)
			(effects
				(font
					(size 0.7874 0.5842)
					(thickness 0.1524)
				)
			)
		)
		(duplicate_pad_numbers_are_jumpers no)
		(fp_line
			(start 1.143 0.5588)
			(end 1.143 -0.5588)
			(stroke
				(width 0.1)
				(type default)
			)
			(layer "F.SilkS")
		)
		(fp_line
			(start 1.143 -0.5588)
			(end -1.143 -0.5588)
			(stroke
				(width 0.1)
				(type default)
			)
			(layer "F.SilkS")
		)
		(fp_line
			(start -1.143 0.5588)
			(end 1.143 0.5588)
			(stroke
				(width 0.1)
				(type default)
			)
			(layer "F.SilkS")
		)
		(fp_line
			(start -1.143 -0.5588)
			(end -1.143 0.5588)
			(stroke
				(width 0.1)
				(type default)
			)
			(layer "F.SilkS")
		)
		(fp_rect
			(start -1.143 0.5588)
			(end 1.143 -0.5588)
			(stroke
				(width 0)
				(type default)
			)
			(fill no)
			(layer "F.CrtYd")
		)
		(fp_line
			(start 0.508 0.3048)
			(end 0.508 -0.3048)
			(stroke
				(width 0.1)
				(type default)
			)
			(layer "F.Fab")
		)
		(fp_line
			(start 0.508 -0.3048)
			(end -0.508 -0.3048)
			(stroke
				(width 0.1)
				(type default)
			)
			(layer "F.Fab")
		)
		(fp_line
			(start -0.508 0.3048)
			(end 0.508 0.3048)
			(stroke
				(width 0.1)
				(type default)
			)
			(layer "F.Fab")
		)
		(fp_line
			(start -0.508 -0.3048)
			(end -0.508 0.3048)
			(stroke
				(width 0.1)
				(type default)
			)
			(layer "F.Fab")
		)
		(pad "1" smd rect
			(at -0.5334 0 180)
			(size 0.7112 0.6096)
			(layers "F.Cu" "F.Mask" "F.Paste")
			(net "XP5R0V_SS")
		)
		(pad "2" smd rect
			(at 0.5334 0 180)
			(size 0.7112 0.6096)
			(layers "F.Cu" "F.Mask" "F.Paste")
			(net "XP5R0V_AGND")
		)
		(zone
			(layer "F.Cu")
			(hatch none 0.5)
			(connect_pads
				(clearance 0)
			)
			(min_thickness 0.25)
			(keepout
				(tracks allowed)
				(vias not_allowed)
				(pads allowed)
				(copperpour not_allowed)
				(footprints allowed)
			)
			(placement
				(enabled no)
				(sheetname "")
			)
			(fill
				(thermal_gap 0.5)
				(thermal_bridge_width 0.5)
				(island_removal_mode 0)
			)
			(polygon
				(pts
					(xy 37.0586 -101.6762) (xy 36.9062 -101.6762) (xy 36.9062 -101.0666) (xy 37.0586 -101.0666)
				)
			)
		)
	)
	(footprint ""
		(layer "F.Cu")
		(at 89.9922 -97.3582 180)
		(property "Reference" "R40"
			(at -1.778 -2.45237 0)
			(unlocked yes)
			(layer "F.SilkS")
			(effects
				(font
					(size 0.7874 0.5842)
					(thickness 0.1524)
				)
			)
		)
		(property "Value" "VAL*"
			(at 0.02032 2.13233 180)
			(unlocked yes)
			(layer "F.Fab")
			(hide yes)
			(effects
				(font
					(size 0.7874 0.5842)
					(thickness 0.1524)
				)
			)
		)
		(property "Tolerance" "TOL*"
			(at 0.044704 3.05435 180)
			(unlocked yes)
			(layer "Cmts.User")
			(hide yes)
			(effects
				(font
					(size 0.7874 0.5842)
					(thickness 0.1524)
				)
			)
		)
		(property "User Part Number" "PARTNUM*"
			(at 0.02032 4.024884 180)
			(unlocked yes)
			(layer "Cmts.User")
			(hide yes)
			(effects
				(font
					(size 0.7874 0.5842)
					(thickness 0.1524)
				)
			)
		)
		(property "Device Type" "RESISTOR-G155-12002-01,20KOHM,A"
			(at 0.008382 1.210564 180)
			(unlocked yes)
			(layer "F.Fab")
			(hide yes)
			(effects
				(font
					(size 0.7874 0.5842)
					(thickness 0.1524)
				)
			)
		)
		(duplicate_pad_numbers_are_jumpers no)
		(fp_line
			(start 1.143 0.5588)
			(end 1.143 -0.5588)
			(stroke
				(width 0.1)
				(type default)
			)
			(layer "F.SilkS")
		)
		(fp_line
			(start 1.143 -0.5588)
			(end -1.143 -0.5588)
			(stroke
				(width 0.1)
				(type default)
			)
			(layer "F.SilkS")
		)
		(fp_line
			(start -1.143 0.5588)
			(end 1.143 0.5588)
			(stroke
				(width 0.1)
				(type default)
			)
			(layer "F.SilkS")
		)
		(fp_line
			(start -1.143 -0.5588)
			(end -1.143 0.5588)
			(stroke
				(width 0.1)
				(type default)
			)
			(layer "F.SilkS")
		)
		(fp_rect
			(start 1.143 -0.5588)
			(end -1.143 0.5588)
			(stroke
				(width 0)
				(type default)
			)
			(fill no)
			(layer "F.CrtYd")
		)
		(fp_line
			(start 0.508 0.3048)
			(end 0.508 -0.3048)
			(stroke
				(width 0.1)
				(type default)
			)
			(layer "F.Fab")
		)
		(fp_line
			(start 0.508 -0.3048)
			(end -0.508 -0.3048)
			(stroke
				(width 0.1)
				(type default)
			)
			(layer "F.Fab")
		)
		(fp_line
			(start -0.508 0.3048)
			(end 0.508 0.3048)
			(stroke
				(width 0.1)
				(type default)
			)
			(layer "F.Fab")
		)
		(fp_line
			(start -0.508 -0.3048)
			(end -0.508 0.3048)
			(stroke
				(width 0.1)
				(type default)
			)
			(layer "F.Fab")
		)
		(pad "1" smd rect
			(at -0.5334 0 180)
			(size 0.7112 0.6096)
			(layers "F.Cu" "F.Mask" "F.Paste")
			(net "UNNAMED_517_CAPACITOR_I30_1")
		)
		(pad "2" smd rect
			(at 0.5334 0 180)
			(size 0.7112 0.6096)
			(layers "F.Cu" "F.Mask" "F.Paste")
			(net "XP3R3V_FB_R_TO_AGND")
		)
		(zone
			(layer "F.Cu")
			(hatch none 0.5)
			(connect_pads
				(clearance 0)
			)
			(min_thickness 0.25)
			(keepout
				(tracks allowed)
				(vias not_allowed)
				(pads allowed)
				(copperpour not_allowed)
				(footprints allowed)
			)
			(placement
				(enabled no)
				(sheetname "")
			)
			(fill
				(thermal_gap 0.5)
				(thermal_bridge_width 0.5)
				(island_removal_mode 0)
			)
			(polygon
				(pts
					(xy 89.916 -97.0534) (xy 90.0684 -97.0534) (xy 90.0684 -97.663) (xy 89.916 -97.663)
				)
			)
		)
	)
	(footprint ""
		(layer "F.Cu")
		(at 32.512 -96.266 180)
		(property "Reference" "C86"
			(at -2.70637 -1.016 90)
			(unlocked yes)
			(layer "F.SilkS")
			(effects
				(font
					(size 0.7874 0.5842)
					(thickness 0.1524)
				)
			)
		)
		(property "Value" "VAL*"
			(at 0.193548 2.13614 180)
			(unlocked yes)
			(layer "F.Fab")
			(hide yes)
			(effects
				(font
					(size 0.7874 0.5842)
					(thickness 0.1524)
				)
			)
		)
		(property "Tolerance" "TOL*"
			(at 0.216154 3.1496 180)
			(unlocked yes)
			(layer "Cmts.User")
			(hide yes)
			(effects
				(font
					(size 0.7874 0.5842)
					(thickness 0.1524)
				)
			)
		)
		(property "Device Type" "CAPACITOR-G104-0A180-FJ,18PF,5%"
			(at 0.184404 1.180592 180)
			(unlocked yes)
			(layer "F.Fab")
			(hide yes)
			(effects
				(font
					(size 0.7874 0.5842)
					(thickness 0.1524)
				)
			)
		)
		(property "User Part Number" "PARTNUM*"
			(at 0.216154 4.185666 180)
			(unlocked yes)
			(layer "Cmts.User")
			(hide yes)
			(effects
				(font
					(size 0.7874 0.5842)
					(thickness 0.1524)
				)
			)
		)
		(duplicate_pad_numbers_are_jumpers no)
		(fp_line
			(start 0.671322 0.4445)
			(end -0.671322 0.4445)
			(stroke
				(width 0.1)
				(type default)
			)
			(layer "F.SilkS")
		)
		(fp_line
			(start 0.671322 -0.4445)
			(end 0.671322 0.4445)
			(stroke
				(width 0.1)
				(type default)
			)
			(layer "F.SilkS")
		)
		(fp_line
			(start -0.671322 0.4445)
			(end -0.671322 -0.4445)
			(stroke
				(width 0.1)
				(type default)
			)
			(layer "F.SilkS")
		)
		(fp_line
			(start -0.671322 -0.4445)
			(end 0.671322 -0.4445)
			(stroke
				(width 0.1)
				(type default)
			)
			(layer "F.SilkS")
		)
		(fp_rect
			(start 0.671322 0.4445)
			(end -0.671322 -0.4445)
			(stroke
				(width 0)
				(type default)
			)
			(fill no)
			(layer "F.CrtYd")
		)
		(fp_line
			(start 0.31496 0.1651)
			(end 0.31496 -0.1651)
			(stroke
				(width 0.1)
				(type default)
			)
			(layer "F.Fab")
		)
		(fp_line
			(start 0.31496 -0.1651)
			(end -0.31496 -0.1651)
			(stroke
				(width 0.1)
				(type default)
			)
			(layer "F.Fab")
		)
		(fp_line
			(start -0.31496 0.1651)
			(end 0.31496 0.1651)
			(stroke
				(width 0.1)
				(type default)
			)
			(layer "F.Fab")
		)
		(fp_line
			(start -0.31496 -0.1651)
			(end -0.31496 0.1651)
			(stroke
				(width 0.1)
				(type default)
			)
			(layer "F.Fab")
		)
		(pad "1" smd rect
			(at -0.264922 0 180)
			(size 0.3048 0.381)
			(layers "F.Cu" "F.Mask" "F.Paste")
			(net "SG")
		)
		(pad "2" smd rect
			(at 0.264922 0 180)
			(size 0.3048 0.381)
			(layers "F.Cu" "F.Mask" "F.Paste")
			(net "UNNAMED_524_CAPACITOR_I7_2")
		)
		(zone
			(layer "F.Cu")
			(hatch none 0.5)
			(connect_pads
				(clearance 0)
			)
			(min_thickness 0.25)
			(keepout
				(tracks allowed)
				(vias not_allowed)
				(pads allowed)
				(copperpour not_allowed)
				(footprints allowed)
			)
			(placement
				(enabled no)
				(sheetname "")
			)
			(fill
				(thermal_gap 0.5)
				(thermal_bridge_width 0.5)
				(island_removal_mode 0)
			)
			(polygon
				(pts
					(xy 32.399478 -96.4565) (xy 32.399478 -96.0755) (xy 32.624522 -96.0755) (xy 32.624522 -96.4565)
				)
			)
		)
	)
	(footprint ""
		(layer "F.Cu")
		(at 69.469 -129.794)
		(property "Reference" "SP48"
			(at 0 0 0)
			(layer "F.SilkS")
			(hide yes)
			(effects
				(font
					(size 1.27 1.27)
				)
			)
		)
		(property "Value" ""
			(at 0 0 0)
			(layer "F.Fab")
			(effects
				(font
					(size 1.27 1.27)
				)
			)
		)
		(duplicate_pad_numbers_are_jumpers no)
	)
	(footprint ""
		(layer "F.Cu")
		(at 122.682 -33.782 90)
		(property "Reference" "TP199"
			(at -1.0668 1.42875 90)
			(unlocked yes)
			(layer "F.SilkS")
			(effects
				(font
					(size 0.635 0.4064)
					(thickness 0.1524)
				)
				(justify left)
			)
		)
		(property "Value" ""
			(at 0 0 90)
			(layer "F.Fab")
			(effects
				(font
					(size 1.27 1.27)
				)
			)
		)
		(property "Device Type" "TP_PIONT-TP010CT020B030_PTH-TPA"
			(at -1.341882 0.996696 90)
			(unlocked yes)
			(layer "F.Fab")
			(hide yes)
			(effects
				(font
					(size 0.7874 0.5842)
					(thickness 0.1524)
				)
				(justify left)
			)
		)
		(duplicate_pad_numbers_are_jumpers no)
		(fp_poly
			(pts
				(arc
					(start 0 0.889)
					(mid 0 -0.889)
					(end 0 0.889)
				)
			)
			(stroke
				(width 0)
				(type default)
			)
			(fill no)
			(layer "B.CrtYd")
		)
		(fp_poly
			(pts
				(arc
					(start 0 0.889)
					(mid 0 -0.889)
					(end 0 0.889)
				)
			)
			(stroke
				(width 0)
				(type default)
			)
			(fill no)
			(layer "F.CrtYd")
		)
		(pad "1" thru_hole circle
			(at 0 0 90)
			(size 0.508 0.508)
			(drill 0.254)
			(layers "*.Cu" "*.Mask")
			(remove_unused_layers no)
			(net "IO_L20P_35")
			(clearance 0.1016)
			(padstack
				(mode front_inner_back)
				(layer "Inner"
					(shape circle)
					(size 0.508 0.508)
					(clearance 0.1016)
				)
				(layer "B.Cu"
					(shape circle)
					(size 0.762 0.762)
					(clearance -0.0254)
				)
			)
		)
	)
	(footprint ""
		(layer "F.Cu")
		(at 14.732 -37.211 -90)
		(property "Reference" "R365"
			(at 1.27 3.77063 90)
			(unlocked yes)
			(layer "F.SilkS")
			(effects
				(font
					(size 0.7874 0.5842)
					(thickness 0.1524)
				)
			)
		)
		(property "Value" "VAL*"
			(at 0.02032 2.13233 270)
			(unlocked yes)
			(layer "F.Fab")
			(hide yes)
			(effects
				(font
					(size 0.7874 0.5842)
					(thickness 0.1524)
				)
			)
		)
		(property "Tolerance" "TOL*"
			(at 0.044704 3.05435 270)
			(unlocked yes)
			(layer "Cmts.User")
			(hide yes)
			(effects
				(font
					(size 0.7874 0.5842)
					(thickness 0.1524)
				)
			)
		)
		(property "User Part Number" "PARTNUM*"
			(at 0.02032 4.024884 270)
			(unlocked yes)
			(layer "Cmts.User")
			(hide yes)
			(effects
				(font
					(size 0.7874 0.5842)
					(thickness 0.1524)
				)
			)
		)
		(property "Device Type" "RESISTOR-G155-14701-01,4.7KOHMA"
			(at 0.008382 1.210564 270)
			(unlocked yes)
			(layer "F.Fab")
			(hide yes)
			(effects
				(font
					(size 0.7874 0.5842)
					(thickness 0.1524)
				)
			)
		)
		(duplicate_pad_numbers_are_jumpers no)
		(fp_line
			(start -1.143 0.5588)
			(end 1.143 0.5588)
			(stroke
				(width 0.1)
				(type default)
			)
			(layer "F.SilkS")
		)
		(fp_line
			(start 1.143 0.5588)
			(end 1.143 -0.5588)
			(stroke
				(width 0.1)
				(type default)
			)
			(layer "F.SilkS")
		)
		(fp_line
			(start -1.143 -0.5588)
			(end -1.143 0.5588)
			(stroke
				(width 0.1)
				(type default)
			)
			(layer "F.SilkS")
		)
		(fp_line
			(start 1.143 -0.5588)
			(end -1.143 -0.5588)
			(stroke
				(width 0.1)
				(type default)
			)
			(layer "F.SilkS")
		)
		(fp_rect
			(start 1.143 0.5588)
			(end -1.143 -0.5588)
			(stroke
				(width 0)
				(type default)
			)
			(fill no)
			(layer "F.CrtYd")
		)
		(fp_line
			(start -0.508 0.3048)
			(end 0.508 0.3048)
			(stroke
				(width 0.1)
				(type default)
			)
			(layer "F.Fab")
		)
		(fp_line
			(start 0.508 0.3048)
			(end 0.508 -0.3048)
			(stroke
				(width 0.1)
				(type default)
			)
			(layer "F.Fab")
		)
		(fp_line
			(start -0.508 -0.3048)
			(end -0.508 0.3048)
			(stroke
				(width 0.1)
				(type default)
			)
			(layer "F.Fab")
		)
		(fp_line
			(start 0.508 -0.3048)
			(end -0.508 -0.3048)
			(stroke
				(width 0.1)
				(type default)
			)
			(layer "F.Fab")
		)
		(pad "1" smd rect
			(at -0.5334 0 270)
			(size 0.7112 0.6096)
			(layers "F.Cu" "F.Mask" "F.Paste")
			(net "XP3R3V_FPGA")
		)
		(pad "2" smd rect
			(at 0.5334 0 270)
			(size 0.7112 0.6096)
			(layers "F.Cu" "F.Mask" "F.Paste")
			(net "SMA3_SIG_OUT_BF_EN_N")
		)
		(zone
			(layer "F.Cu")
			(hatch none 0.5)
			(connect_pads
				(clearance 0)
			)
			(min_thickness 0.25)
			(keepout
				(tracks not_allowed)
				(vias allowed)
				(pads allowed)
				(copperpour not_allowed)
				(footprints allowed)
			)
			(placement
				(enabled no)
				(sheetname "")
			)
			(fill
				(thermal_gap 0.5)
				(thermal_bridge_width 0.5)
				(island_removal_mode 0)
			)
			(polygon
				(pts
					(xy 14.4272 -37.1348) (xy 15.0368 -37.1348) (xy 15.0368 -37.2872) (xy 14.4272 -37.2872)
				)
			)
		)
		(zone
			(layer "F.Cu")
			(hatch none 0.5)
			(connect_pads
				(clearance 0)
			)
			(min_thickness 0.25)
			(keepout
				(tracks allowed)
				(vias not_allowed)
				(pads allowed)
				(copperpour not_allowed)
				(footprints allowed)
			)
			(placement
				(enabled no)
				(sheetname "")
			)
			(fill
				(thermal_gap 0.5)
				(thermal_bridge_width 0.5)
				(island_removal_mode 0)
			)
			(polygon
				(pts
					(xy 14.4272 -37.1348) (xy 15.0368 -37.1348) (xy 15.0368 -37.2872) (xy 14.4272 -37.2872)
				)
			)
		)
	)
	(footprint ""
		(layer "F.Cu")
		(at 120.269 -89.535 -90)
		(property "Reference" "R114"
			(at 3.429 0.08763 90)
			(unlocked yes)
			(layer "F.SilkS")
			(effects
				(font
					(size 0.7874 0.5842)
					(thickness 0.1524)
				)
			)
		)
		(property "Value" "VAL*"
			(at 0.02032 2.13233 270)
			(unlocked yes)
			(layer "F.Fab")
			(hide yes)
			(effects
				(font
					(size 0.7874 0.5842)
					(thickness 0.1524)
				)
			)
		)
		(property "Device Type" "RESISTOR-G155-14701-01,4.7KOHMA"
			(at 0.008382 1.210564 270)
			(unlocked yes)
			(layer "F.Fab")
			(hide yes)
			(effects
				(font
					(size 0.7874 0.5842)
					(thickness 0.1524)
				)
			)
		)
		(property "User Part Number" "PARTNUM*"
			(at 0.02032 4.024884 270)
			(unlocked yes)
			(layer "Cmts.User")
			(hide yes)
			(effects
				(font
					(size 0.7874 0.5842)
					(thickness 0.1524)
				)
			)
		)
		(property "Tolerance" "TOL*"
			(at 0.044704 3.05435 270)
			(unlocked yes)
			(layer "Cmts.User")
			(hide yes)
			(effects
				(font
					(size 0.7874 0.5842)
					(thickness 0.1524)
				)
			)
		)
		(duplicate_pad_numbers_are_jumpers no)
		(fp_line
			(start -1.143 0.5588)
			(end 1.143 0.5588)
			(stroke
				(width 0.1)
				(type default)
			)
			(layer "F.SilkS")
		)
		(fp_line
			(start 1.143 0.5588)
			(end 1.143 -0.5588)
			(stroke
				(width 0.1)
				(type default)
			)
			(layer "F.SilkS")
		)
		(fp_line
			(start -1.143 -0.5588)
			(end -1.143 0.5588)
			(stroke
				(width 0.1)
				(type default)
			)
			(layer "F.SilkS")
		)
		(fp_line
			(start 1.143 -0.5588)
			(end -1.143 -0.5588)
			(stroke
				(width 0.1)
				(type default)
			)
			(layer "F.SilkS")
		)
		(fp_rect
			(start 1.143 -0.5588)
			(end -1.143 0.5588)
			(stroke
				(width 0)
				(type default)
			)
			(fill no)
			(layer "F.CrtYd")
		)
		(fp_line
			(start -0.508 0.3048)
			(end 0.508 0.3048)
			(stroke
				(width 0.1)
				(type default)
			)
			(layer "F.Fab")
		)
		(fp_line
			(start 0.508 0.3048)
			(end 0.508 -0.3048)
			(stroke
				(width 0.1)
				(type default)
			)
			(layer "F.Fab")
		)
		(fp_line
			(start -0.508 -0.3048)
			(end -0.508 0.3048)
			(stroke
				(width 0.1)
				(type default)
			)
			(layer "F.Fab")
		)
		(fp_line
			(start 0.508 -0.3048)
			(end -0.508 -0.3048)
			(stroke
				(width 0.1)
				(type default)
			)
			(layer "F.Fab")
		)
		(pad "1" smd rect
			(at -0.5334 0 270)
			(size 0.7112 0.6096)
			(layers "F.Cu" "F.Mask" "F.Paste")
			(net "GPS_RST_N")
		)
		(pad "2" smd rect
			(at 0.5334 0 270)
			(size 0.7112 0.6096)
			(layers "F.Cu" "F.Mask" "F.Paste")
			(net "SG")
		)
		(zone
			(layer "F.Cu")
			(hatch none 0.5)
			(connect_pads
				(clearance 0)
			)
			(min_thickness 0.25)
			(keepout
				(tracks allowed)
				(vias not_allowed)
				(pads allowed)
				(copperpour not_allowed)
				(footprints allowed)
			)
			(placement
				(enabled no)
				(sheetname "")
			)
			(fill
				(thermal_gap 0.5)
				(thermal_bridge_width 0.5)
				(island_removal_mode 0)
			)
			(polygon
				(pts
					(xy 120.5738 -89.4588) (xy 120.5738 -89.6112) (xy 119.9642 -89.6112) (xy 119.9642 -89.4588)
				)
			)
		)
	)
	(footprint ""
		(layer "F.Cu")
		(at 4.8514 -39.318692 90)
		(property "Reference" "R385"
			(at 2.337308 0.20955 90)
			(unlocked yes)
			(layer "F.SilkS")
			(effects
				(font
					(size 0.635 0.4064)
					(thickness 0.1524)
				)
			)
		)
		(property "Value" "VAL*"
			(at 0.02032 2.13233 90)
			(unlocked yes)
			(layer "F.Fab")
			(hide yes)
			(effects
				(font
					(size 0.7874 0.5842)
					(thickness 0.1524)
				)
			)
		)
		(property "Tolerance" "TOL*"
			(at 0.044704 3.05435 90)
			(unlocked yes)
			(layer "Cmts.User")
			(hide yes)
			(effects
				(font
					(size 0.7874 0.5842)
					(thickness 0.1524)
				)
			)
		)
		(property "User Part Number" "PARTNUM*"
			(at 0.02032 4.024884 90)
			(unlocked yes)
			(layer "Cmts.User")
			(hide yes)
			(effects
				(font
					(size 0.7874 0.5842)
					(thickness 0.1524)
				)
			)
		)
		(property "Device Type" "RESISTOR-G155-133R0-01,33OHM,1%"
			(at 0.008382 1.210564 90)
			(unlocked yes)
			(layer "F.Fab")
			(hide yes)
			(effects
				(font
					(size 0.7874 0.5842)
					(thickness 0.1524)
				)
			)
		)
		(duplicate_pad_numbers_are_jumpers no)
		(fp_line
			(start 1.143 -0.5588)
			(end -1.143 -0.5588)
			(stroke
				(width 0.1)
				(type default)
			)
			(layer "F.SilkS")
		)
		(fp_line
			(start -1.143 -0.5588)
			(end -1.143 0.5588)
			(stroke
				(width 0.1)
				(type default)
			)
			(layer "F.SilkS")
		)
		(fp_line
			(start 1.143 0.5588)
			(end 1.143 -0.5588)
			(stroke
				(width 0.1)
				(type default)
			)
			(layer "F.SilkS")
		)
		(fp_line
			(start -1.143 0.5588)
			(end 1.143 0.5588)
			(stroke
				(width 0.1)
				(type default)
			)
			(layer "F.SilkS")
		)
		(fp_rect
			(start -1.143 -0.5588)
			(end 1.143 0.5588)
			(stroke
				(width 0)
				(type default)
			)
			(fill no)
			(layer "F.CrtYd")
		)
		(fp_line
			(start 0.508 -0.3048)
			(end -0.508 -0.3048)
			(stroke
				(width 0.1)
				(type default)
			)
			(layer "F.Fab")
		)
		(fp_line
			(start -0.508 -0.3048)
			(end -0.508 0.3048)
			(stroke
				(width 0.1)
				(type default)
			)
			(layer "F.Fab")
		)
		(fp_line
			(start 0.508 0.3048)
			(end 0.508 -0.3048)
			(stroke
				(width 0.1)
				(type default)
			)
			(layer "F.Fab")
		)
		(fp_line
			(start -0.508 0.3048)
			(end 0.508 0.3048)
			(stroke
				(width 0.1)
				(type default)
			)
			(layer "F.Fab")
		)
		(pad "1" smd rect
			(at -0.5334 0 90)
			(size 0.7112 0.6096)
			(layers "F.Cu" "F.Mask" "F.Paste")
			(net "SMA1_LED_BLUE_N")
		)
		(pad "2" smd rect
			(at 0.5334 0 90)
			(size 0.7112 0.6096)
			(layers "F.Cu" "F.Mask" "F.Paste")
			(net "UNNAMED_14_LED4PV14_I265_1")
		)
		(zone
			(layer "F.Cu")
			(hatch none 0.5)
			(connect_pads
				(clearance 0)
			)
			(min_thickness 0.25)
			(keepout
				(tracks not_allowed)
				(vias allowed)
				(pads allowed)
				(copperpour not_allowed)
				(footprints allowed)
			)
			(placement
				(enabled no)
				(sheetname "")
			)
			(fill
				(thermal_gap 0.5)
				(thermal_bridge_width 0.5)
				(island_removal_mode 0)
			)
			(polygon
				(pts
					(xy 4.5466 -39.242492) (xy 5.1562 -39.242492) (xy 5.1562 -39.394892) (xy 4.5466 -39.394892)
				)
			)
		)
		(zone
			(layer "F.Cu")
			(hatch none 0.5)
			(connect_pads
				(clearance 0)
			)
			(min_thickness 0.25)
			(keepout
				(tracks allowed)
				(vias not_allowed)
				(pads allowed)
				(copperpour not_allowed)
				(footprints allowed)
			)
			(placement
				(enabled no)
				(sheetname "")
			)
			(fill
				(thermal_gap 0.5)
				(thermal_bridge_width 0.5)
				(island_removal_mode 0)
			)
			(polygon
				(pts
					(xy 4.5466 -39.242492) (xy 5.1562 -39.242492) (xy 5.1562 -39.394892) (xy 4.5466 -39.394892)
				)
			)
		)
	)
	(footprint ""
		(layer "F.Cu")
		(at 41.8084 -100.7364 90)
		(property "Reference" "U5"
			(at -6.66877 1.4986 0)
			(unlocked yes)
			(layer "F.SilkS")
			(effects
				(font
					(size 0.7874 0.5842)
					(thickness 0.1524)
				)
			)
		)
		(property "Value" ""
			(at 0 0 90)
			(layer "F.Fab")
			(effects
				(font
					(size 1.27 1.27)
				)
			)
		)
		(property "User Part Number" "PARTNUM*"
			(at 0.33782 5.715254 90)
			(unlocked yes)
			(layer "Cmts.User")
			(hide yes)
			(effects
				(font
					(size 0.7874 0.5842)
					(thickness 0.1524)
				)
			)
		)
		(property "Device Type" "TPS54824RNVR_VQFN18-G220-10657A"
			(at 0.33782 4.521454 90)
			(unlocked yes)
			(layer "F.Fab")
			(hide yes)
			(effects
				(font
					(size 0.7874 0.5842)
					(thickness 0.1524)
				)
			)
		)
		(duplicate_pad_numbers_are_jumpers no)
		(fp_line
			(start 2.208784 -2.208784)
			(end 2.208784 2.200148)
			(stroke
				(width 0.1)
				(type default)
			)
			(layer "F.SilkS")
		)
		(fp_line
			(start -2.208784 -2.208784)
			(end 2.208784 -2.208784)
			(stroke
				(width 0.1)
				(type default)
			)
			(layer "F.SilkS")
		)
		(fp_line
			(start 2.208784 2.200148)
			(end -2.208784 2.200148)
			(stroke
				(width 0.1)
				(type default)
			)
			(layer "F.SilkS")
		)
		(fp_line
			(start -2.208784 2.200148)
			(end -2.208784 -2.208784)
			(stroke
				(width 0.1)
				(type default)
			)
			(layer "F.SilkS")
		)
		(fp_poly
			(pts
				(arc
					(start -3.084068 -0.48514)
					(mid -3.084068 -1.50114)
					(end -3.084068 -0.48514)
				)
			)
			(stroke
				(width 0)
				(type default)
			)
			(fill yes)
			(layer "F.SilkS")
		)
		(fp_rect
			(start 2.462784 2.454148)
			(end -2.462784 -2.462784)
			(stroke
				(width 0)
				(type default)
			)
			(fill no)
			(layer "F.CrtYd")
		)
		(fp_line
			(start 1.800098 -1.800098)
			(end 1.800098 1.800098)
			(stroke
				(width 0.1)
				(type default)
			)
			(layer "F.Fab")
		)
		(fp_line
			(start -1.800098 -1.800098)
			(end 1.800098 -1.800098)
			(stroke
				(width 0.1)
				(type default)
			)
			(layer "F.Fab")
		)
		(fp_line
			(start 1.800098 1.800098)
			(end -1.800098 1.800098)
			(stroke
				(width 0.1)
				(type default)
			)
			(layer "F.Fab")
		)
		(fp_line
			(start -1.800098 1.800098)
			(end -1.800098 -1.800098)
			(stroke
				(width 0.1)
				(type default)
			)
			(layer "F.Fab")
		)
		(fp_circle
			(center -3.084068 -0.99314)
			(end -3.084068 -0.48514)
			(stroke
				(width 0.1)
				(type default)
			)
			(fill no)
			(layer "F.Fab")
		)
		(fp_text user "13"
			(at 1.6256 -2.78765 90)
			(unlocked yes)
			(layer "F.SilkS")
			(effects
				(font
					(size 0.635 0.4064)
					(thickness 0.1524)
				)
			)
		)
		(fp_text user "18"
			(at -2.3114 -2.66065 90)
			(unlocked yes)
			(layer "F.SilkS")
			(effects
				(font
					(size 0.635 0.4064)
					(thickness 0.1524)
				)
			)
		)
		(fp_text user "12"
			(at 2.73685 -1.0414 0)
			(unlocked yes)
			(layer "F.SilkS")
			(effects
				(font
					(size 0.635 0.4064)
					(thickness 0.1524)
				)
			)
		)
		(fp_text user "8"
			(at 2.60985 2.1336 0)
			(unlocked yes)
			(layer "F.SilkS")
			(effects
				(font
					(size 0.635 0.4064)
					(thickness 0.1524)
				)
			)
		)
		(fp_text user "5"
			(at -1.65735 2.6924 0)
			(unlocked yes)
			(layer "F.SilkS")
			(effects
				(font
					(size 0.635 0.4064)
					(thickness 0.1524)
				)
			)
		)
		(fp_text user "7"
			(at 1.64465 2.8956 0)
			(unlocked yes)
			(layer "F.SilkS")
			(effects
				(font
					(size 0.635 0.4064)
					(thickness 0.1524)
				)
			)
		)
		(fp_text user "6"
			(at -0.81915 3.1496 0)
			(unlocked yes)
			(layer "F.SilkS")
			(effects
				(font
					(size 0.635 0.4064)
					(thickness 0.1524)
				)
			)
		)
		(fp_text user "18"
			(at -1.44907 -2.8194 0)
			(unlocked yes)
			(layer "F.Fab")
			(effects
				(font
					(size 0.7874 0.5842)
					(thickness 0.1524)
				)
			)
		)
		(fp_text user "13"
			(at 1.59893 -2.6924 0)
			(unlocked yes)
			(layer "F.Fab")
			(effects
				(font
					(size 0.7874 0.5842)
					(thickness 0.1524)
				)
			)
		)
		(fp_text user "12"
			(at 2.61493 -1.6764 0)
			(unlocked yes)
			(layer "F.Fab")
			(effects
				(font
					(size 0.7874 0.5842)
					(thickness 0.1524)
				)
			)
		)
		(fp_text user "5"
			(at -2.33807 1.3716 0)
			(unlocked yes)
			(layer "F.Fab")
			(effects
				(font
					(size 0.7874 0.5842)
					(thickness 0.1524)
				)
			)
		)
		(fp_text user "8"
			(at 2.36093 1.6256 0)
			(unlocked yes)
			(layer "F.Fab")
			(effects
				(font
					(size 0.7874 0.5842)
					(thickness 0.1524)
				)
			)
		)
		(fp_text user "7"
			(at 1.34493 2.2606 0)
			(unlocked yes)
			(layer "F.Fab")
			(effects
				(font
					(size 0.7874 0.5842)
					(thickness 0.1524)
				)
			)
		)
		(fp_text user "6"
			(at -1.57607 2.3876 0)
			(unlocked yes)
			(layer "F.Fab")
			(effects
				(font
					(size 0.7874 0.5842)
					(thickness 0.1524)
				)
			)
		)
		(pad "1" smd rect
			(at -1.649984 -0.94996 90)
			(size 0.6096 0.3048)
			(layers "F.Cu" "F.Mask" "F.Paste")
			(net "XP5R0V_BT")
		)
		(pad "2" smd rect
			(at -1.374902 -0.350012 90)
			(size 1.143 0.4064)
			(layers "F.Cu" "F.Mask" "F.Paste")
			(net "VIN_XP5R0V")
		)
		(pad "3" smd rect
			(at -1.374902 0.299974 90)
			(size 1.143 0.3048)
			(layers "F.Cu" "F.Mask" "F.Paste")
			(net "SG")
		)
		(pad "4" smd rect
			(at -1.374902 0.849884 90)
			(size 1.143 0.3048)
			(layers "F.Cu" "F.Mask" "F.Paste")
			(net "SG")
		)
		(pad "5" smd rect
			(at -1.374902 1.400048 90)
			(size 1.143 0.3048)
			(layers "F.Cu" "F.Mask" "F.Paste")
			(net "SG")
		)
		(pad "6" smd rect
			(at -0.32512 0.599948 90)
			(size 0.2032 2.6924)
			(layers "F.Cu" "F.Mask" "F.Paste")
			(net "XP5R0V_SW")
		)
		(pad "7" smd rect
			(at 0.32512 0.599948 90)
			(size 0.2032 2.6924)
			(layers "F.Cu" "F.Mask" "F.Paste")
			(net "XP5R0V_SW")
		)
		(pad "8" smd rect
			(at 1.374902 1.400048 90)
			(size 1.143 0.3048)
			(layers "F.Cu" "F.Mask" "F.Paste")
			(net "SG")
		)
		(pad "9" smd rect
			(at 1.374902 0.849884 90)
			(size 1.143 0.3048)
			(layers "F.Cu" "F.Mask" "F.Paste")
			(net "SG")
		)
		(pad "10" smd rect
			(at 1.374902 0.299974 90)
			(size 1.143 0.3048)
			(layers "F.Cu" "F.Mask" "F.Paste")
			(net "SG")
		)
		(pad "11" smd rect
			(at 1.374902 -0.350012 90)
			(size 1.143 0.4064)
			(layers "F.Cu" "F.Mask" "F.Paste")
			(net "VIN_XP5R0V")
		)
		(pad "12" smd rect
			(at 1.649984 -0.94996 90)
			(size 0.6096 0.3048)
			(layers "F.Cu" "F.Mask" "F.Paste")
			(net "XP5R0V_AGND")
		)
		(pad "13" smd rect
			(at 1.374902 -1.649984 90)
			(size 0.508 0.6096)
			(layers "F.Cu" "F.Mask" "F.Paste")
			(net "XP5R0V_RT")
		)
		(pad "14" smd rect
			(at 0.750062 -1.649984 90)
			(size 0.254 0.6096)
			(layers "F.Cu" "F.Mask" "F.Paste")
			(net "XP5R0V_FB_R_TO_AGND")
		)
		(pad "15" smd rect
			(at 0.249936 -1.649984 90)
			(size 0.254 0.6096)
			(layers "F.Cu" "F.Mask" "F.Paste")
			(net "XP5R0V_COMP")
		)
		(pad "16" smd rect
			(at -0.249936 -1.649984 90)
			(size 0.254 0.6096)
			(layers "F.Cu" "F.Mask" "F.Paste")
			(net "XP5R0V_SS")
		)
		(pad "17" smd rect
			(at -0.750062 -1.649984 90)
			(size 0.254 0.6096)
			(layers "F.Cu" "F.Mask" "F.Paste")
			(net "R_XP5R0V_EN")
		)
		(pad "18" smd rect
			(at -1.374902 -1.649984 90)
			(size 0.508 0.6096)
			(layers "F.Cu" "F.Mask" "F.Paste")
			(net "XP5R0V_PG")
		)
	)
	(footprint ""
		(layer "F.Cu")
		(at 117.346984 -41.32326)
		(property "Reference" "TP140"
			(at 0 0 0)
			(layer "F.SilkS")
			(hide yes)
			(effects
				(font
					(size 1.27 1.27)
				)
			)
		)
		(property "Value" ""
			(at 0 0 0)
			(layer "F.Fab")
			(effects
				(font
					(size 1.27 1.27)
				)
			)
		)
		(property "Device Type" "TP_PIONT-TP010CT020B030_PTH-TPA"
			(at -1.341882 0.996696 0)
			(unlocked yes)
			(layer "F.Fab")
			(hide yes)
			(effects
				(font
					(size 0.7874 0.5842)
					(thickness 0.1524)
				)
				(justify left)
			)
		)
		(duplicate_pad_numbers_are_jumpers no)
		(fp_poly
			(pts
				(arc
					(start 0.889 0)
					(mid -0.889 0)
					(end 0.889 0)
				)
			)
			(stroke
				(width 0)
				(type default)
			)
			(fill no)
			(layer "B.CrtYd")
		)
		(fp_poly
			(pts
				(arc
					(start 0.889 0)
					(mid -0.889 0)
					(end 0.889 0)
				)
			)
			(stroke
				(width 0)
				(type default)
			)
			(fill no)
			(layer "F.CrtYd")
		)
		(pad "1" thru_hole circle
			(at 0 0)
			(size 0.508 0.508)
			(drill 0.254)
			(layers "*.Cu" "*.Mask")
			(remove_unused_layers no)
			(net "IO_L24P_34")
			(clearance 0.1016)
			(padstack
				(mode front_inner_back)
				(layer "Inner"
					(shape circle)
					(size 0.508 0.508)
					(clearance 0.1016)
				)
				(layer "B.Cu"
					(shape circle)
					(size 0.762 0.762)
					(clearance -0.0254)
				)
			)
		)
	)
	(footprint ""
		(layer "F.Cu")
		(at 145.8214 -96.6978)
		(property "Reference" "C5"
			(at 2.667 -0.59563 0)
			(unlocked yes)
			(layer "F.SilkS")
			(effects
				(font
					(size 0.7874 0.5842)
					(thickness 0.1524)
				)
			)
		)
		(property "Value" "VAL*"
			(at 0.0762 2.067306 0)
			(unlocked yes)
			(layer "F.Fab")
			(hide yes)
			(effects
				(font
					(size 0.7874 0.5842)
					(thickness 0.1524)
				)
			)
		)
		(property "Device Type" "CAPACITOR-G105-0B104-EK,0.1UF,A"
			(at 0.0508 1.127506 0)
			(unlocked yes)
			(layer "F.Fab")
			(hide yes)
			(effects
				(font
					(size 0.7874 0.5842)
					(thickness 0.1524)
				)
			)
		)
		(property "User Part Number" "PARTNUM*"
			(at 0.1016 4.023106 0)
			(unlocked yes)
			(layer "Cmts.User")
			(hide yes)
			(effects
				(font
					(size 0.7874 0.5842)
					(thickness 0.1524)
				)
			)
		)
		(property "Tolerance" "TOL*"
			(at 0.0762 3.032506 0)
			(unlocked yes)
			(layer "Cmts.User")
			(hide yes)
			(effects
				(font
					(size 0.7874 0.5842)
					(thickness 0.1524)
				)
			)
		)
		(duplicate_pad_numbers_are_jumpers no)
		(fp_line
			(start -1.143 -0.5588)
			(end -1.143 0.5588)
			(stroke
				(width 0.1)
				(type default)
			)
			(layer "F.SilkS")
		)
		(fp_line
			(start -1.143 0.5588)
			(end 1.143 0.5588)
			(stroke
				(width 0.1)
				(type default)
			)
			(layer "F.SilkS")
		)
		(fp_line
			(start 1.143 -0.5588)
			(end -1.143 -0.5588)
			(stroke
				(width 0.1)
				(type default)
			)
			(layer "F.SilkS")
		)
		(fp_line
			(start 1.143 0.5588)
			(end 1.143 -0.5588)
			(stroke
				(width 0.1)
				(type default)
			)
			(layer "F.SilkS")
		)
		(fp_rect
			(start -1.143 0.5588)
			(end 1.143 -0.5588)
			(stroke
				(width 0)
				(type default)
			)
			(fill no)
			(layer "F.CrtYd")
		)
		(fp_line
			(start -0.508 -0.3048)
			(end -0.508 0.3048)
			(stroke
				(width 0.1)
				(type default)
			)
			(layer "F.Fab")
		)
		(fp_line
			(start -0.508 0.3048)
			(end 0.508 0.3048)
			(stroke
				(width 0.1)
				(type default)
			)
			(layer "F.Fab")
		)
		(fp_line
			(start 0.508 -0.3048)
			(end -0.508 -0.3048)
			(stroke
				(width 0.1)
				(type default)
			)
			(layer "F.Fab")
		)
		(fp_line
			(start 0.508 0.3048)
			(end 0.508 -0.3048)
			(stroke
				(width 0.1)
				(type default)
			)
			(layer "F.Fab")
		)
		(pad "1" smd rect
			(at -0.5334 0)
			(size 0.7112 0.6096)
			(layers "F.Cu" "F.Mask" "F.Paste")
			(net "XP12R0V_A_SS")
		)
		(pad "2" smd rect
			(at 0.5334 0)
			(size 0.7112 0.6096)
			(layers "F.Cu" "F.Mask" "F.Paste")
			(net "SG")
		)
		(zone
			(layer "F.Cu")
			(hatch none 0.5)
			(connect_pads
				(clearance 0)
			)
			(min_thickness 0.25)
			(keepout
				(tracks allowed)
				(vias not_allowed)
				(pads allowed)
				(copperpour not_allowed)
				(footprints allowed)
			)
			(placement
				(enabled no)
				(sheetname "")
			)
			(fill
				(thermal_gap 0.5)
				(thermal_bridge_width 0.5)
				(island_removal_mode 0)
			)
			(polygon
				(pts
					(xy 145.7452 -96.393) (xy 145.8976 -96.393) (xy 145.8976 -97.0026) (xy 145.7452 -97.0026)
				)
			)
		)
	)
	(footprint ""
		(layer "F.Cu")
		(at 126.1364 -32.1056 180)
		(property "Reference" "C292"
			(at 0 -1.96977 0)
			(unlocked yes)
			(layer "F.SilkS")
			(effects
				(font
					(size 0.7874 0.5842)
					(thickness 0.1524)
				)
			)
		)
		(property "Value" "VAL*"
			(at 0.0762 3.134106 180)
			(unlocked yes)
			(layer "F.Fab")
			(hide yes)
			(effects
				(font
					(size 0.7874 0.5842)
					(thickness 0.1524)
				)
			)
		)
		(property "Tolerance" "TOL*"
			(at 0.0762 4.048506 180)
			(unlocked yes)
			(layer "Cmts.User")
			(hide yes)
			(effects
				(font
					(size 0.7874 0.5842)
					(thickness 0.1524)
				)
			)
		)
		(property "User Part Number" "PARTNUM*"
			(at 0.1016 5.013706 180)
			(unlocked yes)
			(layer "Cmts.User")
			(hide yes)
			(effects
				(font
					(size 0.7874 0.5842)
					(thickness 0.1524)
				)
			)
		)
		(property "Device Type" "CAPACITOR-G107-0F226-CM,22UF,2A"
			(at 0.0508 2.194306 180)
			(unlocked yes)
			(layer "F.Fab")
			(hide yes)
			(effects
				(font
					(size 0.7874 0.5842)
					(thickness 0.1524)
				)
			)
		)
		(duplicate_pad_numbers_are_jumpers no)
		(fp_line
			(start 1.5748 0.9398)
			(end 1.5748 -0.9398)
			(stroke
				(width 0.1)
				(type default)
			)
			(layer "F.SilkS")
		)
		(fp_line
			(start 1.5748 -0.9398)
			(end -1.5748 -0.9398)
			(stroke
				(width 0.1)
				(type default)
			)
			(layer "F.SilkS")
		)
		(fp_line
			(start -1.5748 0.9398)
			(end 1.5748 0.9398)
			(stroke
				(width 0.1)
				(type default)
			)
			(layer "F.SilkS")
		)
		(fp_line
			(start -1.5748 -0.9398)
			(end -1.5748 0.9398)
			(stroke
				(width 0.1)
				(type default)
			)
			(layer "F.SilkS")
		)
		(fp_rect
			(start 1.5748 0.9398)
			(end -1.5748 -0.9398)
			(stroke
				(width 0)
				(type default)
			)
			(fill no)
			(layer "F.CrtYd")
		)
		(fp_line
			(start 1.016 0.635)
			(end 1.016 -0.635)
			(stroke
				(width 0.1)
				(type default)
			)
			(layer "F.Fab")
		)
		(fp_line
			(start 1.016 -0.635)
			(end -1.016 -0.635)
			(stroke
				(width 0.1)
				(type default)
			)
			(layer "F.Fab")
		)
		(fp_line
			(start -1.016 0.635)
			(end 1.016 0.635)
			(stroke
				(width 0.1)
				(type default)
			)
			(layer "F.Fab")
		)
		(fp_line
			(start -1.016 -0.635)
			(end -1.016 0.635)
			(stroke
				(width 0.1)
				(type default)
			)
			(layer "F.Fab")
		)
		(pad "1" smd rect
			(at -0.8382 0 180)
			(size 0.9652 1.3716)
			(layers "F.Cu" "F.Mask" "F.Paste")
			(net "XP2R5V_FPGA")
		)
		(pad "2" smd rect
			(at 0.8382 0 180)
			(size 0.9652 1.3716)
			(layers "F.Cu" "F.Mask" "F.Paste")
			(net "SG")
		)
		(zone
			(layer "F.Cu")
			(hatch none 0.5)
			(connect_pads
				(clearance 0)
			)
			(min_thickness 0.25)
			(keepout
				(tracks not_allowed)
				(vias allowed)
				(pads allowed)
				(copperpour not_allowed)
				(footprints allowed)
			)
			(placement
				(enabled no)
				(sheetname "")
			)
			(fill
				(thermal_gap 0.5)
				(thermal_bridge_width 0.5)
				(island_removal_mode 0)
			)
			(polygon
				(pts
					(xy 125.9078 -32.7406) (xy 125.9078 -31.4706) (xy 126.365 -31.4706) (xy 126.365 -32.7406)
				)
			)
		)
		(zone
			(layer "F.Cu")
			(hatch none 0.5)
			(connect_pads
				(clearance 0)
			)
			(min_thickness 0.25)
			(keepout
				(tracks allowed)
				(vias not_allowed)
				(pads allowed)
				(copperpour not_allowed)
				(footprints allowed)
			)
			(placement
				(enabled no)
				(sheetname "")
			)
			(fill
				(thermal_gap 0.5)
				(thermal_bridge_width 0.5)
				(island_removal_mode 0)
			)
			(polygon
				(pts
					(xy 125.9078 -32.7406) (xy 125.9078 -31.4706) (xy 126.365 -31.4706) (xy 126.365 -32.7406)
				)
			)
		)
	)
	(footprint ""
		(layer "F.Cu")
		(at 15.3924 -42.37863 -90)
		(property "Reference" "C84"
			(at 2.11963 -0.64135 90)
			(unlocked yes)
			(layer "F.SilkS")
			(effects
				(font
					(size 0.635 0.4064)
					(thickness 0.1524)
				)
			)
		)
		(property "Value" "VAL*"
			(at 0.0762 2.067306 270)
			(unlocked yes)
			(layer "F.Fab")
			(hide yes)
			(effects
				(font
					(size 0.7874 0.5842)
					(thickness 0.1524)
				)
			)
		)
		(property "Tolerance" "TOL*"
			(at 0.0762 3.032506 270)
			(unlocked yes)
			(layer "Cmts.User")
			(hide yes)
			(effects
				(font
					(size 0.7874 0.5842)
					(thickness 0.1524)
				)
			)
		)
		(property "User Part Number" "PARTNUM*"
			(at 0.1016 4.023106 270)
			(unlocked yes)
			(layer "Cmts.User")
			(hide yes)
			(effects
				(font
					(size 0.7874 0.5842)
					(thickness 0.1524)
				)
			)
		)
		(property "Device Type" "CAPACITOR-G105-0B104-CK,0.1UF,A"
			(at 0.0508 1.127506 270)
			(unlocked yes)
			(layer "F.Fab")
			(hide yes)
			(effects
				(font
					(size 0.7874 0.5842)
					(thickness 0.1524)
				)
			)
		)
		(duplicate_pad_numbers_are_jumpers no)
		(fp_line
			(start -1.143 0.5588)
			(end 1.143 0.5588)
			(stroke
				(width 0.1)
				(type default)
			)
			(layer "F.SilkS")
		)
		(fp_line
			(start 1.143 0.5588)
			(end 1.143 -0.5588)
			(stroke
				(width 0.1)
				(type default)
			)
			(layer "F.SilkS")
		)
		(fp_line
			(start -1.143 -0.5588)
			(end -1.143 0.5588)
			(stroke
				(width 0.1)
				(type default)
			)
			(layer "F.SilkS")
		)
		(fp_line
			(start 1.143 -0.5588)
			(end -1.143 -0.5588)
			(stroke
				(width 0.1)
				(type default)
			)
			(layer "F.SilkS")
		)
		(fp_rect
			(start 1.143 0.5588)
			(end -1.143 -0.5588)
			(stroke
				(width 0)
				(type default)
			)
			(fill no)
			(layer "F.CrtYd")
		)
		(fp_line
			(start -0.508 0.3048)
			(end 0.508 0.3048)
			(stroke
				(width 0.1)
				(type default)
			)
			(layer "F.Fab")
		)
		(fp_line
			(start 0.508 0.3048)
			(end 0.508 -0.3048)
			(stroke
				(width 0.1)
				(type default)
			)
			(layer "F.Fab")
		)
		(fp_line
			(start -0.508 -0.3048)
			(end -0.508 0.3048)
			(stroke
				(width 0.1)
				(type default)
			)
			(layer "F.Fab")
		)
		(fp_line
			(start 0.508 -0.3048)
			(end -0.508 -0.3048)
			(stroke
				(width 0.1)
				(type default)
			)
			(layer "F.Fab")
		)
		(pad "1" smd rect
			(at -0.5334 0 270)
			(size 0.7112 0.6096)
			(layers "F.Cu" "F.Mask" "F.Paste")
			(net "XP3R3V_FPGA")
		)
		(pad "2" smd rect
			(at 0.5334 0 270)
			(size 0.7112 0.6096)
			(layers "F.Cu" "F.Mask" "F.Paste")
			(net "SG")
		)
		(zone
			(layer "F.Cu")
			(hatch none 0.5)
			(connect_pads
				(clearance 0)
			)
			(min_thickness 0.25)
			(keepout
				(tracks allowed)
				(vias not_allowed)
				(pads allowed)
				(copperpour not_allowed)
				(footprints allowed)
			)
			(placement
				(enabled no)
				(sheetname "")
			)
			(fill
				(thermal_gap 0.5)
				(thermal_bridge_width 0.5)
				(island_removal_mode 0)
			)
			(polygon
				(pts
					(xy 15.0876 -42.30243) (xy 15.6972 -42.30243) (xy 15.6972 -42.45483) (xy 15.0876 -42.45483)
				)
			)
		)
	)
	(footprint ""
		(layer "F.Cu")
		(at 1.500124 -68.09994 90)
		(property "Reference" "DS16"
			(at 4.16306 1.587246 90)
			(unlocked yes)
			(layer "F.SilkS")
			(effects
				(font
					(size 0.7874 0.5842)
					(thickness 0.1524)
				)
			)
		)
		(property "Value" ""
			(at 0 0 90)
			(layer "F.Fab")
			(effects
				(font
					(size 1.27 1.27)
				)
			)
		)
		(property "User Part Number" "PARTNUM*"
			(at 0.015494 4.486402 90)
			(unlocked yes)
			(layer "Cmts.User")
			(hide yes)
			(effects
				(font
					(size 0.7874 0.5842)
					(thickness 0.1524)
				)
			)
		)
		(property "Device Type" "LED_4P_V14-G170-10189-01"
			(at 0.015494 3.292602 90)
			(unlocked yes)
			(layer "F.Fab")
			(hide yes)
			(effects
				(font
					(size 0.7874 0.5842)
					(thickness 0.1524)
				)
			)
		)
		(duplicate_pad_numbers_are_jumpers no)
		(fp_line
			(start 1.378966 -0.829056)
			(end -1.378966 -0.829056)
			(stroke
				(width 0.1)
				(type default)
			)
			(layer "F.SilkS")
		)
		(fp_line
			(start -1.378966 -0.829056)
			(end -1.378966 -0.452628)
			(stroke
				(width 0.1)
				(type default)
			)
			(layer "F.SilkS")
		)
		(fp_line
			(start 1.998218 -0.452628)
			(end 1.378966 -0.452628)
			(stroke
				(width 0.1)
				(type default)
			)
			(layer "F.SilkS")
		)
		(fp_line
			(start 1.378966 -0.452628)
			(end 1.378966 -0.829056)
			(stroke
				(width 0.1)
				(type default)
			)
			(layer "F.SilkS")
		)
		(fp_line
			(start -1.378966 -0.452628)
			(end -1.998218 -0.452628)
			(stroke
				(width 0.1)
				(type default)
			)
			(layer "F.SilkS")
		)
		(fp_line
			(start -1.998218 -0.452628)
			(end -1.998218 1.103884)
			(stroke
				(width 0.1)
				(type default)
			)
			(layer "F.SilkS")
		)
		(fp_line
			(start 1.998218 1.103884)
			(end 1.998218 -0.452628)
			(stroke
				(width 0.1)
				(type default)
			)
			(layer "F.SilkS")
		)
		(fp_line
			(start -1.998218 1.103884)
			(end 1.998218 1.103884)
			(stroke
				(width 0.1)
				(type default)
			)
			(layer "F.SilkS")
		)
		(fp_poly
			(pts
				(xy 0.918464 -1.698498) (xy 1.223264 -1.46939) (xy 0.994664 -1.46939) (xy 0.994664 -1.24079) (xy 0.842264 -1.24079)
				(xy 0.842264 -1.46939) (xy 0.613664 -1.46939)
			)
			(stroke
				(width 0)
				(type default)
			)
			(fill yes)
			(layer "F.SilkS")
		)
		(fp_poly
			(pts
				(xy -0.73406 -1.677416) (xy -0.42926 -1.448308) (xy -0.65786 -1.448308) (xy -0.65786 -1.219708)
				(xy -0.81026 -1.219708) (xy -0.81026 -1.448308) (xy -1.03886 -1.448308)
			)
			(stroke
				(width 0)
				(type default)
			)
			(fill yes)
			(layer "F.SilkS")
		)
		(fp_poly
			(pts
				(xy -2.252218 1.357884) (xy -2.252218 -0.706628) (xy -1.632966 -0.706628) (xy -1.632966 -1.083056)
				(xy 1.632966 -1.083056) (xy 1.632966 -0.706628) (xy 2.252218 -0.706628) (xy 2.252218 1.357884)
			)
			(stroke
				(width 0)
				(type default)
			)
			(fill no)
			(layer "F.CrtYd")
		)
		(fp_line
			(start 1.124966 -0.575056)
			(end -1.124966 -0.575056)
			(stroke
				(width 0.1)
				(type default)
			)
			(layer "F.Fab")
		)
		(fp_line
			(start -1.124966 -0.575056)
			(end -1.124966 -0.075184)
			(stroke
				(width 0.1)
				(type default)
			)
			(layer "F.Fab")
		)
		(fp_line
			(start 1.325118 -0.075184)
			(end 1.124966 -0.075184)
			(stroke
				(width 0.1)
				(type default)
			)
			(layer "F.Fab")
		)
		(fp_line
			(start 1.124966 -0.075184)
			(end 1.124966 -0.575056)
			(stroke
				(width 0.1)
				(type default)
			)
			(layer "F.Fab")
		)
		(fp_line
			(start -1.124966 -0.075184)
			(end -1.325118 -0.075184)
			(stroke
				(width 0.1)
				(type default)
			)
			(layer "F.Fab")
		)
		(fp_line
			(start -1.325118 -0.075184)
			(end -1.325118 0.574802)
			(stroke
				(width 0.1)
				(type default)
			)
			(layer "F.Fab")
		)
		(fp_line
			(start 1.325118 0.574802)
			(end 1.325118 -0.075184)
			(stroke
				(width 0.1)
				(type default)
			)
			(layer "F.Fab")
		)
		(fp_line
			(start -1.325118 0.574802)
			(end 1.325118 0.574802)
			(stroke
				(width 0.1)
				(type default)
			)
			(layer "F.Fab")
		)
		(fp_poly
			(pts
				(xy 0.918464 -1.698498) (xy 1.223264 -1.46939) (xy 0.994664 -1.46939) (xy 0.994664 -1.24079) (xy 0.842264 -1.24079)
				(xy 0.842264 -1.46939) (xy 0.613664 -1.46939)
			)
			(stroke
				(width 0)
				(type default)
			)
			(fill yes)
			(layer "F.Fab")
		)
		(fp_poly
			(pts
				(xy -0.73406 -1.677416) (xy -0.42926 -1.448308) (xy -0.65786 -1.448308) (xy -0.65786 -1.219708)
				(xy -0.81026 -1.219708) (xy -0.81026 -1.448308) (xy -1.03886 -1.448308)
			)
			(stroke
				(width 0)
				(type default)
			)
			(fill yes)
			(layer "F.Fab")
		)
		(fp_text user "1"
			(at -2.37617 0.376936 90)
			(unlocked yes)
			(layer "F.SilkS")
			(effects
				(font
					(size 0.7874 0.5842)
					(thickness 0.1524)
				)
			)
		)
		(fp_text user "3"
			(at 0.69469 2.055876 0)
			(unlocked yes)
			(layer "F.SilkS")
			(effects
				(font
					(size 0.7874 0.5842)
					(thickness 0.1524)
				)
			)
		)
		(fp_text user "2"
			(at -0.44831 2.182876 0)
			(unlocked yes)
			(layer "F.SilkS")
			(effects
				(font
					(size 0.7874 0.5842)
					(thickness 0.1524)
				)
			)
		)
		(fp_text user "4"
			(at 1.77038 1.166876 0)
			(unlocked yes)
			(layer "F.Fab")
			(effects
				(font
					(size 0.7874 0.5842)
					(thickness 0.1524)
				)
			)
		)
		(fp_text user "3"
			(at 0.75438 1.166876 0)
			(unlocked yes)
			(layer "F.Fab")
			(effects
				(font
					(size 0.7874 0.5842)
					(thickness 0.1524)
				)
			)
		)
		(fp_text user "2"
			(at -0.38862 1.166876 0)
			(unlocked yes)
			(layer "F.Fab")
			(effects
				(font
					(size 0.7874 0.5842)
					(thickness 0.1524)
				)
			)
		)
		(fp_text user "1"
			(at -1.46431 1.293876 0)
			(unlocked yes)
			(layer "F.Fab")
			(effects
				(font
					(size 0.7874 0.5842)
					(thickness 0.1524)
				)
			)
		)
		(pad "1" smd rect
			(at -1.325118 0.245872 90)
			(size 0.8382 0.889)
			(layers "F.Cu" "F.Mask" "F.Paste")
			(net "UNNAMED_14_LED4PV14_I267_1")
		)
		(pad "2" smd rect
			(at -0.424942 0.595884 90)
			(size 0.4572 0.508)
			(layers "F.Cu" "F.Mask" "F.Paste")
			(net "XP3R3V_FPGA")
		)
		(pad "3" smd rect
			(at 0.424942 0.595884 90)
			(size 0.4572 0.508)
			(layers "F.Cu" "F.Mask" "F.Paste")
			(net "UNNAMED_14_LED4PV14_I267_3")
		)
		(pad "4" smd rect
			(at 1.325118 0.245872 90)
			(size 0.8382 0.889)
			(layers "F.Cu" "F.Mask" "F.Paste")
			(net "UNNAMED_14_LED4PV14_I267_4")
		)
	)
	(footprint ""
		(layer "F.Cu")
		(at 90.678 -59.9186 90)
		(property "Reference" "Y1"
			(at 2.4384 0.16637 90)
			(unlocked yes)
			(layer "F.SilkS")
			(effects
				(font
					(size 0.7874 0.5842)
					(thickness 0.1524)
				)
			)
		)
		(property "Value" "VAL*"
			(at -0.038862 5.168646 90)
			(unlocked yes)
			(layer "F.Fab")
			(hide yes)
			(effects
				(font
					(size 0.7874 0.5842)
					(thickness 0.1524)
				)
			)
		)
		(property "User Part Number" "PARTNUM*"
			(at 0 3.255264 90)
			(unlocked yes)
			(layer "Cmts.User")
			(hide yes)
			(effects
				(font
					(size 0.7874 0.5842)
					(thickness 0.1524)
				)
			)
		)
		(property "Device Type" "XTAL_2-G131-10075-01"
			(at 0 2.061464 90)
			(unlocked yes)
			(layer "F.Fab")
			(hide yes)
			(effects
				(font
					(size 0.7874 0.5842)
					(thickness 0.1524)
				)
			)
		)
		(property "Tolerance" "TOL*"
			(at -0.017272 4.188714 90)
			(unlocked yes)
			(layer "Cmts.User")
			(hide yes)
			(effects
				(font
					(size 0.7874 0.5842)
					(thickness 0.1524)
				)
			)
		)
		(duplicate_pad_numbers_are_jumpers no)
		(fp_line
			(start 1.347978 -0.9525)
			(end 1.347978 0.9525)
			(stroke
				(width 0.1)
				(type default)
			)
			(layer "F.SilkS")
		)
		(fp_line
			(start -1.347978 -0.9525)
			(end 1.347978 -0.9525)
			(stroke
				(width 0.1)
				(type default)
			)
			(layer "F.SilkS")
		)
		(fp_line
			(start 1.347978 0.9525)
			(end -1.347978 0.9525)
			(stroke
				(width 0.1)
				(type default)
			)
			(layer "F.SilkS")
		)
		(fp_line
			(start -1.347978 0.9525)
			(end -1.347978 -0.9525)
			(stroke
				(width 0.1)
				(type default)
			)
			(layer "F.SilkS")
		)
		(fp_rect
			(start -1.601978 -1.2065)
			(end 1.601978 1.2065)
			(stroke
				(width 0)
				(type default)
			)
			(fill no)
			(layer "F.CrtYd")
		)
		(fp_line
			(start 1.050036 -0.649986)
			(end 1.050036 0.649986)
			(stroke
				(width 0.1)
				(type default)
			)
			(layer "F.Fab")
		)
		(fp_line
			(start -1.050036 -0.649986)
			(end 1.050036 -0.649986)
			(stroke
				(width 0.1)
				(type default)
			)
			(layer "F.Fab")
		)
		(fp_line
			(start 1.050036 0.649986)
			(end -1.050036 0.649986)
			(stroke
				(width 0.1)
				(type default)
			)
			(layer "F.Fab")
		)
		(fp_line
			(start -1.050036 0.649986)
			(end -1.050036 -0.649986)
			(stroke
				(width 0.1)
				(type default)
			)
			(layer "F.Fab")
		)
		(pad "1" smd rect
			(at -0.674878 0 90)
			(size 0.8382 1.397)
			(layers "F.Cu" "F.Mask" "F.Paste")
			(net "UNNAMED_9_BNO080LGA28_I29_XOUT3")
		)
		(pad "2" smd rect
			(at 0.674878 0 90)
			(size 0.8382 1.397)
			(layers "F.Cu" "F.Mask" "F.Paste")
			(net "UNNAMED_9_CAPACITOR_I17_1")
		)
		(zone
			(layer "F.Cu")
			(hatch none 0.5)
			(connect_pads
				(clearance 0)
			)
			(min_thickness 0.25)
			(keepout
				(tracks allowed)
				(vias not_allowed)
				(pads allowed)
				(copperpour not_allowed)
				(footprints allowed)
			)
			(placement
				(enabled no)
				(sheetname "")
			)
			(fill
				(thermal_gap 0.5)
				(thermal_bridge_width 0.5)
				(island_removal_mode 0)
			)
			(polygon
				(pts
					(xy 90.028014 -59.662822) (xy 91.327986 -59.662822) (xy 91.327986 -60.174378) (xy 90.028014 -60.174378)
				)
			)
		)
	)
	(footprint ""
		(layer "F.Cu")
		(at 84.2772 -97.2058 180)
		(property "Reference" "C48"
			(at 4.3942 -5.67817 0)
			(unlocked yes)
			(layer "F.SilkS")
			(effects
				(font
					(size 0.7874 0.5842)
					(thickness 0.1524)
				)
			)
		)
		(property "Value" "VAL*"
			(at 0.0762 3.134106 180)
			(unlocked yes)
			(layer "F.Fab")
			(hide yes)
			(effects
				(font
					(size 0.7874 0.5842)
					(thickness 0.1524)
				)
			)
		)
		(property "Tolerance" "TOL*"
			(at 0.0762 4.048506 180)
			(unlocked yes)
			(layer "Cmts.User")
			(hide yes)
			(effects
				(font
					(size 0.7874 0.5842)
					(thickness 0.1524)
				)
			)
		)
		(property "User Part Number" "PARTNUM*"
			(at 0.1016 5.013706 180)
			(unlocked yes)
			(layer "Cmts.User")
			(hide yes)
			(effects
				(font
					(size 0.7874 0.5842)
					(thickness 0.1524)
				)
			)
		)
		(property "Device Type" "CAPACITOR-G107-0F106-EM,10UF,2A"
			(at 0.0508 2.194306 180)
			(unlocked yes)
			(layer "F.Fab")
			(hide yes)
			(effects
				(font
					(size 0.7874 0.5842)
					(thickness 0.1524)
				)
			)
		)
		(duplicate_pad_numbers_are_jumpers no)
		(fp_line
			(start 1.5748 0.9398)
			(end 1.5748 -0.9398)
			(stroke
				(width 0.1)
				(type default)
			)
			(layer "F.SilkS")
		)
		(fp_line
			(start 1.5748 -0.9398)
			(end -1.5748 -0.9398)
			(stroke
				(width 0.1)
				(type default)
			)
			(layer "F.SilkS")
		)
		(fp_line
			(start -1.5748 0.9398)
			(end 1.5748 0.9398)
			(stroke
				(width 0.1)
				(type default)
			)
			(layer "F.SilkS")
		)
		(fp_line
			(start -1.5748 -0.9398)
			(end -1.5748 0.9398)
			(stroke
				(width 0.1)
				(type default)
			)
			(layer "F.SilkS")
		)
		(fp_rect
			(start 1.5748 -0.9398)
			(end -1.5748 0.9398)
			(stroke
				(width 0)
				(type default)
			)
			(fill no)
			(layer "F.CrtYd")
		)
		(fp_line
			(start 1.016 0.635)
			(end 1.016 -0.635)
			(stroke
				(width 0.1)
				(type default)
			)
			(layer "F.Fab")
		)
		(fp_line
			(start 1.016 -0.635)
			(end -1.016 -0.635)
			(stroke
				(width 0.1)
				(type default)
			)
			(layer "F.Fab")
		)
		(fp_line
			(start -1.016 0.635)
			(end 1.016 0.635)
			(stroke
				(width 0.1)
				(type default)
			)
			(layer "F.Fab")
		)
		(fp_line
			(start -1.016 -0.635)
			(end -1.016 0.635)
			(stroke
				(width 0.1)
				(type default)
			)
			(layer "F.Fab")
		)
		(pad "1" smd rect
			(at -0.8382 0 180)
			(size 0.9652 1.3716)
			(layers "F.Cu" "F.Mask" "F.Paste")
			(net "VIN_XP3R3")
		)
		(pad "2" smd rect
			(at 0.8382 0 180)
			(size 0.9652 1.3716)
			(layers "F.Cu" "F.Mask" "F.Paste")
			(net "SG")
		)
		(zone
			(layer "F.Cu")
			(hatch none 0.5)
			(connect_pads
				(clearance 0)
			)
			(min_thickness 0.25)
			(keepout
				(tracks allowed)
				(vias not_allowed)
				(pads allowed)
				(copperpour not_allowed)
				(footprints allowed)
			)
			(placement
				(enabled no)
				(sheetname "")
			)
			(fill
				(thermal_gap 0.5)
				(thermal_bridge_width 0.5)
				(island_removal_mode 0)
			)
			(polygon
				(pts
					(xy 84.0486 -96.5708) (xy 84.5058 -96.5708) (xy 84.5058 -97.8408) (xy 84.0486 -97.8408)
				)
			)
		)
	)
	(footprint ""
		(layer "F.Cu")
		(at 155.4734 -71.501 90)
		(property "Reference" "J10"
			(at 7.07263 0.2286 0)
			(unlocked yes)
			(layer "F.SilkS")
			(effects
				(font
					(size 0.7874 0.5842)
					(thickness 0.1524)
				)
			)
		)
		(property "Value" ""
			(at 0 0 90)
			(layer "F.Fab")
			(effects
				(font
					(size 1.27 1.27)
				)
			)
		)
		(property "User Part Number" "PARTNUM*"
			(at 0.191262 6.403086 90)
			(unlocked yes)
			(layer "Cmts.User")
			(hide yes)
			(effects
				(font
					(size 0.7874 0.5842)
					(thickness 0.1524)
				)
			)
		)
		(property "Device Type" "G200_10283_01-G200-10283-01"
			(at 0.241808 5.437378 90)
			(unlocked yes)
			(layer "F.Fab")
			(hide yes)
			(effects
				(font
					(size 0.7874 0.5842)
					(thickness 0.1524)
				)
			)
		)
		(duplicate_pad_numbers_are_jumpers no)
		(fp_line
			(start 6.4008 -4.6355)
			(end 6.4008 4.6355)
			(stroke
				(width 0.1)
				(type default)
			)
			(layer "F.SilkS")
		)
		(fp_line
			(start -6.4008 -4.6355)
			(end 6.4008 -4.6355)
			(stroke
				(width 0.1)
				(type default)
			)
			(layer "F.SilkS")
		)
		(fp_line
			(start 6.4008 4.6355)
			(end -6.4008 4.6355)
			(stroke
				(width 0.1)
				(type default)
			)
			(layer "F.SilkS")
		)
		(fp_line
			(start -6.4008 4.6355)
			(end -6.4008 -4.6355)
			(stroke
				(width 0.1)
				(type default)
			)
			(layer "F.SilkS")
		)
		(fp_rect
			(start -6.6548 4.8895)
			(end 6.6548 -4.8895)
			(stroke
				(width 0)
				(type default)
			)
			(fill no)
			(layer "F.CrtYd")
		)
		(fp_line
			(start 5.386832 -3.7084)
			(end 5.386832 -2.436876)
			(stroke
				(width 0.1)
				(type default)
			)
			(layer "F.Fab")
		)
		(fp_line
			(start 4.746752 -3.7084)
			(end 5.386832 -3.7084)
			(stroke
				(width 0.1)
				(type default)
			)
			(layer "F.Fab")
		)
		(fp_line
			(start 2.872232 -3.7084)
			(end 2.872232 -2.436876)
			(stroke
				(width 0.1)
				(type default)
			)
			(layer "F.Fab")
		)
		(fp_line
			(start 2.232152 -3.7084)
			(end 2.872232 -3.7084)
			(stroke
				(width 0.1)
				(type default)
			)
			(layer "F.Fab")
		)
		(fp_line
			(start 0.306832 -3.7084)
			(end 0.306832 -2.436876)
			(stroke
				(width 0.1)
				(type default)
			)
			(layer "F.Fab")
		)
		(fp_line
			(start -0.333248 -3.7084)
			(end 0.306832 -3.7084)
			(stroke
				(width 0.1)
				(type default)
			)
			(layer "F.Fab")
		)
		(fp_line
			(start -2.233168 -3.7084)
			(end -2.233168 -2.436876)
			(stroke
				(width 0.1)
				(type default)
			)
			(layer "F.Fab")
		)
		(fp_line
			(start -2.873248 -3.7084)
			(end -2.233168 -3.7084)
			(stroke
				(width 0.1)
				(type default)
			)
			(layer "F.Fab")
		)
		(fp_line
			(start -4.773168 -3.7084)
			(end -4.773168 -2.436876)
			(stroke
				(width 0.1)
				(type default)
			)
			(layer "F.Fab")
		)
		(fp_line
			(start -5.413248 -3.7084)
			(end -4.773168 -3.7084)
			(stroke
				(width 0.1)
				(type default)
			)
			(layer "F.Fab")
		)
		(fp_line
			(start 6.145022 -2.4384)
			(end 6.145022 2.4384)
			(stroke
				(width 0.1)
				(type default)
			)
			(layer "F.Fab")
		)
		(fp_line
			(start -6.145022 -2.4384)
			(end 6.145022 -2.4384)
			(stroke
				(width 0.1)
				(type default)
			)
			(layer "F.Fab")
		)
		(fp_line
			(start 5.386832 -2.436876)
			(end 4.746752 -2.436876)
			(stroke
				(width 0.1)
				(type default)
			)
			(layer "F.Fab")
		)
		(fp_line
			(start 4.746752 -2.436876)
			(end 4.746752 -3.7084)
			(stroke
				(width 0.1)
				(type default)
			)
			(layer "F.Fab")
		)
		(fp_line
			(start 2.872232 -2.436876)
			(end 2.232152 -2.436876)
			(stroke
				(width 0.1)
				(type default)
			)
			(layer "F.Fab")
		)
		(fp_line
			(start 2.232152 -2.436876)
			(end 2.232152 -3.7084)
			(stroke
				(width 0.1)
				(type default)
			)
			(layer "F.Fab")
		)
		(fp_line
			(start 0.306832 -2.436876)
			(end -0.333248 -2.436876)
			(stroke
				(width 0.1)
				(type default)
			)
			(layer "F.Fab")
		)
		(fp_line
			(start -0.333248 -2.436876)
			(end -0.333248 -3.7084)
			(stroke
				(width 0.1)
				(type default)
			)
			(layer "F.Fab")
		)
		(fp_line
			(start -2.233168 -2.436876)
			(end -2.873248 -2.436876)
			(stroke
				(width 0.1)
				(type default)
			)
			(layer "F.Fab")
		)
		(fp_line
			(start -2.873248 -2.436876)
			(end -2.873248 -3.7084)
			(stroke
				(width 0.1)
				(type default)
			)
			(layer "F.Fab")
		)
		(fp_line
			(start -4.773168 -2.436876)
			(end -5.413248 -2.436876)
			(stroke
				(width 0.1)
				(type default)
			)
			(layer "F.Fab")
		)
		(fp_line
			(start -5.413248 -2.436876)
			(end -5.413248 -3.7084)
			(stroke
				(width 0.1)
				(type default)
			)
			(layer "F.Fab")
		)
		(fp_line
			(start 6.145022 2.4384)
			(end -6.145022 2.4384)
			(stroke
				(width 0.1)
				(type default)
			)
			(layer "F.Fab")
		)
		(fp_line
			(start 5.386832 2.4384)
			(end 5.386832 3.709924)
			(stroke
				(width 0.1)
				(type default)
			)
			(layer "F.Fab")
		)
		(fp_line
			(start 4.746752 2.4384)
			(end 5.386832 2.4384)
			(stroke
				(width 0.1)
				(type default)
			)
			(layer "F.Fab")
		)
		(fp_line
			(start 2.846832 2.4384)
			(end 2.846832 3.709924)
			(stroke
				(width 0.1)
				(type default)
			)
			(layer "F.Fab")
		)
		(fp_line
			(start 2.206752 2.4384)
			(end 2.846832 2.4384)
			(stroke
				(width 0.1)
				(type default)
			)
			(layer "F.Fab")
		)
		(fp_line
			(start 0.306832 2.4384)
			(end 0.306832 3.709924)
			(stroke
				(width 0.1)
				(type default)
			)
			(layer "F.Fab")
		)
		(fp_line
			(start -0.333248 2.4384)
			(end 0.306832 2.4384)
			(stroke
				(width 0.1)
				(type default)
			)
			(layer "F.Fab")
		)
		(fp_line
			(start -2.233168 2.4384)
			(end -2.233168 3.709924)
			(stroke
				(width 0.1)
				(type default)
			)
			(layer "F.Fab")
		)
		(fp_line
			(start -2.873248 2.4384)
			(end -2.233168 2.4384)
			(stroke
				(width 0.1)
				(type default)
			)
			(layer "F.Fab")
		)
		(fp_line
			(start -4.747768 2.4384)
			(end -4.747768 3.709924)
			(stroke
				(width 0.1)
				(type default)
			)
			(layer "F.Fab")
		)
		(fp_line
			(start -5.387848 2.4384)
			(end -4.747768 2.4384)
			(stroke
				(width 0.1)
				(type default)
			)
			(layer "F.Fab")
		)
		(fp_line
			(start -6.145022 2.4384)
			(end -6.145022 -2.4384)
			(stroke
				(width 0.1)
				(type default)
			)
			(layer "F.Fab")
		)
		(fp_line
			(start 5.386832 3.709924)
			(end 4.746752 3.709924)
			(stroke
				(width 0.1)
				(type default)
			)
			(layer "F.Fab")
		)
		(fp_line
			(start 4.746752 3.709924)
			(end 4.746752 2.4384)
			(stroke
				(width 0.1)
				(type default)
			)
			(layer "F.Fab")
		)
		(fp_line
			(start 2.846832 3.709924)
			(end 2.206752 3.709924)
			(stroke
				(width 0.1)
				(type default)
			)
			(layer "F.Fab")
		)
		(fp_line
			(start 2.206752 3.709924)
			(end 2.206752 2.4384)
			(stroke
				(width 0.1)
				(type default)
			)
			(layer "F.Fab")
		)
		(fp_line
			(start 0.306832 3.709924)
			(end -0.333248 3.709924)
			(stroke
				(width 0.1)
				(type default)
			)
			(layer "F.Fab")
		)
		(fp_line
			(start -0.333248 3.709924)
			(end -0.333248 2.4384)
			(stroke
				(width 0.1)
				(type default)
			)
			(layer "F.Fab")
		)
		(fp_line
			(start -2.233168 3.709924)
			(end -2.873248 3.709924)
			(stroke
				(width 0.1)
				(type default)
			)
			(layer "F.Fab")
		)
		(fp_line
			(start -2.873248 3.709924)
			(end -2.873248 2.4384)
			(stroke
				(width 0.1)
				(type default)
			)
			(layer "F.Fab")
		)
		(fp_line
			(start -4.747768 3.709924)
			(end -5.387848 3.709924)
			(stroke
				(width 0.1)
				(type default)
			)
			(layer "F.Fab")
		)
		(fp_line
			(start -5.387848 3.709924)
			(end -5.387848 2.4384)
			(stroke
				(width 0.1)
				(type default)
			)
			(layer "F.Fab")
		)
		(fp_text user "10"
			(at 6.223 -5.57403 90)
			(unlocked yes)
			(layer "F.SilkS")
			(effects
				(font
					(size 0.7874 0.5842)
					(thickness 0.1524)
				)
			)
		)
		(fp_text user "2"
			(at -5.88137 -5.2324 0)
			(unlocked yes)
			(layer "F.SilkS")
			(effects
				(font
					(size 0.7874 0.5842)
					(thickness 0.1524)
				)
			)
		)
		(fp_text user "1"
			(at -5.37337 5.3086 0)
			(unlocked yes)
			(layer "F.SilkS")
			(effects
				(font
					(size 0.7874 0.5842)
					(thickness 0.1524)
				)
			)
		)
		(fp_text user "9"
			(at 6.05663 5.4356 0)
			(unlocked yes)
			(layer "F.SilkS")
			(effects
				(font
					(size 0.7874 0.5842)
					(thickness 0.1524)
				)
			)
		)
		(fp_text user "10"
			(at 5.18033 -5.2324 0)
			(unlocked yes)
			(layer "F.Fab")
			(effects
				(font
					(size 0.7874 0.5842)
					(thickness 0.1524)
				)
			)
		)
		(fp_text user "2"
			(at -5.37337 -4.8514 0)
			(unlocked yes)
			(layer "F.Fab")
			(effects
				(font
					(size 0.7874 0.5842)
					(thickness 0.1524)
				)
			)
		)
		(fp_text user "9"
			(at 5.16763 5.0546 0)
			(unlocked yes)
			(layer "F.Fab")
			(effects
				(font
					(size 0.7874 0.5842)
					(thickness 0.1524)
				)
			)
		)
		(fp_text user "1"
			(at -5.37337 5.0546 0)
			(unlocked yes)
			(layer "F.Fab")
			(effects
				(font
					(size 0.7874 0.5842)
					(thickness 0.1524)
				)
			)
		)
		(pad "1" smd rect
			(at -5.08 2.605024 90)
			(size 1.27 3.556)
			(layers "F.Cu" "F.Mask" "F.Paste")
			(net "FT4232_CHD_TX")
		)
		(pad "2" smd rect
			(at -5.08 -2.605024 90)
			(size 1.27 3.556)
			(layers "F.Cu" "F.Mask" "F.Paste")
			(net "DBG_UART_MAC_RX")
		)
		(pad "3" smd rect
			(at -2.54 2.605024 90)
			(size 1.27 3.556)
			(layers "F.Cu" "F.Mask" "F.Paste")
			(net "FT4232_CHD_TX")
		)
		(pad "4" smd rect
			(at -2.54 -2.605024 90)
			(size 1.27 3.556)
			(layers "F.Cu" "F.Mask" "F.Paste")
			(net "DBG_UART_GPS_RXD")
		)
		(pad "5" smd rect
			(at 0 2.605024 90)
			(size 1.27 3.556)
			(layers "F.Cu" "F.Mask" "F.Paste")
			(net "FT4232_CHD_RX")
		)
		(pad "6" smd rect
			(at 0 -2.605024 90)
			(size 1.27 3.556)
			(layers "F.Cu" "F.Mask" "F.Paste")
			(net "DBG_UART_MAC_TX")
		)
		(pad "7" smd rect
			(at 2.54 2.605024 90)
			(size 1.27 3.556)
			(layers "F.Cu" "F.Mask" "F.Paste")
			(net "FT4232_CHD_RX")
		)
		(pad "8" smd rect
			(at 2.54 -2.605024 90)
			(size 1.27 3.556)
			(layers "F.Cu" "F.Mask" "F.Paste")
			(net "DBG_UART_GPS_TXD")
		)
		(pad "9" smd rect
			(at 5.08 2.605024 90)
			(size 1.27 3.556)
			(layers "F.Cu" "F.Mask" "F.Paste")
			(net "SG")
		)
		(pad "10" smd rect
			(at 5.08 -2.605024 90)
			(size 1.27 3.556)
			(layers "F.Cu" "F.Mask" "F.Paste")
			(net "FPGA_CFG_INIT_N")
		)
		(zone
			(layer "F.Cu")
			(hatch none 0.5)
			(connect_pads
				(clearance 0)
			)
			(min_thickness 0.25)
			(keepout
				(tracks not_allowed)
				(vias allowed)
				(pads allowed)
				(copperpour not_allowed)
				(footprints allowed)
			)
			(placement
				(enabled no)
				(sheetname "")
			)
			(fill
				(thermal_gap 0.5)
				(thermal_bridge_width 0.5)
				(island_removal_mode 0)
			)
			(polygon
				(pts
					(xy 156.2862 -65.789302) (xy 156.2862 -77.219302) (xy 154.6606 -77.219302) (xy 154.6606 -65.789302)
				)
			)
		)
		(zone
			(layer "F.Cu")
			(hatch none 0.5)
			(connect_pads
				(clearance 0)
			)
			(min_thickness 0.25)
			(keepout
				(tracks allowed)
				(vias not_allowed)
				(pads allowed)
				(copperpour not_allowed)
				(footprints allowed)
			)
			(placement
				(enabled no)
				(sheetname "")
			)
			(fill
				(thermal_gap 0.5)
				(thermal_bridge_width 0.5)
				(island_removal_mode 0)
			)
			(polygon
				(pts
					(xy 156.2862 -65.789302) (xy 156.2862 -77.219302) (xy 154.6606 -77.219302) (xy 154.6606 -65.789302)
				)
			)
		)
	)
	(footprint ""
		(layer "F.Cu")
		(at 111.887 -96.266)
		(property "Reference" "C89"
			(at 2.794 0.16637 0)
			(unlocked yes)
			(layer "F.SilkS")
			(effects
				(font
					(size 0.7874 0.5842)
					(thickness 0.1524)
				)
			)
		)
		(property "Value" "VAL*"
			(at 0.0762 2.067306 0)
			(unlocked yes)
			(layer "F.Fab")
			(hide yes)
			(effects
				(font
					(size 0.7874 0.5842)
					(thickness 0.1524)
				)
			)
		)
		(property "Tolerance" "TOL*"
			(at 0.0762 3.032506 0)
			(unlocked yes)
			(layer "Cmts.User")
			(hide yes)
			(effects
				(font
					(size 0.7874 0.5842)
					(thickness 0.1524)
				)
			)
		)
		(property "User Part Number" "PARTNUM*"
			(at 0.1016 4.023106 0)
			(unlocked yes)
			(layer "Cmts.User")
			(hide yes)
			(effects
				(font
					(size 0.7874 0.5842)
					(thickness 0.1524)
				)
			)
		)
		(property "Device Type" "CAPACITOR-G105-0B104-EK,0.1UF,A"
			(at 0.0508 1.127506 0)
			(unlocked yes)
			(layer "F.Fab")
			(hide yes)
			(effects
				(font
					(size 0.7874 0.5842)
					(thickness 0.1524)
				)
			)
		)
		(duplicate_pad_numbers_are_jumpers no)
		(fp_line
			(start -1.143 -0.5588)
			(end -1.143 0.5588)
			(stroke
				(width 0.1)
				(type default)
			)
			(layer "F.SilkS")
		)
		(fp_line
			(start -1.143 0.5588)
			(end 1.143 0.5588)
			(stroke
				(width 0.1)
				(type default)
			)
			(layer "F.SilkS")
		)
		(fp_line
			(start 1.143 -0.5588)
			(end -1.143 -0.5588)
			(stroke
				(width 0.1)
				(type default)
			)
			(layer "F.SilkS")
		)
		(fp_line
			(start 1.143 0.5588)
			(end 1.143 -0.5588)
			(stroke
				(width 0.1)
				(type default)
			)
			(layer "F.SilkS")
		)
		(fp_rect
			(start 1.143 -0.5588)
			(end -1.143 0.5588)
			(stroke
				(width 0)
				(type default)
			)
			(fill no)
			(layer "F.CrtYd")
		)
		(fp_line
			(start -0.508 -0.3048)
			(end -0.508 0.3048)
			(stroke
				(width 0.1)
				(type default)
			)
			(layer "F.Fab")
		)
		(fp_line
			(start -0.508 0.3048)
			(end 0.508 0.3048)
			(stroke
				(width 0.1)
				(type default)
			)
			(layer "F.Fab")
		)
		(fp_line
			(start 0.508 -0.3048)
			(end -0.508 -0.3048)
			(stroke
				(width 0.1)
				(type default)
			)
			(layer "F.Fab")
		)
		(fp_line
			(start 0.508 0.3048)
			(end 0.508 -0.3048)
			(stroke
				(width 0.1)
				(type default)
			)
			(layer "F.Fab")
		)
		(pad "1" smd rect
			(at -0.5334 0)
			(size 0.7112 0.6096)
			(layers "F.Cu" "F.Mask" "F.Paste")
			(net "XP3R3V_FPGA")
		)
		(pad "2" smd rect
			(at 0.5334 0)
			(size 0.7112 0.6096)
			(layers "F.Cu" "F.Mask" "F.Paste")
			(net "SG")
		)
		(zone
			(layer "F.Cu")
			(hatch none 0.5)
			(connect_pads
				(clearance 0)
			)
			(min_thickness 0.25)
			(keepout
				(tracks allowed)
				(vias not_allowed)
				(pads allowed)
				(copperpour not_allowed)
				(footprints allowed)
			)
			(placement
				(enabled no)
				(sheetname "")
			)
			(fill
				(thermal_gap 0.5)
				(thermal_bridge_width 0.5)
				(island_removal_mode 0)
			)
			(polygon
				(pts
					(xy 111.9632 -96.5708) (xy 111.8108 -96.5708) (xy 111.8108 -95.9612) (xy 111.9632 -95.9612)
				)
			)
		)
	)
	(footprint ""
		(layer "F.Cu")
		(at 132.334 -43.815)
		(property "Reference" "L12"
			(at -1.0795 -1.23063 0)
			(unlocked yes)
			(layer "F.SilkS")
			(effects
				(font
					(size 0.7874 0.5842)
					(thickness 0.1524)
				)
				(justify left)
			)
		)
		(property "Value" "VAL*"
			(at -0.9398 3.70967 0)
			(unlocked yes)
			(layer "F.Fab")
			(hide yes)
			(effects
				(font
					(size 0.7874 0.5842)
					(thickness 0.1524)
				)
				(justify left)
			)
		)
		(property "Tolerance" "TOL*"
			(at -0.9906 5.00507 0)
			(unlocked yes)
			(layer "Cmts.User")
			(hide yes)
			(effects
				(font
					(size 0.7874 0.5842)
					(thickness 0.1524)
				)
				(justify left)
			)
		)
		(property "User Part Number" "PARTNUM*"
			(at -2.54 2.46507 0)
			(unlocked yes)
			(layer "Cmts.User")
			(hide yes)
			(effects
				(font
					(size 0.7874 0.5842)
					(thickness 0.1524)
				)
				(justify left)
			)
		)
		(property "Device Type" "FERRITEBEAD-G191-10100-01,120OA"
			(at -0.9906 1.22047 0)
			(unlocked yes)
			(layer "F.Fab")
			(hide yes)
			(effects
				(font
					(size 0.7874 0.5842)
					(thickness 0.1524)
				)
				(justify left)
			)
		)
		(duplicate_pad_numbers_are_jumpers no)
		(fp_line
			(start -1.3208 -0.7112)
			(end 1.3208 -0.7112)
			(stroke
				(width 0.1)
				(type default)
			)
			(layer "F.SilkS")
		)
		(fp_line
			(start -1.3208 0.7112)
			(end -1.3208 -0.7112)
			(stroke
				(width 0.1)
				(type default)
			)
			(layer "F.SilkS")
		)
		(fp_line
			(start 1.3208 -0.7112)
			(end 1.3208 0.7112)
			(stroke
				(width 0.1)
				(type default)
			)
			(layer "F.SilkS")
		)
		(fp_line
			(start 1.3208 0.7112)
			(end -1.3208 0.7112)
			(stroke
				(width 0.1)
				(type default)
			)
			(layer "F.SilkS")
		)
		(fp_rect
			(start -1.3208 0.7112)
			(end 1.3208 -0.7112)
			(stroke
				(width 0)
				(type default)
			)
			(fill no)
			(layer "F.CrtYd")
		)
		(fp_line
			(start -0.8128 -0.4572)
			(end 0.8128 -0.4572)
			(stroke
				(width 0.1)
				(type default)
			)
			(layer "F.Fab")
		)
		(fp_line
			(start -0.8128 0.4572)
			(end -0.8128 -0.4572)
			(stroke
				(width 0.1)
				(type default)
			)
			(layer "F.Fab")
		)
		(fp_line
			(start 0.8128 -0.4572)
			(end 0.8128 0.4572)
			(stroke
				(width 0.1)
				(type default)
			)
			(layer "F.Fab")
		)
		(fp_line
			(start 0.8128 0.4572)
			(end -0.8128 0.4572)
			(stroke
				(width 0.1)
				(type default)
			)
			(layer "F.Fab")
		)
		(pad "1" smd rect
			(at -0.6858 0)
			(size 0.762 0.8636)
			(layers "F.Cu" "F.Mask" "F.Paste")
			(net "XP1R0V_FPGA_VCCINT")
		)
		(pad "2" smd rect
			(at 0.6858 0)
			(size 0.762 0.8636)
			(layers "F.Cu" "F.Mask" "F.Paste")
			(net "XP1R0V_FPGA")
		)
		(zone
			(layer "F.Cu")
			(hatch none 0.5)
			(connect_pads
				(clearance 0)
			)
			(min_thickness 0.25)
			(keepout
				(tracks allowed)
				(vias not_allowed)
				(pads allowed)
				(copperpour not_allowed)
				(footprints allowed)
			)
			(placement
				(enabled no)
				(sheetname "")
			)
			(fill
				(thermal_gap 0.5)
				(thermal_bridge_width 0.5)
				(island_removal_mode 0)
			)
			(polygon
				(pts
					(xy 132.1816 -43.3578) (xy 132.4864 -43.3578) (xy 132.4864 -44.2722) (xy 132.1816 -44.2722)
				)
			)
		)
		(zone
			(layer "F.Cu")
			(hatch none 0.5)
			(connect_pads
				(clearance 0)
			)
			(min_thickness 0.25)
			(keepout
				(tracks not_allowed)
				(vias allowed)
				(pads allowed)
				(copperpour not_allowed)
				(footprints allowed)
			)
			(placement
				(enabled no)
				(sheetname "")
			)
			(fill
				(thermal_gap 0.5)
				(thermal_bridge_width 0.5)
				(island_removal_mode 0)
			)
			(polygon
				(pts
					(xy 132.1816 -43.3578) (xy 132.4864 -43.3578) (xy 132.4864 -44.2722) (xy 132.1816 -44.2722)
				)
			)
		)
	)
	(footprint ""
		(layer "F.Cu")
		(at 57.404 -126.873)
		(property "Reference" "SP57"
			(at 0 0 0)
			(layer "F.SilkS")
			(hide yes)
			(effects
				(font
					(size 1.27 1.27)
				)
			)
		)
		(property "Value" ""
			(at 0 0 0)
			(layer "F.Fab")
			(effects
				(font
					(size 1.27 1.27)
				)
			)
		)
		(duplicate_pad_numbers_are_jumpers no)
	)
	(footprint ""
		(layer "F.Cu")
		(at 48.26 -126.238)
		(property "Reference" "SP26"
			(at 0 0 0)
			(layer "F.SilkS")
			(hide yes)
			(effects
				(font
					(size 1.27 1.27)
				)
			)
		)
		(property "Value" ""
			(at 0 0 0)
			(layer "F.Fab")
			(effects
				(font
					(size 1.27 1.27)
				)
			)
		)
		(duplicate_pad_numbers_are_jumpers no)
	)
	(footprint ""
		(layer "F.Cu")
		(at 57.47512 -82.9564 90)
		(property "Reference" "R406"
			(at 0.2286 1.11125 90)
			(unlocked yes)
			(layer "F.SilkS")
			(effects
				(font
					(size 0.7874 0.5842)
					(thickness 0.1524)
				)
			)
		)
		(property "Value" "VAL*"
			(at 0.02032 2.13233 90)
			(unlocked yes)
			(layer "F.Fab")
			(hide yes)
			(effects
				(font
					(size 0.7874 0.5842)
					(thickness 0.1524)
				)
			)
		)
		(property "Device Type" "RESISTOR-G155-133R0-01,33OHM,1%"
			(at 0.008382 1.210564 90)
			(unlocked yes)
			(layer "F.Fab")
			(hide yes)
			(effects
				(font
					(size 0.7874 0.5842)
					(thickness 0.1524)
				)
			)
		)
		(property "User Part Number" "PARTNUM*"
			(at 0.02032 4.024884 90)
			(unlocked yes)
			(layer "Cmts.User")
			(hide yes)
			(effects
				(font
					(size 0.7874 0.5842)
					(thickness 0.1524)
				)
			)
		)
		(property "Tolerance" "TOL*"
			(at 0.044704 3.05435 90)
			(unlocked yes)
			(layer "Cmts.User")
			(hide yes)
			(effects
				(font
					(size 0.7874 0.5842)
					(thickness 0.1524)
				)
			)
		)
		(duplicate_pad_numbers_are_jumpers no)
		(fp_line
			(start 1.143 -0.5588)
			(end -1.143 -0.5588)
			(stroke
				(width 0.1)
				(type default)
			)
			(layer "F.SilkS")
		)
		(fp_line
			(start -1.143 -0.5588)
			(end -1.143 0.5588)
			(stroke
				(width 0.1)
				(type default)
			)
			(layer "F.SilkS")
		)
		(fp_line
			(start 1.143 0.5588)
			(end 1.143 -0.5588)
			(stroke
				(width 0.1)
				(type default)
			)
			(layer "F.SilkS")
		)
		(fp_line
			(start -1.143 0.5588)
			(end 1.143 0.5588)
			(stroke
				(width 0.1)
				(type default)
			)
			(layer "F.SilkS")
		)
		(fp_rect
			(start -1.143 0.5588)
			(end 1.143 -0.5588)
			(stroke
				(width 0)
				(type default)
			)
			(fill no)
			(layer "F.CrtYd")
		)
		(fp_line
			(start 0.508 -0.3048)
			(end -0.508 -0.3048)
			(stroke
				(width 0.1)
				(type default)
			)
			(layer "F.Fab")
		)
		(fp_line
			(start -0.508 -0.3048)
			(end -0.508 0.3048)
			(stroke
				(width 0.1)
				(type default)
			)
			(layer "F.Fab")
		)
		(fp_line
			(start 0.508 0.3048)
			(end 0.508 -0.3048)
			(stroke
				(width 0.1)
				(type default)
			)
			(layer "F.Fab")
		)
		(fp_line
			(start -0.508 0.3048)
			(end 0.508 0.3048)
			(stroke
				(width 0.1)
				(type default)
			)
			(layer "F.Fab")
		)
		(pad "1" smd rect
			(at -0.5334 0 90)
			(size 0.7112 0.6096)
			(layers "F.Cu" "F.Mask" "F.Paste")
			(net "LM75B_I2C_SDA")
		)
		(pad "2" smd rect
			(at 0.5334 0 90)
			(size 0.7112 0.6096)
			(layers "F.Cu" "F.Mask" "F.Paste")
			(net "R_LM75B_2_I2C_SDA")
		)
		(zone
			(layer "F.Cu")
			(hatch none 0.5)
			(connect_pads
				(clearance 0)
			)
			(min_thickness 0.25)
			(keepout
				(tracks allowed)
				(vias not_allowed)
				(pads allowed)
				(copperpour not_allowed)
				(footprints allowed)
			)
			(placement
				(enabled no)
				(sheetname "")
			)
			(fill
				(thermal_gap 0.5)
				(thermal_bridge_width 0.5)
				(island_removal_mode 0)
			)
			(polygon
				(pts
					(xy 57.77992 -82.8802) (xy 57.77992 -83.0326) (xy 57.17032 -83.0326) (xy 57.17032 -82.8802)
				)
			)
		)
		(zone
			(layer "F.Cu")
			(hatch none 0.5)
			(connect_pads
				(clearance 0)
			)
			(min_thickness 0.25)
			(keepout
				(tracks not_allowed)
				(vias allowed)
				(pads allowed)
				(copperpour not_allowed)
				(footprints allowed)
			)
			(placement
				(enabled no)
				(sheetname "")
			)
			(fill
				(thermal_gap 0.5)
				(thermal_bridge_width 0.5)
				(island_removal_mode 0)
			)
			(polygon
				(pts
					(xy 57.77992 -82.8802) (xy 57.77992 -83.0326) (xy 57.17032 -83.0326) (xy 57.17032 -82.8802)
				)
			)
		)
	)
	(footprint ""
		(layer "F.Cu")
		(at 64.507618 -23.734522)
		(property "Reference" "MAC_PIN8"
			(at -3.936238 2.580132 0)
			(unlocked yes)
			(layer "F.SilkS")
			(effects
				(font
					(size 0.7874 0.5842)
					(thickness 0.1524)
				)
			)
		)
		(property "Value" ""
			(at 0 0 0)
			(layer "F.Fab")
			(effects
				(font
					(size 1.27 1.27)
				)
			)
		)
		(property "Device Type" "NUT-A200-00029-FB"
			(at 0 2.632964 0)
			(unlocked yes)
			(layer "F.Fab")
			(hide yes)
			(effects
				(font
					(size 0.7874 0.5842)
					(thickness 0.1524)
				)
			)
		)
		(property "User Part Number" "PARTNUM*"
			(at 0 3.826764 0)
			(unlocked yes)
			(layer "Cmts.User")
			(hide yes)
			(effects
				(font
					(size 0.7874 0.5842)
					(thickness 0.1524)
				)
			)
		)
		(duplicate_pad_numbers_are_jumpers no)
		(fp_circle
			(center 0 0)
			(end 1.524 0)
			(stroke
				(width 0.1)
				(type default)
			)
			(fill no)
			(layer "F.SilkS")
		)
		(fp_poly
			(pts
				(arc
					(start -1.260856 -0.1524)
					(mid -0.898049 -0.898049)
					(end -0.1524 -1.260856)
				)
				(arc
					(start -0.1524 -0.991616)
					(mid -0.709411 -0.709411)
					(end -0.991616 -0.1524)
				)
			)
			(stroke
				(width 0)
				(type default)
			)
			(fill yes)
			(layer "F.Paste")
		)
		(fp_poly
			(pts
				(arc
					(start -0.1524 1.260856)
					(mid -0.898049 0.898049)
					(end -1.260856 0.1524)
				)
				(arc
					(start -0.991616 0.1524)
					(mid -0.709411 0.709411)
					(end -0.1524 0.991616)
				)
			)
			(stroke
				(width 0)
				(type default)
			)
			(fill yes)
			(layer "F.Paste")
		)
		(fp_poly
			(pts
				(arc
					(start 0.1524 -1.260856)
					(mid 0.898049 -0.898049)
					(end 1.260856 -0.1524)
				)
				(arc
					(start 0.991616 -0.1524)
					(mid 0.709411 -0.709411)
					(end 0.1524 -0.991616)
				)
			)
			(stroke
				(width 0)
				(type default)
			)
			(fill yes)
			(layer "F.Paste")
		)
		(fp_poly
			(pts
				(arc
					(start 1.260856 0.1524)
					(mid 0.898049 0.898049)
					(end 0.1524 1.260856)
				)
				(arc
					(start 0.1524 0.991616)
					(mid 0.709411 0.709411)
					(end 0.991616 0.1524)
				)
			)
			(stroke
				(width 0)
				(type default)
			)
			(fill yes)
			(layer "F.Paste")
		)
		(fp_poly
			(pts
				(arc
					(start 6.35 0)
					(mid -6.35 0)
					(end 6.35 0)
				)
			)
			(stroke
				(width 0)
				(type default)
			)
			(fill no)
			(layer "B.CrtYd")
		)
		(fp_poly
			(pts
				(arc
					(start 1.778 0)
					(mid -1.778 0)
					(end 1.778 0)
				)
			)
			(stroke
				(width 0)
				(type default)
			)
			(fill no)
			(layer "F.CrtYd")
		)
		(fp_circle
			(center 0 0)
			(end 1.1684 0)
			(stroke
				(width 0.1)
				(type default)
			)
			(fill no)
			(layer "F.Fab")
		)
		(pad "1" thru_hole circle
			(at 0 0)
			(size 2.54 2.54)
			(drill 2.0066)
			(layers "*.Cu" "*.Mask")
			(remove_unused_layers no)
			(net "R_MAC_UART_RX_FPGA_TX")
			(thermal_gap 0.0254)
			(padstack
				(mode front_inner_back)
				(layer "Inner"
					(shape circle)
					(size 2.54 2.54)
					(clearance 0.0254)
				)
				(layer "B.Cu"
					(shape circle)
					(size 2.54 2.54)
				)
			)
		)
	)
	(footprint ""
		(layer "F.Cu")
		(at 146.431 -24.892)
		(property "Reference" "TP41"
			(at -0.7112 0.92837 0)
			(unlocked yes)
			(layer "F.SilkS")
			(effects
				(font
					(size 0.7874 0.5842)
					(thickness 0.1524)
				)
				(justify left)
			)
		)
		(property "Value" ""
			(at 0 0 0)
			(layer "F.Fab")
			(effects
				(font
					(size 1.27 1.27)
				)
			)
		)
		(property "Device Type" "TP_PIONT-TP010CT020B030_PTH-TPA"
			(at -1.341882 0.996696 0)
			(unlocked yes)
			(layer "F.Fab")
			(hide yes)
			(effects
				(font
					(size 0.7874 0.5842)
					(thickness 0.000001)
				)
				(justify left)
			)
		)
		(duplicate_pad_numbers_are_jumpers no)
		(fp_poly
			(pts
				(arc
					(start 0.889 0)
					(mid -0.889 0)
					(end 0.889 0)
				)
			)
			(stroke
				(width 0)
				(type default)
			)
			(fill no)
			(layer "B.CrtYd")
		)
		(fp_poly
			(pts
				(arc
					(start 0.889 0)
					(mid -0.889 0)
					(end 0.889 0)
				)
			)
			(stroke
				(width 0)
				(type default)
			)
			(fill no)
			(layer "F.CrtYd")
		)
		(pad "1" thru_hole circle
			(at 0 0)
			(size 0.508 0.508)
			(drill 0.254)
			(layers "*.Cu" "*.Mask")
			(remove_unused_layers no)
			(net "XP1R8V_FPGA_PG")
			(clearance 0.1016)
			(padstack
				(mode front_inner_back)
				(layer "Inner"
					(shape circle)
					(size 0.508 0.508)
					(clearance 0.1016)
				)
				(layer "B.Cu"
					(shape circle)
					(size 0.762 0.762)
					(clearance -0.0254)
				)
			)
		)
	)
	(footprint ""
		(layer "F.Cu")
		(at 110.236 -88.265 -90)
		(property "Reference" "R443"
			(at 2.794 -0.16637 90)
			(unlocked yes)
			(layer "F.SilkS")
			(effects
				(font
					(size 0.7874 0.5842)
					(thickness 0.1524)
				)
			)
		)
		(property "Value" "VAL*"
			(at 0.02032 2.13233 270)
			(unlocked yes)
			(layer "F.Fab")
			(hide yes)
			(effects
				(font
					(size 0.7874 0.5842)
					(thickness 0.1524)
				)
			)
		)
		(property "Tolerance" "TOL*"
			(at 0.044704 3.05435 270)
			(unlocked yes)
			(layer "Cmts.User")
			(hide yes)
			(effects
				(font
					(size 0.7874 0.5842)
					(thickness 0.1524)
				)
			)
		)
		(property "User Part Number" "PARTNUM*"
			(at 0.02032 4.024884 270)
			(unlocked yes)
			(layer "Cmts.User")
			(hide yes)
			(effects
				(font
					(size 0.7874 0.5842)
					(thickness 0.1524)
				)
			)
		)
		(property "Device Type" "RESISTOR-G155-11000-01,100OHM,A"
			(at 0.008382 1.210564 270)
			(unlocked yes)
			(layer "F.Fab")
			(hide yes)
			(effects
				(font
					(size 0.7874 0.5842)
					(thickness 0.1524)
				)
			)
		)
		(duplicate_pad_numbers_are_jumpers no)
		(fp_line
			(start -1.143 0.5588)
			(end 1.143 0.5588)
			(stroke
				(width 0.1)
				(type default)
			)
			(layer "F.SilkS")
		)
		(fp_line
			(start 1.143 0.5588)
			(end 1.143 -0.5588)
			(stroke
				(width 0.1)
				(type default)
			)
			(layer "F.SilkS")
		)
		(fp_line
			(start -1.143 -0.5588)
			(end -1.143 0.5588)
			(stroke
				(width 0.1)
				(type default)
			)
			(layer "F.SilkS")
		)
		(fp_line
			(start 1.143 -0.5588)
			(end -1.143 -0.5588)
			(stroke
				(width 0.1)
				(type default)
			)
			(layer "F.SilkS")
		)
		(fp_poly
			(pts
				(xy -1.143 0.5588) (xy 1.143 0.5588) (xy 1.143 -0.5588) (xy -1.143 -0.5588)
			)
			(stroke
				(width 0)
				(type default)
			)
			(fill no)
			(layer "F.CrtYd")
		)
		(fp_line
			(start -0.508 0.3048)
			(end 0.508 0.3048)
			(stroke
				(width 0.1)
				(type default)
			)
			(layer "F.Fab")
		)
		(fp_line
			(start 0.508 0.3048)
			(end 0.508 -0.3048)
			(stroke
				(width 0.1)
				(type default)
			)
			(layer "F.Fab")
		)
		(fp_line
			(start -0.508 -0.3048)
			(end -0.508 0.3048)
			(stroke
				(width 0.1)
				(type default)
			)
			(layer "F.Fab")
		)
		(fp_line
			(start 0.508 -0.3048)
			(end -0.508 -0.3048)
			(stroke
				(width 0.1)
				(type default)
			)
			(layer "F.Fab")
		)
		(pad "1" smd rect
			(at -0.5334 0 270)
			(size 0.7112 0.6096)
			(layers "F.Cu" "F.Mask" "F.Paste")
			(net "FT_USB_DETECT")
		)
		(pad "2" smd rect
			(at 0.5334 0 270)
			(size 0.7112 0.6096)
			(layers "F.Cu" "F.Mask" "F.Paste")
			(net "FPGA_IO_FT_USBDET_RST_N")
		)
		(zone
			(layer "F.Cu")
			(hatch none 0.5)
			(connect_pads
				(clearance 0)
			)
			(min_thickness 0.25)
			(keepout
				(tracks not_allowed)
				(vias allowed)
				(pads allowed)
				(copperpour not_allowed)
				(footprints allowed)
			)
			(placement
				(enabled no)
				(sheetname "")
			)
			(fill
				(thermal_gap 0.5)
				(thermal_bridge_width 0.5)
				(island_removal_mode 0)
			)
			(polygon
				(pts
					(xy 109.9312 -88.3412) (xy 109.9312 -88.1888) (xy 110.5408 -88.1888) (xy 110.5408 -88.3412)
				)
			)
		)
		(zone
			(layer "F.Cu")
			(hatch none 0.5)
			(connect_pads
				(clearance 0)
			)
			(min_thickness 0.25)
			(keepout
				(tracks allowed)
				(vias not_allowed)
				(pads allowed)
				(copperpour not_allowed)
				(footprints allowed)
			)
			(placement
				(enabled no)
				(sheetname "")
			)
			(fill
				(thermal_gap 0.5)
				(thermal_bridge_width 0.5)
				(island_removal_mode 0)
			)
			(polygon
				(pts
					(xy 109.9312 -88.3412) (xy 109.9312 -88.1888) (xy 110.5408 -88.1888) (xy 110.5408 -88.3412)
				)
			)
		)
	)
	(footprint ""
		(layer "F.Cu")
		(at 34.798 -129.667)
		(property "Reference" "SP23"
			(at 0 0 0)
			(layer "F.SilkS")
			(hide yes)
			(effects
				(font
					(size 1.27 1.27)
				)
			)
		)
		(property "Value" ""
			(at 0 0 0)
			(layer "F.Fab")
			(effects
				(font
					(size 1.27 1.27)
				)
			)
		)
		(duplicate_pad_numbers_are_jumpers no)
	)
	(footprint ""
		(layer "F.Cu")
		(at 20.32 -29.21 180)
		(property "Reference" "R373"
			(at -2.794 -0.54737 0)
			(unlocked yes)
			(layer "F.SilkS")
			(effects
				(font
					(size 0.7874 0.5842)
					(thickness 0.1524)
				)
			)
		)
		(property "Value" "VAL*"
			(at 0.02032 2.13233 180)
			(unlocked yes)
			(layer "F.Fab")
			(hide yes)
			(effects
				(font
					(size 0.7874 0.5842)
					(thickness 0.1524)
				)
			)
		)
		(property "Device Type" "RESISTOR-G155-11000-01,100OHM,A"
			(at 0.008382 1.210564 180)
			(unlocked yes)
			(layer "F.Fab")
			(hide yes)
			(effects
				(font
					(size 0.7874 0.5842)
					(thickness 0.1524)
				)
			)
		)
		(property "User Part Number" "PARTNUM*"
			(at 0.02032 4.024884 180)
			(unlocked yes)
			(layer "Cmts.User")
			(hide yes)
			(effects
				(font
					(size 0.7874 0.5842)
					(thickness 0.1524)
				)
			)
		)
		(property "Tolerance" "TOL*"
			(at 0.044704 3.05435 180)
			(unlocked yes)
			(layer "Cmts.User")
			(hide yes)
			(effects
				(font
					(size 0.7874 0.5842)
					(thickness 0.1524)
				)
			)
		)
		(duplicate_pad_numbers_are_jumpers no)
		(fp_line
			(start 1.143 0.5588)
			(end 1.143 -0.5588)
			(stroke
				(width 0.1)
				(type default)
			)
			(layer "F.SilkS")
		)
		(fp_line
			(start 1.143 -0.5588)
			(end -1.143 -0.5588)
			(stroke
				(width 0.1)
				(type default)
			)
			(layer "F.SilkS")
		)
		(fp_line
			(start -1.143 0.5588)
			(end 1.143 0.5588)
			(stroke
				(width 0.1)
				(type default)
			)
			(layer "F.SilkS")
		)
		(fp_line
			(start -1.143 -0.5588)
			(end -1.143 0.5588)
			(stroke
				(width 0.1)
				(type default)
			)
			(layer "F.SilkS")
		)
		(fp_poly
			(pts
				(xy -1.143 0.5588) (xy 1.143 0.5588) (xy 1.143 -0.5588) (xy -1.143 -0.5588)
			)
			(stroke
				(width 0)
				(type default)
			)
			(fill no)
			(layer "F.CrtYd")
		)
		(fp_line
			(start 0.508 0.3048)
			(end 0.508 -0.3048)
			(stroke
				(width 0.1)
				(type default)
			)
			(layer "F.Fab")
		)
		(fp_line
			(start 0.508 -0.3048)
			(end -0.508 -0.3048)
			(stroke
				(width 0.1)
				(type default)
			)
			(layer "F.Fab")
		)
		(fp_line
			(start -0.508 0.3048)
			(end 0.508 0.3048)
			(stroke
				(width 0.1)
				(type default)
			)
			(layer "F.Fab")
		)
		(fp_line
			(start -0.508 -0.3048)
			(end -0.508 0.3048)
			(stroke
				(width 0.1)
				(type default)
			)
			(layer "F.Fab")
		)
		(pad "1" smd rect
			(at -0.5334 0 180)
			(size 0.7112 0.6096)
			(layers "F.Cu" "F.Mask" "F.Paste")
			(net "FPGA_OUT_SMA2_LED_RED_N")
		)
		(pad "2" smd rect
			(at 0.5334 0 180)
			(size 0.7112 0.6096)
			(layers "F.Cu" "F.Mask" "F.Paste")
			(net "UNNAMED_14_LED4PV14_I266_3")
		)
		(zone
			(layer "F.Cu")
			(hatch none 0.5)
			(connect_pads
				(clearance 0)
			)
			(min_thickness 0.25)
			(keepout
				(tracks not_allowed)
				(vias allowed)
				(pads allowed)
				(copperpour not_allowed)
				(footprints allowed)
			)
			(placement
				(enabled no)
				(sheetname "")
			)
			(fill
				(thermal_gap 0.5)
				(thermal_bridge_width 0.5)
				(island_removal_mode 0)
			)
			(polygon
				(pts
					(xy 20.3962 -29.5148) (xy 20.2438 -29.5148) (xy 20.2438 -28.9052) (xy 20.3962 -28.9052)
				)
			)
		)
		(zone
			(layer "F.Cu")
			(hatch none 0.5)
			(connect_pads
				(clearance 0)
			)
			(min_thickness 0.25)
			(keepout
				(tracks allowed)
				(vias not_allowed)
				(pads allowed)
				(copperpour not_allowed)
				(footprints allowed)
			)
			(placement
				(enabled no)
				(sheetname "")
			)
			(fill
				(thermal_gap 0.5)
				(thermal_bridge_width 0.5)
				(island_removal_mode 0)
			)
			(polygon
				(pts
					(xy 20.3962 -29.5148) (xy 20.2438 -29.5148) (xy 20.2438 -28.9052) (xy 20.3962 -28.9052)
				)
			)
		)
	)
	(footprint ""
		(layer "F.Cu")
		(at 128.6002 -65.9638)
		(property "Reference" "C189"
			(at 0.508 5.75437 0)
			(unlocked yes)
			(layer "F.SilkS")
			(effects
				(font
					(size 0.7874 0.5842)
					(thickness 0.1524)
				)
			)
		)
		(property "Value" "VAL*"
			(at 0.0762 2.067306 0)
			(unlocked yes)
			(layer "F.Fab")
			(hide yes)
			(effects
				(font
					(size 0.7874 0.5842)
					(thickness 0.1524)
				)
			)
		)
		(property "Tolerance" "TOL*"
			(at 0.0762 3.032506 0)
			(unlocked yes)
			(layer "Cmts.User")
			(hide yes)
			(effects
				(font
					(size 0.7874 0.5842)
					(thickness 0.1524)
				)
			)
		)
		(property "User Part Number" "PARTNUM*"
			(at 0.1016 4.023106 0)
			(unlocked yes)
			(layer "Cmts.User")
			(hide yes)
			(effects
				(font
					(size 0.7874 0.5842)
					(thickness 0.1524)
				)
			)
		)
		(property "Device Type" "CAPACITOR-G105-0B104-EK,0.1UF,A"
			(at 0.0508 1.127506 0)
			(unlocked yes)
			(layer "F.Fab")
			(hide yes)
			(effects
				(font
					(size 0.7874 0.5842)
					(thickness 0.1524)
				)
			)
		)
		(duplicate_pad_numbers_are_jumpers no)
		(fp_line
			(start -1.143 -0.5588)
			(end -1.143 0.5588)
			(stroke
				(width 0.1)
				(type default)
			)
			(layer "F.SilkS")
		)
		(fp_line
			(start -1.143 0.5588)
			(end 1.143 0.5588)
			(stroke
				(width 0.1)
				(type default)
			)
			(layer "F.SilkS")
		)
		(fp_line
			(start 1.143 -0.5588)
			(end -1.143 -0.5588)
			(stroke
				(width 0.1)
				(type default)
			)
			(layer "F.SilkS")
		)
		(fp_line
			(start 1.143 0.5588)
			(end 1.143 -0.5588)
			(stroke
				(width 0.1)
				(type default)
			)
			(layer "F.SilkS")
		)
		(fp_rect
			(start 1.143 -0.5588)
			(end -1.143 0.5588)
			(stroke
				(width 0)
				(type default)
			)
			(fill no)
			(layer "F.CrtYd")
		)
		(fp_line
			(start -0.508 -0.3048)
			(end -0.508 0.3048)
			(stroke
				(width 0.1)
				(type default)
			)
			(layer "F.Fab")
		)
		(fp_line
			(start -0.508 0.3048)
			(end 0.508 0.3048)
			(stroke
				(width 0.1)
				(type default)
			)
			(layer "F.Fab")
		)
		(fp_line
			(start 0.508 -0.3048)
			(end -0.508 -0.3048)
			(stroke
				(width 0.1)
				(type default)
			)
			(layer "F.Fab")
		)
		(fp_line
			(start 0.508 0.3048)
			(end 0.508 -0.3048)
			(stroke
				(width 0.1)
				(type default)
			)
			(layer "F.Fab")
		)
		(pad "1" smd rect
			(at -0.5334 0)
			(size 0.7112 0.6096)
			(layers "F.Cu" "F.Mask" "F.Paste")
			(net "XP1R8V_VIN")
		)
		(pad "2" smd rect
			(at 0.5334 0)
			(size 0.7112 0.6096)
			(layers "F.Cu" "F.Mask" "F.Paste")
			(net "SG")
		)
		(zone
			(layer "F.Cu")
			(hatch none 0.5)
			(connect_pads
				(clearance 0)
			)
			(min_thickness 0.25)
			(keepout
				(tracks allowed)
				(vias not_allowed)
				(pads allowed)
				(copperpour not_allowed)
				(footprints allowed)
			)
			(placement
				(enabled no)
				(sheetname "")
			)
			(fill
				(thermal_gap 0.5)
				(thermal_bridge_width 0.5)
				(island_removal_mode 0)
			)
			(polygon
				(pts
					(xy 128.6764 -66.2686) (xy 128.524 -66.2686) (xy 128.524 -65.659) (xy 128.6764 -65.659)
				)
			)
		)
	)
	(footprint ""
		(layer "F.Cu")
		(at 101.854 -26.67 90)
		(property "Reference" "C254"
			(at 0.508 -2.11963 90)
			(unlocked yes)
			(layer "F.SilkS")
			(effects
				(font
					(size 0.7874 0.5842)
					(thickness 0.1524)
				)
			)
		)
		(property "Value" "VAL*"
			(at 0.0762 2.067306 90)
			(unlocked yes)
			(layer "F.Fab")
			(hide yes)
			(effects
				(font
					(size 0.7874 0.5842)
					(thickness 0.1524)
				)
			)
		)
		(property "Tolerance" "TOL*"
			(at 0.0762 3.032506 90)
			(unlocked yes)
			(layer "Cmts.User")
			(hide yes)
			(effects
				(font
					(size 0.7874 0.5842)
					(thickness 0.1524)
				)
			)
		)
		(property "User Part Number" "PARTNUM*"
			(at 0.1016 4.023106 90)
			(unlocked yes)
			(layer "Cmts.User")
			(hide yes)
			(effects
				(font
					(size 0.7874 0.5842)
					(thickness 0.1524)
				)
			)
		)
		(property "Device Type" "CAPACITOR-G105-0B104-CK,0.1UF,A"
			(at 0.0508 1.127506 90)
			(unlocked yes)
			(layer "F.Fab")
			(hide yes)
			(effects
				(font
					(size 0.7874 0.5842)
					(thickness 0.1524)
				)
			)
		)
		(duplicate_pad_numbers_are_jumpers no)
		(fp_line
			(start 1.143 -0.5588)
			(end -1.143 -0.5588)
			(stroke
				(width 0.1)
				(type default)
			)
			(layer "F.SilkS")
		)
		(fp_line
			(start -1.143 -0.5588)
			(end -1.143 0.5588)
			(stroke
				(width 0.1)
				(type default)
			)
			(layer "F.SilkS")
		)
		(fp_line
			(start 1.143 0.5588)
			(end 1.143 -0.5588)
			(stroke
				(width 0.1)
				(type default)
			)
			(layer "F.SilkS")
		)
		(fp_line
			(start -1.143 0.5588)
			(end 1.143 0.5588)
			(stroke
				(width 0.1)
				(type default)
			)
			(layer "F.SilkS")
		)
		(fp_rect
			(start -1.143 -0.5588)
			(end 1.143 0.5588)
			(stroke
				(width 0)
				(type default)
			)
			(fill no)
			(layer "F.CrtYd")
		)
		(fp_line
			(start 0.508 -0.3048)
			(end -0.508 -0.3048)
			(stroke
				(width 0.1)
				(type default)
			)
			(layer "F.Fab")
		)
		(fp_line
			(start -0.508 -0.3048)
			(end -0.508 0.3048)
			(stroke
				(width 0.1)
				(type default)
			)
			(layer "F.Fab")
		)
		(fp_line
			(start 0.508 0.3048)
			(end 0.508 -0.3048)
			(stroke
				(width 0.1)
				(type default)
			)
			(layer "F.Fab")
		)
		(fp_line
			(start -0.508 0.3048)
			(end 0.508 0.3048)
			(stroke
				(width 0.1)
				(type default)
			)
			(layer "F.Fab")
		)
		(pad "1" smd rect
			(at -0.5334 0 90)
			(size 0.7112 0.6096)
			(layers "F.Cu" "F.Mask" "F.Paste")
			(net "OSC_125M_CLKN")
		)
		(pad "2" smd rect
			(at 0.5334 0 90)
			(size 0.7112 0.6096)
			(layers "F.Cu" "F.Mask" "F.Paste")
			(net "MHZ125CLKN_CLKIN")
		)
		(zone
			(layer "F.Cu")
			(hatch none 0.5)
			(connect_pads
				(clearance 0)
			)
			(min_thickness 0.25)
			(keepout
				(tracks allowed)
				(vias not_allowed)
				(pads allowed)
				(copperpour not_allowed)
				(footprints allowed)
			)
			(placement
				(enabled no)
				(sheetname "")
			)
			(fill
				(thermal_gap 0.5)
				(thermal_bridge_width 0.5)
				(island_removal_mode 0)
			)
			(polygon
				(pts
					(xy 101.5492 -26.5938) (xy 102.1588 -26.5938) (xy 102.1588 -26.7462) (xy 101.5492 -26.7462)
				)
			)
		)
	)
	(footprint ""
		(layer "F.Cu")
		(at 52.451 -131.064)
		(property "Reference" "SP27"
			(at 0 0 0)
			(layer "F.SilkS")
			(hide yes)
			(effects
				(font
					(size 1.27 1.27)
				)
			)
		)
		(property "Value" ""
			(at 0 0 0)
			(layer "F.Fab")
			(effects
				(font
					(size 1.27 1.27)
				)
			)
		)
		(duplicate_pad_numbers_are_jumpers no)
	)
	(footprint ""
		(layer "F.Cu")
		(at 9.5758 -68.201032 90)
		(property "Reference" "R392"
			(at 3.553968 -0.64643 90)
			(unlocked yes)
			(layer "F.SilkS")
			(effects
				(font
					(size 0.7874 0.5842)
					(thickness 0.1524)
				)
			)
		)
		(property "Value" "VAL*"
			(at 0.02032 2.13233 90)
			(unlocked yes)
			(layer "F.Fab")
			(hide yes)
			(effects
				(font
					(size 0.7874 0.5842)
					(thickness 0.1524)
				)
			)
		)
		(property "Tolerance" "TOL*"
			(at 0.044704 3.05435 90)
			(unlocked yes)
			(layer "Cmts.User")
			(hide yes)
			(effects
				(font
					(size 0.7874 0.5842)
					(thickness 0.1524)
				)
			)
		)
		(property "User Part Number" "PARTNUM*"
			(at 0.02032 4.024884 90)
			(unlocked yes)
			(layer "Cmts.User")
			(hide yes)
			(effects
				(font
					(size 0.7874 0.5842)
					(thickness 0.1524)
				)
			)
		)
		(property "Device Type" "RESISTOR-G155-133R0-01,33OHM,1%"
			(at 0.008382 1.210564 90)
			(unlocked yes)
			(layer "F.Fab")
			(hide yes)
			(effects
				(font
					(size 0.7874 0.5842)
					(thickness 0.1524)
				)
			)
		)
		(duplicate_pad_numbers_are_jumpers no)
		(fp_line
			(start 1.143 -0.5588)
			(end -1.143 -0.5588)
			(stroke
				(width 0.1)
				(type default)
			)
			(layer "F.SilkS")
		)
		(fp_line
			(start -1.143 -0.5588)
			(end -1.143 0.5588)
			(stroke
				(width 0.1)
				(type default)
			)
			(layer "F.SilkS")
		)
		(fp_line
			(start 1.143 0.5588)
			(end 1.143 -0.5588)
			(stroke
				(width 0.1)
				(type default)
			)
			(layer "F.SilkS")
		)
		(fp_line
			(start -1.143 0.5588)
			(end 1.143 0.5588)
			(stroke
				(width 0.1)
				(type default)
			)
			(layer "F.SilkS")
		)
		(fp_rect
			(start -1.143 -0.5588)
			(end 1.143 0.5588)
			(stroke
				(width 0)
				(type default)
			)
			(fill no)
			(layer "F.CrtYd")
		)
		(fp_line
			(start 0.508 -0.3048)
			(end -0.508 -0.3048)
			(stroke
				(width 0.1)
				(type default)
			)
			(layer "F.Fab")
		)
		(fp_line
			(start -0.508 -0.3048)
			(end -0.508 0.3048)
			(stroke
				(width 0.1)
				(type default)
			)
			(layer "F.Fab")
		)
		(fp_line
			(start 0.508 0.3048)
			(end 0.508 -0.3048)
			(stroke
				(width 0.1)
				(type default)
			)
			(layer "F.Fab")
		)
		(fp_line
			(start -0.508 0.3048)
			(end 0.508 0.3048)
			(stroke
				(width 0.1)
				(type default)
			)
			(layer "F.Fab")
		)
		(pad "1" smd rect
			(at -0.5334 0 90)
			(size 0.7112 0.6096)
			(layers "F.Cu" "F.Mask" "F.Paste")
			(net "SMA3_LED_GREEN_N")
		)
		(pad "2" smd rect
			(at 0.5334 0 90)
			(size 0.7112 0.6096)
			(layers "F.Cu" "F.Mask" "F.Paste")
			(net "UNNAMED_14_LED4PV14_I267_4")
		)
		(zone
			(layer "F.Cu")
			(hatch none 0.5)
			(connect_pads
				(clearance 0)
			)
			(min_thickness 0.25)
			(keepout
				(tracks not_allowed)
				(vias allowed)
				(pads allowed)
				(copperpour not_allowed)
				(footprints allowed)
			)
			(placement
				(enabled no)
				(sheetname "")
			)
			(fill
				(thermal_gap 0.5)
				(thermal_bridge_width 0.5)
				(island_removal_mode 0)
			)
			(polygon
				(pts
					(xy 9.271 -68.124832) (xy 9.8806 -68.124832) (xy 9.8806 -68.277232) (xy 9.271 -68.277232)
				)
			)
		)
		(zone
			(layer "F.Cu")
			(hatch none 0.5)
			(connect_pads
				(clearance 0)
			)
			(min_thickness 0.25)
			(keepout
				(tracks allowed)
				(vias not_allowed)
				(pads allowed)
				(copperpour not_allowed)
				(footprints allowed)
			)
			(placement
				(enabled no)
				(sheetname "")
			)
			(fill
				(thermal_gap 0.5)
				(thermal_bridge_width 0.5)
				(island_removal_mode 0)
			)
			(polygon
				(pts
					(xy 9.271 -68.124832) (xy 9.8806 -68.124832) (xy 9.8806 -68.277232) (xy 9.271 -68.277232)
				)
			)
		)
	)
	(footprint ""
		(layer "F.Cu")
		(at 126.492 -35.179 180)
		(property "Reference" "R221"
			(at -2.921 -1.56337 0)
			(unlocked yes)
			(layer "F.SilkS")
			(effects
				(font
					(size 0.7874 0.5842)
					(thickness 0.1524)
				)
			)
		)
		(property "Value" "VAL*"
			(at 0.02032 2.13233 180)
			(unlocked yes)
			(layer "F.Fab")
			(hide yes)
			(effects
				(font
					(size 0.7874 0.5842)
					(thickness 0.1524)
				)
			)
		)
		(property "Device Type" "RESISTOR-G155-11000-01,100OHM,A"
			(at 0.008382 1.210564 180)
			(unlocked yes)
			(layer "F.Fab")
			(hide yes)
			(effects
				(font
					(size 0.7874 0.5842)
					(thickness 0.1524)
				)
			)
		)
		(property "User Part Number" "PARTNUM*"
			(at 0.02032 4.024884 180)
			(unlocked yes)
			(layer "Cmts.User")
			(hide yes)
			(effects
				(font
					(size 0.7874 0.5842)
					(thickness 0.1524)
				)
			)
		)
		(property "Tolerance" "TOL*"
			(at 0.044704 3.05435 180)
			(unlocked yes)
			(layer "Cmts.User")
			(hide yes)
			(effects
				(font
					(size 0.7874 0.5842)
					(thickness 0.1524)
				)
			)
		)
		(duplicate_pad_numbers_are_jumpers no)
		(fp_line
			(start 1.143 0.5588)
			(end 1.143 -0.5588)
			(stroke
				(width 0.1)
				(type default)
			)
			(layer "F.SilkS")
		)
		(fp_line
			(start 1.143 -0.5588)
			(end -1.143 -0.5588)
			(stroke
				(width 0.1)
				(type default)
			)
			(layer "F.SilkS")
		)
		(fp_line
			(start -1.143 0.5588)
			(end 1.143 0.5588)
			(stroke
				(width 0.1)
				(type default)
			)
			(layer "F.SilkS")
		)
		(fp_line
			(start -1.143 -0.5588)
			(end -1.143 0.5588)
			(stroke
				(width 0.1)
				(type default)
			)
			(layer "F.SilkS")
		)
		(fp_rect
			(start 1.143 0.5588)
			(end -1.143 -0.5588)
			(stroke
				(width 0)
				(type default)
			)
			(fill no)
			(layer "F.CrtYd")
		)
		(fp_line
			(start 0.508 0.3048)
			(end 0.508 -0.3048)
			(stroke
				(width 0.1)
				(type default)
			)
			(layer "F.Fab")
		)
		(fp_line
			(start 0.508 -0.3048)
			(end -0.508 -0.3048)
			(stroke
				(width 0.1)
				(type default)
			)
			(layer "F.Fab")
		)
		(fp_line
			(start -0.508 0.3048)
			(end 0.508 0.3048)
			(stroke
				(width 0.1)
				(type default)
			)
			(layer "F.Fab")
		)
		(fp_line
			(start -0.508 -0.3048)
			(end -0.508 0.3048)
			(stroke
				(width 0.1)
				(type default)
			)
			(layer "F.Fab")
		)
		(pad "1" smd rect
			(at -0.5334 0 180)
			(size 0.7112 0.6096)
			(layers "F.Cu" "F.Mask" "F.Paste")
			(net "XP3R3V_FPGA")
		)
		(pad "2" smd rect
			(at 0.5334 0 180)
			(size 0.7112 0.6096)
			(layers "F.Cu" "F.Mask" "F.Paste")
			(net "FPGA_M2")
		)
		(zone
			(layer "F.Cu")
			(hatch none 0.5)
			(connect_pads
				(clearance 0)
			)
			(min_thickness 0.25)
			(keepout
				(tracks allowed)
				(vias not_allowed)
				(pads allowed)
				(copperpour not_allowed)
				(footprints allowed)
			)
			(placement
				(enabled no)
				(sheetname "")
			)
			(fill
				(thermal_gap 0.5)
				(thermal_bridge_width 0.5)
				(island_removal_mode 0)
			)
			(polygon
				(pts
					(xy 126.4158 -35.4838) (xy 126.4158 -34.8742) (xy 126.5682 -34.8742) (xy 126.5682 -35.4838)
				)
			)
		)
	)
	(footprint ""
		(layer "F.Cu")
		(at 80.772 -57.2516)
		(property "Reference" "R79"
			(at -10.668 -19.39163 0)
			(unlocked yes)
			(layer "F.SilkS")
			(effects
				(font
					(size 0.7874 0.5842)
					(thickness 0.1524)
				)
			)
		)
		(property "Value" "VAL*"
			(at 0.02032 2.13233 0)
			(unlocked yes)
			(layer "F.Fab")
			(hide yes)
			(effects
				(font
					(size 0.7874 0.5842)
					(thickness 0.1524)
				)
			)
		)
		(property "Tolerance" "TOL*"
			(at 0.044704 3.05435 0)
			(unlocked yes)
			(layer "Cmts.User")
			(hide yes)
			(effects
				(font
					(size 0.7874 0.5842)
					(thickness 0.1524)
				)
			)
		)
		(property "User Part Number" "PARTNUM*"
			(at 0.02032 4.024884 0)
			(unlocked yes)
			(layer "Cmts.User")
			(hide yes)
			(effects
				(font
					(size 0.7874 0.5842)
					(thickness 0.1524)
				)
			)
		)
		(property "Device Type" "RESISTOR-G155-133R0-01,33OHM,1%"
			(at 0.008382 1.210564 0)
			(unlocked yes)
			(layer "F.Fab")
			(hide yes)
			(effects
				(font
					(size 0.7874 0.5842)
					(thickness 0.1524)
				)
			)
		)
		(duplicate_pad_numbers_are_jumpers no)
		(fp_line
			(start -1.143 -0.5588)
			(end -1.143 0.5588)
			(stroke
				(width 0.1)
				(type default)
			)
			(layer "F.SilkS")
		)
		(fp_line
			(start -1.143 0.5588)
			(end 1.143 0.5588)
			(stroke
				(width 0.1)
				(type default)
			)
			(layer "F.SilkS")
		)
		(fp_line
			(start 1.143 -0.5588)
			(end -1.143 -0.5588)
			(stroke
				(width 0.1)
				(type default)
			)
			(layer "F.SilkS")
		)
		(fp_line
			(start 1.143 0.5588)
			(end 1.143 -0.5588)
			(stroke
				(width 0.1)
				(type default)
			)
			(layer "F.SilkS")
		)
		(fp_rect
			(start -1.143 0.5588)
			(end 1.143 -0.5588)
			(stroke
				(width 0)
				(type default)
			)
			(fill no)
			(layer "F.CrtYd")
		)
		(fp_line
			(start -0.508 -0.3048)
			(end -0.508 0.3048)
			(stroke
				(width 0.1)
				(type default)
			)
			(layer "F.Fab")
		)
		(fp_line
			(start -0.508 0.3048)
			(end 0.508 0.3048)
			(stroke
				(width 0.1)
				(type default)
			)
			(layer "F.Fab")
		)
		(fp_line
			(start 0.508 -0.3048)
			(end -0.508 -0.3048)
			(stroke
				(width 0.1)
				(type default)
			)
			(layer "F.Fab")
		)
		(fp_line
			(start 0.508 0.3048)
			(end 0.508 -0.3048)
			(stroke
				(width 0.1)
				(type default)
			)
			(layer "F.Fab")
		)
		(pad "1" smd rect
			(at -0.5334 0)
			(size 0.7112 0.6096)
			(layers "F.Cu" "F.Mask" "F.Paste")
			(net "FPGA_IN_BNO080_INT_N")
		)
		(pad "2" smd rect
			(at 0.5334 0)
			(size 0.7112 0.6096)
			(layers "F.Cu" "F.Mask" "F.Paste")
			(net "R_BNO080_INT_N")
		)
		(zone
			(layer "F.Cu")
			(hatch none 0.5)
			(connect_pads
				(clearance 0)
			)
			(min_thickness 0.25)
			(keepout
				(tracks allowed)
				(vias not_allowed)
				(pads allowed)
				(copperpour not_allowed)
				(footprints allowed)
			)
			(placement
				(enabled no)
				(sheetname "")
			)
			(fill
				(thermal_gap 0.5)
				(thermal_bridge_width 0.5)
				(island_removal_mode 0)
			)
			(polygon
				(pts
					(xy 80.6958 -56.9468) (xy 80.8482 -56.9468) (xy 80.8482 -57.5564) (xy 80.6958 -57.5564)
				)
			)
		)
	)
	(footprint ""
		(layer "F.Cu")
		(at 15.748 -50.673)
		(property "Reference" "TP33"
			(at 1.18237 3.3782 90)
			(unlocked yes)
			(layer "F.SilkS")
			(effects
				(font
					(size 0.7874 0.5842)
					(thickness 0.1524)
				)
				(justify left)
			)
		)
		(property "Value" ""
			(at 0 0 0)
			(layer "F.Fab")
			(effects
				(font
					(size 1.27 1.27)
				)
			)
		)
		(property "Device Type" "TP_PIONT-TP010CT020B030_PTH-TPA"
			(at -1.341882 0.996696 0)
			(unlocked yes)
			(layer "F.Fab")
			(hide yes)
			(effects
				(font
					(size 0.7874 0.5842)
					(thickness 0.000001)
				)
				(justify left)
			)
		)
		(duplicate_pad_numbers_are_jumpers no)
		(fp_poly
			(pts
				(arc
					(start 0.889 0)
					(mid -0.889 0)
					(end 0.889 0)
				)
			)
			(stroke
				(width 0)
				(type default)
			)
			(fill no)
			(layer "B.CrtYd")
		)
		(fp_poly
			(pts
				(arc
					(start 0.889 0)
					(mid -0.889 0)
					(end 0.889 0)
				)
			)
			(stroke
				(width 0)
				(type default)
			)
			(fill no)
			(layer "F.CrtYd")
		)
		(pad "1" thru_hole circle
			(at 0 0)
			(size 0.508 0.508)
			(drill 0.254)
			(layers "*.Cu" "*.Mask")
			(remove_unused_layers no)
			(net "SMA2_SIG_OUT_BF_EN_N")
			(clearance 0.1016)
			(padstack
				(mode front_inner_back)
				(layer "Inner"
					(shape circle)
					(size 0.508 0.508)
					(clearance 0.1016)
				)
				(layer "B.Cu"
					(shape circle)
					(size 0.762 0.762)
					(clearance -0.0254)
				)
			)
		)
	)
	(footprint ""
		(layer "F.Cu")
		(at 52.01158 -15.5194 -90)
		(property "Reference" "R25"
			(at -3.0226 -0.22479 90)
			(unlocked yes)
			(layer "F.SilkS")
			(effects
				(font
					(size 0.7874 0.5842)
					(thickness 0.1524)
				)
			)
		)
		(property "Value" "VAL*"
			(at 0.02032 2.13233 270)
			(unlocked yes)
			(layer "F.Fab")
			(hide yes)
			(effects
				(font
					(size 0.7874 0.5842)
					(thickness 0.1524)
				)
			)
		)
		(property "Tolerance" "TOL*"
			(at 0.044704 3.05435 270)
			(unlocked yes)
			(layer "Cmts.User")
			(hide yes)
			(effects
				(font
					(size 0.7874 0.5842)
					(thickness 0.1524)
				)
			)
		)
		(property "User Part Number" "PARTNUM*"
			(at 0.02032 4.024884 270)
			(unlocked yes)
			(layer "Cmts.User")
			(hide yes)
			(effects
				(font
					(size 0.7874 0.5842)
					(thickness 0.1524)
				)
			)
		)
		(property "Device Type" "RESISTOR-G155-14701-01,4.7KOHMA"
			(at 0.008382 1.210564 270)
			(unlocked yes)
			(layer "F.Fab")
			(hide yes)
			(effects
				(font
					(size 0.7874 0.5842)
					(thickness 0.1524)
				)
			)
		)
		(duplicate_pad_numbers_are_jumpers no)
		(fp_line
			(start -1.143 0.5588)
			(end 1.143 0.5588)
			(stroke
				(width 0.1)
				(type default)
			)
			(layer "F.SilkS")
		)
		(fp_line
			(start 1.143 0.5588)
			(end 1.143 -0.5588)
			(stroke
				(width 0.1)
				(type default)
			)
			(layer "F.SilkS")
		)
		(fp_line
			(start -1.143 -0.5588)
			(end -1.143 0.5588)
			(stroke
				(width 0.1)
				(type default)
			)
			(layer "F.SilkS")
		)
		(fp_line
			(start 1.143 -0.5588)
			(end -1.143 -0.5588)
			(stroke
				(width 0.1)
				(type default)
			)
			(layer "F.SilkS")
		)
		(fp_rect
			(start 1.143 0.5588)
			(end -1.143 -0.5588)
			(stroke
				(width 0)
				(type default)
			)
			(fill no)
			(layer "F.CrtYd")
		)
		(fp_line
			(start -0.508 0.3048)
			(end 0.508 0.3048)
			(stroke
				(width 0.1)
				(type default)
			)
			(layer "F.Fab")
		)
		(fp_line
			(start 0.508 0.3048)
			(end 0.508 -0.3048)
			(stroke
				(width 0.1)
				(type default)
			)
			(layer "F.Fab")
		)
		(fp_line
			(start -0.508 -0.3048)
			(end -0.508 0.3048)
			(stroke
				(width 0.1)
				(type default)
			)
			(layer "F.Fab")
		)
		(fp_line
			(start 0.508 -0.3048)
			(end -0.508 -0.3048)
			(stroke
				(width 0.1)
				(type default)
			)
			(layer "F.Fab")
		)
		(pad "1" smd rect
			(at -0.5334 0 270)
			(size 0.7112 0.6096)
			(layers "F.Cu" "F.Mask" "F.Paste")
			(net "XP3R3V_FPGA")
		)
		(pad "2" smd rect
			(at 0.5334 0 270)
			(size 0.7112 0.6096)
			(layers "F.Cu" "F.Mask" "F.Paste")
			(net "UNNAMED_3_G2201019801_I100_EN")
		)
		(zone
			(layer "F.Cu")
			(hatch none 0.5)
			(connect_pads
				(clearance 0)
			)
			(min_thickness 0.25)
			(keepout
				(tracks allowed)
				(vias not_allowed)
				(pads allowed)
				(copperpour not_allowed)
				(footprints allowed)
			)
			(placement
				(enabled no)
				(sheetname "")
			)
			(fill
				(thermal_gap 0.5)
				(thermal_bridge_width 0.5)
				(island_removal_mode 0)
			)
			(polygon
				(pts
					(xy 51.70678 -15.4432) (xy 52.31638 -15.4432) (xy 52.31638 -15.5956) (xy 51.70678 -15.5956)
				)
			)
		)
	)
	(footprint ""
		(layer "F.Cu")
		(at 130.048 -98.552 90)
		(property "Reference" "L15"
			(at 1.5875 0.67437 90)
			(unlocked yes)
			(layer "F.SilkS")
			(effects
				(font
					(size 0.7874 0.5842)
					(thickness 0.1524)
				)
				(justify left)
			)
		)
		(property "Value" "VAL*"
			(at -0.9398 3.70967 90)
			(unlocked yes)
			(layer "F.Fab")
			(hide yes)
			(effects
				(font
					(size 0.7874 0.5842)
					(thickness 0.1524)
				)
				(justify left)
			)
		)
		(property "Tolerance" "TOL*"
			(at -0.9906 5.00507 90)
			(unlocked yes)
			(layer "Cmts.User")
			(hide yes)
			(effects
				(font
					(size 0.7874 0.5842)
					(thickness 0.1524)
				)
				(justify left)
			)
		)
		(property "User Part Number" "PARTNUM*"
			(at -2.54 2.46507 90)
			(unlocked yes)
			(layer "Cmts.User")
			(hide yes)
			(effects
				(font
					(size 0.7874 0.5842)
					(thickness 0.1524)
				)
				(justify left)
			)
		)
		(property "Device Type" "FERRITEBEAD-G191-10100-01,120OA"
			(at -0.9906 1.22047 90)
			(unlocked yes)
			(layer "F.Fab")
			(hide yes)
			(effects
				(font
					(size 0.7874 0.5842)
					(thickness 0.1524)
				)
				(justify left)
			)
		)
		(duplicate_pad_numbers_are_jumpers no)
		(fp_line
			(start 1.3208 -0.7112)
			(end 1.3208 0.7112)
			(stroke
				(width 0.1)
				(type default)
			)
			(layer "F.SilkS")
		)
		(fp_line
			(start -1.3208 -0.7112)
			(end 1.3208 -0.7112)
			(stroke
				(width 0.1)
				(type default)
			)
			(layer "F.SilkS")
		)
		(fp_line
			(start 1.3208 0.7112)
			(end -1.3208 0.7112)
			(stroke
				(width 0.1)
				(type default)
			)
			(layer "F.SilkS")
		)
		(fp_line
			(start -1.3208 0.7112)
			(end -1.3208 -0.7112)
			(stroke
				(width 0.1)
				(type default)
			)
			(layer "F.SilkS")
		)
		(fp_rect
			(start -1.3208 0.7112)
			(end 1.3208 -0.7112)
			(stroke
				(width 0)
				(type default)
			)
			(fill no)
			(layer "F.CrtYd")
		)
		(fp_line
			(start 0.8128 -0.4572)
			(end 0.8128 0.4572)
			(stroke
				(width 0.1)
				(type default)
			)
			(layer "F.Fab")
		)
		(fp_line
			(start -0.8128 -0.4572)
			(end 0.8128 -0.4572)
			(stroke
				(width 0.1)
				(type default)
			)
			(layer "F.Fab")
		)
		(fp_line
			(start 0.8128 0.4572)
			(end -0.8128 0.4572)
			(stroke
				(width 0.1)
				(type default)
			)
			(layer "F.Fab")
		)
		(fp_line
			(start -0.8128 0.4572)
			(end -0.8128 -0.4572)
			(stroke
				(width 0.1)
				(type default)
			)
			(layer "F.Fab")
		)
		(pad "1" smd rect
			(at -0.6858 0 90)
			(size 0.762 0.8636)
			(layers "F.Cu" "F.Mask" "F.Paste")
			(net "XP5R0V")
		)
		(pad "2" smd rect
			(at 0.6858 0 90)
			(size 0.762 0.8636)
			(layers "F.Cu" "F.Mask" "F.Paste")
			(net "XP5R0V_VCC_ANT")
		)
		(zone
			(layer "F.Cu")
			(hatch none 0.5)
			(connect_pads
				(clearance 0)
			)
			(min_thickness 0.25)
			(keepout
				(tracks allowed)
				(vias not_allowed)
				(pads allowed)
				(copperpour not_allowed)
				(footprints allowed)
			)
			(placement
				(enabled no)
				(sheetname "")
			)
			(fill
				(thermal_gap 0.5)
				(thermal_bridge_width 0.5)
				(island_removal_mode 0)
			)
			(polygon
				(pts
					(xy 130.5052 -98.3996) (xy 130.5052 -98.7044) (xy 129.5908 -98.7044) (xy 129.5908 -98.3996)
				)
			)
		)
		(zone
			(layer "F.Cu")
			(hatch none 0.5)
			(connect_pads
				(clearance 0)
			)
			(min_thickness 0.25)
			(keepout
				(tracks not_allowed)
				(vias allowed)
				(pads allowed)
				(copperpour not_allowed)
				(footprints allowed)
			)
			(placement
				(enabled no)
				(sheetname "")
			)
			(fill
				(thermal_gap 0.5)
				(thermal_bridge_width 0.5)
				(island_removal_mode 0)
			)
			(polygon
				(pts
					(xy 130.5052 -98.3996) (xy 130.5052 -98.7044) (xy 129.5908 -98.7044) (xy 129.5908 -98.3996)
				)
			)
		)
	)
	(footprint ""
		(layer "F.Cu")
		(at 24.003 -75.946)
		(property "Reference" "TP9"
			(at 0 0 0)
			(layer "F.SilkS")
			(hide yes)
			(effects
				(font
					(size 1.27 1.27)
				)
			)
		)
		(property "Value" ""
			(at 0 0 0)
			(layer "F.Fab")
			(effects
				(font
					(size 1.27 1.27)
				)
			)
		)
		(property "Device Type" "TP_PIONT-TP010CT020B030_PTH-TPA"
			(at -1.341882 0.996696 0)
			(unlocked yes)
			(layer "F.Fab")
			(hide yes)
			(effects
				(font
					(size 0.7874 0.5842)
					(thickness 0.1524)
				)
				(justify left)
			)
		)
		(duplicate_pad_numbers_are_jumpers no)
		(fp_poly
			(pts
				(arc
					(start 0.889 0)
					(mid -0.889 0)
					(end 0.889 0)
				)
			)
			(stroke
				(width 0)
				(type default)
			)
			(fill no)
			(layer "B.CrtYd")
		)
		(fp_poly
			(pts
				(arc
					(start 0.889 0)
					(mid -0.889 0)
					(end 0.889 0)
				)
			)
			(stroke
				(width 0)
				(type default)
			)
			(fill no)
			(layer "F.CrtYd")
		)
		(pad "1" thru_hole circle
			(at 0 0)
			(size 0.508 0.508)
			(drill 0.254)
			(layers "*.Cu" "*.Mask")
			(remove_unused_layers no)
			(net "UNNAMED_524_FT4232HLREELQFP64_4")
			(clearance 0.1016)
			(padstack
				(mode front_inner_back)
				(layer "Inner"
					(shape circle)
					(size 0.508 0.508)
					(clearance 0.1016)
				)
				(layer "B.Cu"
					(shape circle)
					(size 0.762 0.762)
					(clearance -0.0254)
				)
			)
		)
	)
	(footprint ""
		(layer "F.Cu")
		(at 126.492 -33.909 180)
		(property "Reference" "R194"
			(at -2.921 -1.43637 0)
			(unlocked yes)
			(layer "F.SilkS")
			(effects
				(font
					(size 0.7874 0.5842)
					(thickness 0.1524)
				)
			)
		)
		(property "Value" "VAL*"
			(at 0.02032 2.13233 180)
			(unlocked yes)
			(layer "F.Fab")
			(hide yes)
			(effects
				(font
					(size 0.7874 0.5842)
					(thickness 0.1524)
				)
			)
		)
		(property "Tolerance" "TOL*"
			(at 0.044704 3.05435 180)
			(unlocked yes)
			(layer "Cmts.User")
			(hide yes)
			(effects
				(font
					(size 0.7874 0.5842)
					(thickness 0.1524)
				)
			)
		)
		(property "User Part Number" "PARTNUM*"
			(at 0.02032 4.024884 180)
			(unlocked yes)
			(layer "Cmts.User")
			(hide yes)
			(effects
				(font
					(size 0.7874 0.5842)
					(thickness 0.1524)
				)
			)
		)
		(property "Device Type" "RESISTOR-G155-14701-01,4.7KOHMA"
			(at 0.008382 1.210564 180)
			(unlocked yes)
			(layer "F.Fab")
			(hide yes)
			(effects
				(font
					(size 0.7874 0.5842)
					(thickness 0.1524)
				)
			)
		)
		(duplicate_pad_numbers_are_jumpers no)
		(fp_line
			(start 1.143 0.5588)
			(end 1.143 -0.5588)
			(stroke
				(width 0.1)
				(type default)
			)
			(layer "F.SilkS")
		)
		(fp_line
			(start 1.143 -0.5588)
			(end -1.143 -0.5588)
			(stroke
				(width 0.1)
				(type default)
			)
			(layer "F.SilkS")
		)
		(fp_line
			(start -1.143 0.5588)
			(end 1.143 0.5588)
			(stroke
				(width 0.1)
				(type default)
			)
			(layer "F.SilkS")
		)
		(fp_line
			(start -1.143 -0.5588)
			(end -1.143 0.5588)
			(stroke
				(width 0.1)
				(type default)
			)
			(layer "F.SilkS")
		)
		(fp_rect
			(start 1.143 0.5588)
			(end -1.143 -0.5588)
			(stroke
				(width 0)
				(type default)
			)
			(fill no)
			(layer "F.CrtYd")
		)
		(fp_line
			(start 0.508 0.3048)
			(end 0.508 -0.3048)
			(stroke
				(width 0.1)
				(type default)
			)
			(layer "F.Fab")
		)
		(fp_line
			(start 0.508 -0.3048)
			(end -0.508 -0.3048)
			(stroke
				(width 0.1)
				(type default)
			)
			(layer "F.Fab")
		)
		(fp_line
			(start -0.508 0.3048)
			(end 0.508 0.3048)
			(stroke
				(width 0.1)
				(type default)
			)
			(layer "F.Fab")
		)
		(fp_line
			(start -0.508 -0.3048)
			(end -0.508 0.3048)
			(stroke
				(width 0.1)
				(type default)
			)
			(layer "F.Fab")
		)
		(pad "1" smd rect
			(at -0.5334 0 180)
			(size 0.7112 0.6096)
			(layers "F.Cu" "F.Mask" "F.Paste")
			(net "XP3R3V_FPGA")
		)
		(pad "2" smd rect
			(at 0.5334 0 180)
			(size 0.7112 0.6096)
			(layers "F.Cu" "F.Mask" "F.Paste")
			(net "CFGBVS")
		)
		(zone
			(layer "F.Cu")
			(hatch none 0.5)
			(connect_pads
				(clearance 0)
			)
			(min_thickness 0.25)
			(keepout
				(tracks allowed)
				(vias not_allowed)
				(pads allowed)
				(copperpour not_allowed)
				(footprints allowed)
			)
			(placement
				(enabled no)
				(sheetname "")
			)
			(fill
				(thermal_gap 0.5)
				(thermal_bridge_width 0.5)
				(island_removal_mode 0)
			)
			(polygon
				(pts
					(xy 126.4158 -34.2138) (xy 126.4158 -33.6042) (xy 126.5682 -33.6042) (xy 126.5682 -34.2138)
				)
			)
		)
	)
	(footprint ""
		(layer "F.Cu")
		(at 125.499876 -78.650084)
		(property "Reference" "ME4"
			(at -1.230376 -4.114546 0)
			(unlocked yes)
			(layer "F.SilkS")
			(effects
				(font
					(size 0.7874 0.5842)
					(thickness 0.1524)
				)
				(justify left)
			)
		)
		(property "Value" ""
			(at 0 0 0)
			(layer "F.Fab")
			(effects
				(font
					(size 1.27 1.27)
				)
			)
		)
		(property "User Part Number" "PARTNUM*"
			(at -3.048 5.242306 0)
			(unlocked yes)
			(layer "Cmts.User")
			(hide yes)
			(effects
				(font
					(size 0.7874 0.5842)
					(thickness 0.1524)
				)
				(justify left)
			)
		)
		(property "Device Type" "NUT-G340-10437-01"
			(at -1.4732 4.226306 0)
			(unlocked yes)
			(layer "F.Fab")
			(hide yes)
			(effects
				(font
					(size 0.7874 0.5842)
					(thickness 0.1524)
				)
				(justify left)
			)
		)
		(duplicate_pad_numbers_are_jumpers no)
		(fp_circle
			(center 0 0)
			(end 3.3528 0)
			(stroke
				(width 0.1)
				(type default)
			)
			(fill no)
			(layer "F.SilkS")
		)
		(fp_poly
			(pts
				(arc
					(start -2.102612 -0.1524)
					(mid -1.490671 -1.490671)
					(end -0.1524 -2.102612)
				)
				(arc
					(start -0.1524 -3.171444)
					(mid -2.245137 -2.245137)
					(end -3.171444 -0.1524)
				)
			)
			(stroke
				(width 0)
				(type default)
			)
			(fill yes)
			(layer "F.Paste")
		)
		(fp_poly
			(pts
				(arc
					(start -0.1524 2.102612)
					(mid -1.490671 1.490671)
					(end -2.102612 0.1524)
				)
				(arc
					(start -3.171444 0.1524)
					(mid -2.245137 2.245137)
					(end -0.1524 3.171444)
				)
			)
			(stroke
				(width 0)
				(type default)
			)
			(fill yes)
			(layer "F.Paste")
		)
		(fp_poly
			(pts
				(arc
					(start 0.1524 -2.102612)
					(mid 1.490671 -1.490671)
					(end 2.102612 -0.1524)
				)
				(arc
					(start 3.171444 -0.1524)
					(mid 2.245137 -2.245137)
					(end 0.1524 -3.171444)
				)
			)
			(stroke
				(width 0)
				(type default)
			)
			(fill yes)
			(layer "F.Paste")
		)
		(fp_poly
			(pts
				(arc
					(start 2.102612 0.1524)
					(mid 1.490671 1.490671)
					(end 0.1524 2.102612)
				)
				(arc
					(start 0.1524 3.171444)
					(mid 2.245137 2.245137)
					(end 3.171444 0.1524)
				)
			)
			(stroke
				(width 0)
				(type default)
			)
			(fill yes)
			(layer "F.Paste")
		)
		(fp_rect
			(start -7.5946 7.5946)
			(end 7.5946 -7.5946)
			(stroke
				(width 0)
				(type default)
			)
			(fill no)
			(layer "B.CrtYd")
		)
		(fp_poly
			(pts
				(arc
					(start 3.6068 0)
					(mid -3.6068 0)
					(end 3.6068 0)
				)
			)
			(stroke
				(width 0)
				(type default)
			)
			(fill no)
			(layer "F.CrtYd")
		)
		(fp_circle
			(center 0 0)
			(end 2.8448 0)
			(stroke
				(width 0.1)
				(type default)
			)
			(fill no)
			(layer "F.Fab")
		)
		(pad "1" thru_hole circle
			(at 0 0)
			(size 6.1976 6.1976)
			(drill 4.2164)
			(layers "*.Cu" "*.Mask")
			(remove_unused_layers no)
			(net "SG")
			(padstack
				(mode front_inner_back)
				(layer "Inner"
					(shape circle)
					(size 5.0292 5.0292)
					(clearance -0.1143)
				)
				(layer "B.Cu"
					(shape circle)
					(size 5.0292 5.0292)
				)
			)
		)
	)
	(footprint ""
		(layer "F.Cu")
		(at 125.2982 -63.3222 90)
		(property "Reference" "L6"
			(at -0.762 -1.43383 90)
			(unlocked yes)
			(layer "F.SilkS")
			(effects
				(font
					(size 0.7874 0.5842)
					(thickness 0.1524)
				)
				(justify left)
			)
		)
		(property "Value" "VAL*"
			(at -0.9398 3.70967 90)
			(unlocked yes)
			(layer "F.Fab")
			(hide yes)
			(effects
				(font
					(size 0.7874 0.5842)
					(thickness 0.1524)
				)
				(justify left)
			)
		)
		(property "Device Type" "FERRITEBEAD-G191-10101-01,26OHA"
			(at -0.9906 1.22047 90)
			(unlocked yes)
			(layer "F.Fab")
			(hide yes)
			(effects
				(font
					(size 0.7874 0.5842)
					(thickness 0.1524)
				)
				(justify left)
			)
		)
		(property "User Part Number" "PARTNUM*"
			(at -2.54 2.46507 90)
			(unlocked yes)
			(layer "Cmts.User")
			(hide yes)
			(effects
				(font
					(size 0.7874 0.5842)
					(thickness 0.1524)
				)
				(justify left)
			)
		)
		(property "Tolerance" "TOL*"
			(at -0.9906 5.00507 90)
			(unlocked yes)
			(layer "Cmts.User")
			(hide yes)
			(effects
				(font
					(size 0.7874 0.5842)
					(thickness 0.1524)
				)
				(justify left)
			)
		)
		(duplicate_pad_numbers_are_jumpers no)
		(fp_line
			(start 1.3208 -0.7112)
			(end 1.3208 0.7112)
			(stroke
				(width 0.1)
				(type default)
			)
			(layer "F.SilkS")
		)
		(fp_line
			(start -1.3208 -0.7112)
			(end 1.3208 -0.7112)
			(stroke
				(width 0.1)
				(type default)
			)
			(layer "F.SilkS")
		)
		(fp_line
			(start 1.3208 0.7112)
			(end -1.3208 0.7112)
			(stroke
				(width 0.1)
				(type default)
			)
			(layer "F.SilkS")
		)
		(fp_line
			(start -1.3208 0.7112)
			(end -1.3208 -0.7112)
			(stroke
				(width 0.1)
				(type default)
			)
			(layer "F.SilkS")
		)
		(fp_rect
			(start 1.3208 0.7112)
			(end -1.3208 -0.7112)
			(stroke
				(width 0)
				(type default)
			)
			(fill no)
			(layer "F.CrtYd")
		)
		(fp_line
			(start 0.8128 -0.4572)
			(end 0.8128 0.4572)
			(stroke
				(width 0.1)
				(type default)
			)
			(layer "F.Fab")
		)
		(fp_line
			(start -0.8128 -0.4572)
			(end 0.8128 -0.4572)
			(stroke
				(width 0.1)
				(type default)
			)
			(layer "F.Fab")
		)
		(fp_line
			(start 0.8128 0.4572)
			(end -0.8128 0.4572)
			(stroke
				(width 0.1)
				(type default)
			)
			(layer "F.Fab")
		)
		(fp_line
			(start -0.8128 0.4572)
			(end -0.8128 -0.4572)
			(stroke
				(width 0.1)
				(type default)
			)
			(layer "F.Fab")
		)
		(pad "1" smd rect
			(at -0.6858 0 90)
			(size 0.762 0.8636)
			(layers "F.Cu" "F.Mask" "F.Paste")
			(net "XP3R3V")
		)
		(pad "2" smd rect
			(at 0.6858 0 90)
			(size 0.762 0.8636)
			(layers "F.Cu" "F.Mask" "F.Paste")
			(net "XP1R8V_VIN")
		)
		(zone
			(layer "F.Cu")
			(hatch none 0.5)
			(connect_pads
				(clearance 0)
			)
			(min_thickness 0.25)
			(keepout
				(tracks allowed)
				(vias not_allowed)
				(pads allowed)
				(copperpour not_allowed)
				(footprints allowed)
			)
			(placement
				(enabled no)
				(sheetname "")
			)
			(fill
				(thermal_gap 0.5)
				(thermal_bridge_width 0.5)
				(island_removal_mode 0)
			)
			(polygon
				(pts
					(xy 125.7554 -63.4746) (xy 124.841 -63.4746) (xy 124.841 -63.1698) (xy 125.7554 -63.1698)
				)
			)
		)
	)
	(footprint ""
		(layer "F.Cu")
		(at 98.298 -87.503 90)
		(property "Reference" "R464"
			(at 2.794 -0.59563 90)
			(unlocked yes)
			(layer "F.SilkS")
			(effects
				(font
					(size 0.7874 0.5842)
					(thickness 0.1524)
				)
			)
		)
		(property "Value" "VAL*"
			(at 0.02032 2.13233 90)
			(unlocked yes)
			(layer "F.Fab")
			(hide yes)
			(effects
				(font
					(size 0.7874 0.5842)
					(thickness 0.1524)
				)
			)
		)
		(property "Tolerance" "TOL*"
			(at 0.044704 3.05435 90)
			(unlocked yes)
			(layer "Cmts.User")
			(hide yes)
			(effects
				(font
					(size 0.7874 0.5842)
					(thickness 0.1524)
				)
			)
		)
		(property "User Part Number" "PARTNUM*"
			(at 0.02032 4.024884 90)
			(unlocked yes)
			(layer "Cmts.User")
			(hide yes)
			(effects
				(font
					(size 0.7874 0.5842)
					(thickness 0.1524)
				)
			)
		)
		(property "Device Type" "RESISTOR-G155-100R0-J0,0OHM,-"
			(at 0.008382 1.210564 90)
			(unlocked yes)
			(layer "F.Fab")
			(hide yes)
			(effects
				(font
					(size 0.7874 0.5842)
					(thickness 0.1524)
				)
			)
		)
		(duplicate_pad_numbers_are_jumpers no)
		(fp_line
			(start 1.143 -0.5588)
			(end -1.143 -0.5588)
			(stroke
				(width 0.1)
				(type default)
			)
			(layer "F.SilkS")
		)
		(fp_line
			(start -1.143 -0.5588)
			(end -1.143 0.5588)
			(stroke
				(width 0.1)
				(type default)
			)
			(layer "F.SilkS")
		)
		(fp_line
			(start 1.143 0.5588)
			(end 1.143 -0.5588)
			(stroke
				(width 0.1)
				(type default)
			)
			(layer "F.SilkS")
		)
		(fp_line
			(start -1.143 0.5588)
			(end 1.143 0.5588)
			(stroke
				(width 0.1)
				(type default)
			)
			(layer "F.SilkS")
		)
		(fp_poly
			(pts
				(xy -1.143 0.5588) (xy 1.143 0.5588) (xy 1.143 -0.5588) (xy -1.143 -0.5588)
			)
			(stroke
				(width 0)
				(type default)
			)
			(fill no)
			(layer "F.CrtYd")
		)
		(fp_line
			(start 0.508 -0.3048)
			(end -0.508 -0.3048)
			(stroke
				(width 0.1)
				(type default)
			)
			(layer "F.Fab")
		)
		(fp_line
			(start -0.508 -0.3048)
			(end -0.508 0.3048)
			(stroke
				(width 0.1)
				(type default)
			)
			(layer "F.Fab")
		)
		(fp_line
			(start 0.508 0.3048)
			(end 0.508 -0.3048)
			(stroke
				(width 0.1)
				(type default)
			)
			(layer "F.Fab")
		)
		(fp_line
			(start -0.508 0.3048)
			(end 0.508 0.3048)
			(stroke
				(width 0.1)
				(type default)
			)
			(layer "F.Fab")
		)
		(pad "1" smd rect
			(at -0.5334 0 90)
			(size 0.7112 0.6096)
			(layers "F.Cu" "F.Mask" "F.Paste")
			(net "FPGA_FLASH_DQ2")
		)
		(pad "2" smd rect
			(at 0.5334 0 90)
			(size 0.7112 0.6096)
			(layers "F.Cu" "F.Mask" "F.Paste")
			(net "FLASH_DQ2")
		)
		(zone
			(layer "F.Cu")
			(hatch none 0.5)
			(connect_pads
				(clearance 0)
			)
			(min_thickness 0.25)
			(keepout
				(tracks allowed)
				(vias not_allowed)
				(pads allowed)
				(copperpour not_allowed)
				(footprints allowed)
			)
			(placement
				(enabled no)
				(sheetname "")
			)
			(fill
				(thermal_gap 0.5)
				(thermal_bridge_width 0.5)
				(island_removal_mode 0)
			)
			(polygon
				(pts
					(xy 98.6028 -87.4268) (xy 98.6028 -87.5792) (xy 97.9932 -87.5792) (xy 97.9932 -87.4268)
				)
			)
		)
		(zone
			(layer "F.Cu")
			(hatch none 0.5)
			(connect_pads
				(clearance 0)
			)
			(min_thickness 0.25)
			(keepout
				(tracks not_allowed)
				(vias allowed)
				(pads allowed)
				(copperpour not_allowed)
				(footprints allowed)
			)
			(placement
				(enabled no)
				(sheetname "")
			)
			(fill
				(thermal_gap 0.5)
				(thermal_bridge_width 0.5)
				(island_removal_mode 0)
			)
			(polygon
				(pts
					(xy 98.6028 -87.4268) (xy 98.6028 -87.5792) (xy 97.9932 -87.5792) (xy 97.9932 -87.4268)
				)
			)
		)
	)
	(footprint ""
		(layer "F.Cu")
		(at 12.319 -22.987 90)
		(property "Reference" "R370"
			(at -0.635 -3.26263 90)
			(unlocked yes)
			(layer "F.SilkS")
			(effects
				(font
					(size 0.7874 0.5842)
					(thickness 0.1524)
				)
			)
		)
		(property "Value" "VAL*"
			(at 0.02032 2.13233 90)
			(unlocked yes)
			(layer "F.Fab")
			(hide yes)
			(effects
				(font
					(size 0.7874 0.5842)
					(thickness 0.1524)
				)
			)
		)
		(property "Tolerance" "TOL*"
			(at 0.044704 3.05435 90)
			(unlocked yes)
			(layer "Cmts.User")
			(hide yes)
			(effects
				(font
					(size 0.7874 0.5842)
					(thickness 0.1524)
				)
			)
		)
		(property "User Part Number" "PARTNUM*"
			(at 0.02032 4.024884 90)
			(unlocked yes)
			(layer "Cmts.User")
			(hide yes)
			(effects
				(font
					(size 0.7874 0.5842)
					(thickness 0.1524)
				)
			)
		)
		(property "Device Type" "RESISTOR-G155-149R9-01,49.9OHMA"
			(at 0.008382 1.210564 90)
			(unlocked yes)
			(layer "F.Fab")
			(hide yes)
			(effects
				(font
					(size 0.7874 0.5842)
					(thickness 0.1524)
				)
			)
		)
		(duplicate_pad_numbers_are_jumpers no)
		(fp_line
			(start 1.143 -0.5588)
			(end -1.143 -0.5588)
			(stroke
				(width 0.1)
				(type default)
			)
			(layer "F.SilkS")
		)
		(fp_line
			(start -1.143 -0.5588)
			(end -1.143 0.5588)
			(stroke
				(width 0.1)
				(type default)
			)
			(layer "F.SilkS")
		)
		(fp_line
			(start 1.143 0.5588)
			(end 1.143 -0.5588)
			(stroke
				(width 0.1)
				(type default)
			)
			(layer "F.SilkS")
		)
		(fp_line
			(start -1.143 0.5588)
			(end 1.143 0.5588)
			(stroke
				(width 0.1)
				(type default)
			)
			(layer "F.SilkS")
		)
		(fp_poly
			(pts
				(xy -1.143 0.5588) (xy 1.143 0.5588) (xy 1.143 -0.5588) (xy -1.143 -0.5588)
			)
			(stroke
				(width 0)
				(type default)
			)
			(fill no)
			(layer "F.CrtYd")
		)
		(fp_line
			(start 0.508 -0.3048)
			(end -0.508 -0.3048)
			(stroke
				(width 0.1)
				(type default)
			)
			(layer "F.Fab")
		)
		(fp_line
			(start -0.508 -0.3048)
			(end -0.508 0.3048)
			(stroke
				(width 0.1)
				(type default)
			)
			(layer "F.Fab")
		)
		(fp_line
			(start 0.508 0.3048)
			(end 0.508 -0.3048)
			(stroke
				(width 0.1)
				(type default)
			)
			(layer "F.Fab")
		)
		(fp_line
			(start -0.508 0.3048)
			(end 0.508 0.3048)
			(stroke
				(width 0.1)
				(type default)
			)
			(layer "F.Fab")
		)
		(pad "1" smd rect
			(at -0.5334 0 90)
			(size 0.7112 0.6096)
			(layers "F.Cu" "F.Mask" "F.Paste")
			(net "BF_ANT4_IN")
		)
		(pad "2" smd rect
			(at 0.5334 0 90)
			(size 0.7112 0.6096)
			(layers "F.Cu" "F.Mask" "F.Paste")
			(net "ANT4_IN")
		)
		(zone
			(layer "F.Cu")
			(hatch none 0.5)
			(connect_pads
				(clearance 0)
			)
			(min_thickness 0.25)
			(keepout
				(tracks allowed)
				(vias not_allowed)
				(pads allowed)
				(copperpour not_allowed)
				(footprints allowed)
			)
			(placement
				(enabled no)
				(sheetname "")
			)
			(fill
				(thermal_gap 0.5)
				(thermal_bridge_width 0.5)
				(island_removal_mode 0)
			)
			(polygon
				(pts
					(xy 12.6238 -22.9108) (xy 12.6238 -23.0632) (xy 12.0142 -23.0632) (xy 12.0142 -22.9108)
				)
			)
		)
		(zone
			(layer "F.Cu")
			(hatch none 0.5)
			(connect_pads
				(clearance 0)
			)
			(min_thickness 0.25)
			(keepout
				(tracks not_allowed)
				(vias allowed)
				(pads allowed)
				(copperpour not_allowed)
				(footprints allowed)
			)
			(placement
				(enabled no)
				(sheetname "")
			)
			(fill
				(thermal_gap 0.5)
				(thermal_bridge_width 0.5)
				(island_removal_mode 0)
			)
			(polygon
				(pts
					(xy 12.6238 -22.9108) (xy 12.6238 -23.0632) (xy 12.0142 -23.0632) (xy 12.0142 -22.9108)
				)
			)
		)
	)
	(footprint ""
		(layer "F.Cu")
		(at 46.482 -127.127)
		(property "Reference" "SP66"
			(at 0 0 0)
			(layer "F.SilkS")
			(hide yes)
			(effects
				(font
					(size 1.27 1.27)
				)
			)
		)
		(property "Value" ""
			(at 0 0 0)
			(layer "F.Fab")
			(effects
				(font
					(size 1.27 1.27)
				)
			)
		)
		(duplicate_pad_numbers_are_jumpers no)
	)
	(footprint ""
		(layer "F.Cu")
		(at 122.3264 -31.9532 90)
		(property "Reference" "TP201"
			(at -1.50495 -0.3302 0)
			(unlocked yes)
			(layer "F.SilkS")
			(effects
				(font
					(size 0.635 0.4064)
					(thickness 0.1524)
				)
				(justify left)
			)
		)
		(property "Value" ""
			(at 0 0 90)
			(layer "F.Fab")
			(effects
				(font
					(size 1.27 1.27)
				)
			)
		)
		(property "Device Type" "TP_PIONT-TP010CT020B030_PTH-TPA"
			(at -1.341882 0.996696 90)
			(unlocked yes)
			(layer "F.Fab")
			(hide yes)
			(effects
				(font
					(size 0.7874 0.5842)
					(thickness 0.1524)
				)
				(justify left)
			)
		)
		(duplicate_pad_numbers_are_jumpers no)
		(fp_poly
			(pts
				(arc
					(start 0 0.889)
					(mid 0 -0.889)
					(end 0 0.889)
				)
			)
			(stroke
				(width 0)
				(type default)
			)
			(fill no)
			(layer "B.CrtYd")
		)
		(fp_poly
			(pts
				(arc
					(start 0 0.889)
					(mid 0 -0.889)
					(end 0 0.889)
				)
			)
			(stroke
				(width 0)
				(type default)
			)
			(fill no)
			(layer "F.CrtYd")
		)
		(pad "1" thru_hole circle
			(at 0 0 90)
			(size 0.508 0.508)
			(drill 0.254)
			(layers "*.Cu" "*.Mask")
			(remove_unused_layers no)
			(net "IO_L22P_35")
			(clearance 0.1016)
			(padstack
				(mode front_inner_back)
				(layer "Inner"
					(shape circle)
					(size 0.508 0.508)
					(clearance 0.1016)
				)
				(layer "B.Cu"
					(shape circle)
					(size 0.762 0.762)
					(clearance -0.0254)
				)
			)
		)
	)
	(footprint ""
		(layer "F.Cu")
		(at 106.9086 -64.2874 -90)
		(property "Reference" "R325"
			(at 0.0254 -2.22377 90)
			(unlocked yes)
			(layer "F.SilkS")
			(effects
				(font
					(size 0.7874 0.5842)
					(thickness 0.1524)
				)
			)
		)
		(property "Value" "VAL*"
			(at 0.02032 2.13233 270)
			(unlocked yes)
			(layer "F.Fab")
			(hide yes)
			(effects
				(font
					(size 0.7874 0.5842)
					(thickness 0.1524)
				)
			)
		)
		(property "Tolerance" "TOL*"
			(at 0.044704 3.05435 270)
			(unlocked yes)
			(layer "Cmts.User")
			(hide yes)
			(effects
				(font
					(size 0.7874 0.5842)
					(thickness 0.1524)
				)
			)
		)
		(property "User Part Number" "PARTNUM*"
			(at 0.02032 4.024884 270)
			(unlocked yes)
			(layer "Cmts.User")
			(hide yes)
			(effects
				(font
					(size 0.7874 0.5842)
					(thickness 0.1524)
				)
			)
		)
		(property "Device Type" "RESISTOR-G155-11002-01,10KOHM,A"
			(at 0.008382 1.210564 270)
			(unlocked yes)
			(layer "F.Fab")
			(hide yes)
			(effects
				(font
					(size 0.7874 0.5842)
					(thickness 0.1524)
				)
			)
		)
		(duplicate_pad_numbers_are_jumpers no)
		(fp_line
			(start -1.143 0.5588)
			(end 1.143 0.5588)
			(stroke
				(width 0.1)
				(type default)
			)
			(layer "F.SilkS")
		)
		(fp_line
			(start 1.143 0.5588)
			(end 1.143 -0.5588)
			(stroke
				(width 0.1)
				(type default)
			)
			(layer "F.SilkS")
		)
		(fp_line
			(start -1.143 -0.5588)
			(end -1.143 0.5588)
			(stroke
				(width 0.1)
				(type default)
			)
			(layer "F.SilkS")
		)
		(fp_line
			(start 1.143 -0.5588)
			(end -1.143 -0.5588)
			(stroke
				(width 0.1)
				(type default)
			)
			(layer "F.SilkS")
		)
		(fp_poly
			(pts
				(xy -1.143 0.5588) (xy 1.143 0.5588) (xy 1.143 -0.5588) (xy -1.143 -0.5588)
			)
			(stroke
				(width 0)
				(type default)
			)
			(fill no)
			(layer "F.CrtYd")
		)
		(fp_line
			(start -0.508 0.3048)
			(end 0.508 0.3048)
			(stroke
				(width 0.1)
				(type default)
			)
			(layer "F.Fab")
		)
		(fp_line
			(start 0.508 0.3048)
			(end 0.508 -0.3048)
			(stroke
				(width 0.1)
				(type default)
			)
			(layer "F.Fab")
		)
		(fp_line
			(start -0.508 -0.3048)
			(end -0.508 0.3048)
			(stroke
				(width 0.1)
				(type default)
			)
			(layer "F.Fab")
		)
		(fp_line
			(start 0.508 -0.3048)
			(end -0.508 -0.3048)
			(stroke
				(width 0.1)
				(type default)
			)
			(layer "F.Fab")
		)
		(pad "1" smd rect
			(at -0.5334 0 270)
			(size 0.7112 0.6096)
			(layers "F.Cu" "F.Mask" "F.Paste")
			(net "XP3R3V_FPGA")
		)
		(pad "2" smd rect
			(at 0.5334 0 270)
			(size 0.7112 0.6096)
			(layers "F.Cu" "F.Mask" "F.Paste")
			(net "FPGA_IO_6")
		)
		(zone
			(layer "F.Cu")
			(hatch none 0.5)
			(connect_pads
				(clearance 0)
			)
			(min_thickness 0.25)
			(keepout
				(tracks allowed)
				(vias not_allowed)
				(pads allowed)
				(copperpour not_allowed)
				(footprints allowed)
			)
			(placement
				(enabled no)
				(sheetname "")
			)
			(fill
				(thermal_gap 0.5)
				(thermal_bridge_width 0.5)
				(island_removal_mode 0)
			)
			(polygon
				(pts
					(xy 106.6038 -64.3636) (xy 106.6038 -64.2112) (xy 107.2134 -64.2112) (xy 107.2134 -64.3636)
				)
			)
		)
		(zone
			(layer "F.Cu")
			(hatch none 0.5)
			(connect_pads
				(clearance 0)
			)
			(min_thickness 0.25)
			(keepout
				(tracks not_allowed)
				(vias allowed)
				(pads allowed)
				(copperpour not_allowed)
				(footprints allowed)
			)
			(placement
				(enabled no)
				(sheetname "")
			)
			(fill
				(thermal_gap 0.5)
				(thermal_bridge_width 0.5)
				(island_removal_mode 0)
			)
			(polygon
				(pts
					(xy 106.6038 -64.3636) (xy 106.6038 -64.2112) (xy 107.2134 -64.2112) (xy 107.2134 -64.3636)
				)
			)
		)
	)
	(footprint ""
		(layer "F.Cu")
		(at 139.8524 -90.6526 180)
		(property "Reference" "FU1"
			(at 2.4384 -0.39497 0)
			(unlocked yes)
			(layer "F.SilkS")
			(effects
				(font
					(size 0.7874 0.5842)
					(thickness 0.1524)
				)
			)
		)
		(property "Value" "VAL*"
			(at 0.0508 2.549906 180)
			(unlocked yes)
			(layer "F.Fab")
			(hide yes)
			(effects
				(font
					(size 0.7874 0.5842)
					(thickness 0.1524)
				)
			)
		)
		(property "Device Type" "FUSE-G280-10012-01,2.5A"
			(at 0.0254 1.584706 180)
			(unlocked yes)
			(layer "F.Fab")
			(hide yes)
			(effects
				(font
					(size 0.7874 0.5842)
					(thickness 0.1524)
				)
			)
		)
		(property "User Part Number" "PARTNUM*"
			(at 0.0762 4.480306 180)
			(unlocked yes)
			(layer "Cmts.User")
			(hide yes)
			(effects
				(font
					(size 0.7874 0.5842)
					(thickness 0.1524)
				)
			)
		)
		(property "Tolerance" "TOL*"
			(at 0.0508 3.515106 180)
			(unlocked yes)
			(layer "Cmts.User")
			(hide yes)
			(effects
				(font
					(size 0.7874 0.5842)
					(thickness 0.1524)
				)
			)
		)
		(duplicate_pad_numbers_are_jumpers no)
		(fp_line
			(start 1.3208 0.7112)
			(end -1.3208 0.7112)
			(stroke
				(width 0.1)
				(type default)
			)
			(layer "F.SilkS")
		)
		(fp_line
			(start 1.3208 -0.7112)
			(end 1.3208 0.7112)
			(stroke
				(width 0.1)
				(type default)
			)
			(layer "F.SilkS")
		)
		(fp_line
			(start -1.3208 0.7112)
			(end -1.3208 -0.7112)
			(stroke
				(width 0.1)
				(type default)
			)
			(layer "F.SilkS")
		)
		(fp_line
			(start -1.3208 -0.7112)
			(end 1.3208 -0.7112)
			(stroke
				(width 0.1)
				(type default)
			)
			(layer "F.SilkS")
		)
		(fp_rect
			(start 1.3208 -0.7112)
			(end -1.3208 0.7112)
			(stroke
				(width 0)
				(type default)
			)
			(fill no)
			(layer "F.CrtYd")
		)
		(fp_line
			(start 0.8128 0.4572)
			(end -0.8128 0.4572)
			(stroke
				(width 0.1)
				(type default)
			)
			(layer "F.Fab")
		)
		(fp_line
			(start 0.8128 -0.4572)
			(end 0.8128 0.4572)
			(stroke
				(width 0.1)
				(type default)
			)
			(layer "F.Fab")
		)
		(fp_line
			(start -0.8128 0.4572)
			(end -0.8128 -0.4572)
			(stroke
				(width 0.1)
				(type default)
			)
			(layer "F.Fab")
		)
		(fp_line
			(start -0.8128 -0.4572)
			(end 0.8128 -0.4572)
			(stroke
				(width 0.1)
				(type default)
			)
			(layer "F.Fab")
		)
		(pad "1" smd rect
			(at -0.6858 0 180)
			(size 0.762 0.8636)
			(layers "F.Cu" "F.Mask" "F.Paste")
			(net "XP12R0V_IN")
		)
		(pad "2" smd rect
			(at 0.6858 0 180)
			(size 0.762 0.8636)
			(layers "F.Cu" "F.Mask" "F.Paste")
			(net "XP12R0V")
		)
		(zone
			(layer "F.Cu")
			(hatch none 0.5)
			(connect_pads
				(clearance 0)
			)
			(min_thickness 0.25)
			(keepout
				(tracks allowed)
				(vias not_allowed)
				(pads allowed)
				(copperpour not_allowed)
				(footprints allowed)
			)
			(placement
				(enabled no)
				(sheetname "")
			)
			(fill
				(thermal_gap 0.5)
				(thermal_bridge_width 0.5)
				(island_removal_mode 0)
			)
			(polygon
				(pts
					(xy 139.7 -90.1954) (xy 140.0048 -90.1954) (xy 140.0048 -91.1098) (xy 139.7 -91.1098)
				)
			)
		)
	)
	(footprint ""
		(layer "F.Cu")
		(at 52.451 -131.699)
		(property "Reference" "SP33"
			(at 0 0 0)
			(layer "F.SilkS")
			(hide yes)
			(effects
				(font
					(size 1.27 1.27)
				)
			)
		)
		(property "Value" ""
			(at 0 0 0)
			(layer "F.Fab")
			(effects
				(font
					(size 1.27 1.27)
				)
			)
		)
		(duplicate_pad_numbers_are_jumpers no)
	)
	(footprint ""
		(layer "F.Cu")
		(at 115.443 -73.533)
		(property "Reference" "C235"
			(at 3.302 0.42037 0)
			(unlocked yes)
			(layer "F.SilkS")
			(effects
				(font
					(size 0.7874 0.5842)
					(thickness 0.1524)
				)
			)
		)
		(property "Value" "VAL*"
			(at 0.0762 2.067306 0)
			(unlocked yes)
			(layer "F.Fab")
			(hide yes)
			(effects
				(font
					(size 0.7874 0.5842)
					(thickness 0.1524)
				)
			)
		)
		(property "Tolerance" "TOL*"
			(at 0.0762 3.032506 0)
			(unlocked yes)
			(layer "Cmts.User")
			(hide yes)
			(effects
				(font
					(size 0.7874 0.5842)
					(thickness 0.1524)
				)
			)
		)
		(property "User Part Number" "PARTNUM*"
			(at 0.1016 4.023106 0)
			(unlocked yes)
			(layer "Cmts.User")
			(hide yes)
			(effects
				(font
					(size 0.7874 0.5842)
					(thickness 0.1524)
				)
			)
		)
		(property "Device Type" "CAPACITOR-G105-0B104-CK,0.1UF,A"
			(at 0.0508 1.127506 0)
			(unlocked yes)
			(layer "F.Fab")
			(hide yes)
			(effects
				(font
					(size 0.7874 0.5842)
					(thickness 0.1524)
				)
			)
		)
		(duplicate_pad_numbers_are_jumpers no)
		(fp_line
			(start -1.143 -0.5588)
			(end -1.143 0.5588)
			(stroke
				(width 0.1)
				(type default)
			)
			(layer "F.SilkS")
		)
		(fp_line
			(start -1.143 0.5588)
			(end 1.143 0.5588)
			(stroke
				(width 0.1)
				(type default)
			)
			(layer "F.SilkS")
		)
		(fp_line
			(start 1.143 -0.5588)
			(end -1.143 -0.5588)
			(stroke
				(width 0.1)
				(type default)
			)
			(layer "F.SilkS")
		)
		(fp_line
			(start 1.143 0.5588)
			(end 1.143 -0.5588)
			(stroke
				(width 0.1)
				(type default)
			)
			(layer "F.SilkS")
		)
		(fp_rect
			(start 1.143 0.5588)
			(end -1.143 -0.5588)
			(stroke
				(width 0)
				(type default)
			)
			(fill no)
			(layer "F.CrtYd")
		)
		(fp_line
			(start -0.508 -0.3048)
			(end -0.508 0.3048)
			(stroke
				(width 0.1)
				(type default)
			)
			(layer "F.Fab")
		)
		(fp_line
			(start -0.508 0.3048)
			(end 0.508 0.3048)
			(stroke
				(width 0.1)
				(type default)
			)
			(layer "F.Fab")
		)
		(fp_line
			(start 0.508 -0.3048)
			(end -0.508 -0.3048)
			(stroke
				(width 0.1)
				(type default)
			)
			(layer "F.Fab")
		)
		(fp_line
			(start 0.508 0.3048)
			(end 0.508 -0.3048)
			(stroke
				(width 0.1)
				(type default)
			)
			(layer "F.Fab")
		)
		(pad "1" smd rect
			(at -0.5334 0)
			(size 0.7112 0.6096)
			(layers "F.Cu" "F.Mask" "F.Paste")
			(net "XP3R3V")
		)
		(pad "2" smd rect
			(at 0.5334 0)
			(size 0.7112 0.6096)
			(layers "F.Cu" "F.Mask" "F.Paste")
			(net "SG")
		)
		(zone
			(layer "F.Cu")
			(hatch none 0.5)
			(connect_pads
				(clearance 0)
			)
			(min_thickness 0.25)
			(keepout
				(tracks allowed)
				(vias not_allowed)
				(pads allowed)
				(copperpour not_allowed)
				(footprints allowed)
			)
			(placement
				(enabled no)
				(sheetname "")
			)
			(fill
				(thermal_gap 0.5)
				(thermal_bridge_width 0.5)
				(island_removal_mode 0)
			)
			(polygon
				(pts
					(xy 115.5192 -73.2282) (xy 115.5192 -73.8378) (xy 115.3668 -73.8378) (xy 115.3668 -73.2282)
				)
			)
		)
	)
	(footprint ""
		(layer "F.Cu")
		(at 14.605 -52.578 -90)
		(property "Reference" "R331"
			(at 0.508 3.51663 90)
			(unlocked yes)
			(layer "F.SilkS")
			(effects
				(font
					(size 0.7874 0.5842)
					(thickness 0.1524)
				)
			)
		)
		(property "Value" "VAL*"
			(at 0.02032 2.13233 270)
			(unlocked yes)
			(layer "F.Fab")
			(hide yes)
			(effects
				(font
					(size 0.7874 0.5842)
					(thickness 0.1524)
				)
			)
		)
		(property "Device Type" "RESISTOR-G155-14701-01,4.7KOHMA"
			(at 0.008382 1.210564 270)
			(unlocked yes)
			(layer "F.Fab")
			(hide yes)
			(effects
				(font
					(size 0.7874 0.5842)
					(thickness 0.1524)
				)
			)
		)
		(property "User Part Number" "PARTNUM*"
			(at 0.02032 4.024884 270)
			(unlocked yes)
			(layer "Cmts.User")
			(hide yes)
			(effects
				(font
					(size 0.7874 0.5842)
					(thickness 0.1524)
				)
			)
		)
		(property "Tolerance" "TOL*"
			(at 0.044704 3.05435 270)
			(unlocked yes)
			(layer "Cmts.User")
			(hide yes)
			(effects
				(font
					(size 0.7874 0.5842)
					(thickness 0.1524)
				)
			)
		)
		(duplicate_pad_numbers_are_jumpers no)
		(fp_line
			(start -1.143 0.5588)
			(end 1.143 0.5588)
			(stroke
				(width 0.1)
				(type default)
			)
			(layer "F.SilkS")
		)
		(fp_line
			(start 1.143 0.5588)
			(end 1.143 -0.5588)
			(stroke
				(width 0.1)
				(type default)
			)
			(layer "F.SilkS")
		)
		(fp_line
			(start -1.143 -0.5588)
			(end -1.143 0.5588)
			(stroke
				(width 0.1)
				(type default)
			)
			(layer "F.SilkS")
		)
		(fp_line
			(start 1.143 -0.5588)
			(end -1.143 -0.5588)
			(stroke
				(width 0.1)
				(type default)
			)
			(layer "F.SilkS")
		)
		(fp_rect
			(start 1.143 0.5588)
			(end -1.143 -0.5588)
			(stroke
				(width 0)
				(type default)
			)
			(fill no)
			(layer "F.CrtYd")
		)
		(fp_line
			(start -0.508 0.3048)
			(end 0.508 0.3048)
			(stroke
				(width 0.1)
				(type default)
			)
			(layer "F.Fab")
		)
		(fp_line
			(start 0.508 0.3048)
			(end 0.508 -0.3048)
			(stroke
				(width 0.1)
				(type default)
			)
			(layer "F.Fab")
		)
		(fp_line
			(start -0.508 -0.3048)
			(end -0.508 0.3048)
			(stroke
				(width 0.1)
				(type default)
			)
			(layer "F.Fab")
		)
		(fp_line
			(start 0.508 -0.3048)
			(end -0.508 -0.3048)
			(stroke
				(width 0.1)
				(type default)
			)
			(layer "F.Fab")
		)
		(pad "1" smd rect
			(at -0.5334 0 270)
			(size 0.7112 0.6096)
			(layers "F.Cu" "F.Mask" "F.Paste")
			(net "XP3R3V_FPGA")
		)
		(pad "2" smd rect
			(at 0.5334 0 270)
			(size 0.7112 0.6096)
			(layers "F.Cu" "F.Mask" "F.Paste")
			(net "SMA2_SIG_OUT_BF_EN_N")
		)
		(zone
			(layer "F.Cu")
			(hatch none 0.5)
			(connect_pads
				(clearance 0)
			)
			(min_thickness 0.25)
			(keepout
				(tracks allowed)
				(vias not_allowed)
				(pads allowed)
				(copperpour not_allowed)
				(footprints allowed)
			)
			(placement
				(enabled no)
				(sheetname "")
			)
			(fill
				(thermal_gap 0.5)
				(thermal_bridge_width 0.5)
				(island_removal_mode 0)
			)
			(polygon
				(pts
					(xy 14.3002 -52.5018) (xy 14.9098 -52.5018) (xy 14.9098 -52.6542) (xy 14.3002 -52.6542)
				)
			)
		)
	)
	(footprint ""
		(layer "F.Cu")
		(at 57.15 -100.584)
		(property "Reference" "TP60"
			(at 1.651 0.15367 0)
			(unlocked yes)
			(layer "F.SilkS")
			(effects
				(font
					(size 0.7874 0.5842)
					(thickness 0.1524)
				)
				(justify left)
			)
		)
		(property "Value" ""
			(at 0 0 0)
			(layer "F.Fab")
			(effects
				(font
					(size 1.27 1.27)
				)
			)
		)
		(property "Device Type" "TP_PIONT-TP010CT020B030_PTH-TPA"
			(at -1.341882 0.996696 0)
			(unlocked yes)
			(layer "F.Fab")
			(hide yes)
			(effects
				(font
					(size 0.7874 0.5842)
					(thickness 0.1524)
				)
				(justify left)
			)
		)
		(duplicate_pad_numbers_are_jumpers no)
		(fp_poly
			(pts
				(arc
					(start 0.889 0)
					(mid -0.889 0)
					(end 0.889 0)
				)
			)
			(stroke
				(width 0)
				(type default)
			)
			(fill no)
			(layer "B.CrtYd")
		)
		(fp_poly
			(pts
				(arc
					(start 0.889 0)
					(mid -0.889 0)
					(end 0.889 0)
				)
			)
			(stroke
				(width 0)
				(type default)
			)
			(fill no)
			(layer "F.CrtYd")
		)
		(pad "1" thru_hole circle
			(at 0 0)
			(size 0.508 0.508)
			(drill 0.254)
			(layers "*.Cu" "*.Mask")
			(remove_unused_layers no)
			(net "XP5R0V")
			(clearance 0.1016)
			(padstack
				(mode front_inner_back)
				(layer "Inner"
					(shape circle)
					(size 0.508 0.508)
					(clearance 0.1016)
				)
				(layer "B.Cu"
					(shape circle)
					(size 0.762 0.762)
					(clearance -0.0254)
				)
			)
		)
	)
	(footprint ""
		(layer "F.Cu")
		(at 110.3757 -28.5242 180)
		(property "Reference" "R360"
			(at 2.00533 -0.8382 90)
			(unlocked yes)
			(layer "F.SilkS")
			(effects
				(font
					(size 0.7874 0.5842)
					(thickness 0.1524)
				)
			)
		)
		(property "Value" "VAL*"
			(at 0.02032 2.13233 180)
			(unlocked yes)
			(layer "F.Fab")
			(hide yes)
			(effects
				(font
					(size 0.7874 0.5842)
					(thickness 0.1524)
				)
			)
		)
		(property "Tolerance" "TOL*"
			(at 0.044704 3.05435 180)
			(unlocked yes)
			(layer "Cmts.User")
			(hide yes)
			(effects
				(font
					(size 0.7874 0.5842)
					(thickness 0.1524)
				)
			)
		)
		(property "User Part Number" "PARTNUM*"
			(at 0.02032 4.024884 180)
			(unlocked yes)
			(layer "Cmts.User")
			(hide yes)
			(effects
				(font
					(size 0.7874 0.5842)
					(thickness 0.1524)
				)
			)
		)
		(property "Device Type" "RESISTOR-G155-11002-01,10KOHM,A"
			(at 0.008382 1.210564 180)
			(unlocked yes)
			(layer "F.Fab")
			(hide yes)
			(effects
				(font
					(size 0.7874 0.5842)
					(thickness 0.1524)
				)
			)
		)
		(duplicate_pad_numbers_are_jumpers no)
		(fp_line
			(start 1.143 0.5588)
			(end 1.143 -0.5588)
			(stroke
				(width 0.1)
				(type default)
			)
			(layer "F.SilkS")
		)
		(fp_line
			(start 1.143 -0.5588)
			(end -1.143 -0.5588)
			(stroke
				(width 0.1)
				(type default)
			)
			(layer "F.SilkS")
		)
		(fp_line
			(start -1.143 0.5588)
			(end 1.143 0.5588)
			(stroke
				(width 0.1)
				(type default)
			)
			(layer "F.SilkS")
		)
		(fp_line
			(start -1.143 -0.5588)
			(end -1.143 0.5588)
			(stroke
				(width 0.1)
				(type default)
			)
			(layer "F.SilkS")
		)
		(fp_poly
			(pts
				(xy -1.143 0.5588) (xy 1.143 0.5588) (xy 1.143 -0.5588) (xy -1.143 -0.5588)
			)
			(stroke
				(width 0)
				(type default)
			)
			(fill no)
			(layer "F.CrtYd")
		)
		(fp_line
			(start 0.508 0.3048)
			(end 0.508 -0.3048)
			(stroke
				(width 0.1)
				(type default)
			)
			(layer "F.Fab")
		)
		(fp_line
			(start 0.508 -0.3048)
			(end -0.508 -0.3048)
			(stroke
				(width 0.1)
				(type default)
			)
			(layer "F.Fab")
		)
		(fp_line
			(start -0.508 0.3048)
			(end 0.508 0.3048)
			(stroke
				(width 0.1)
				(type default)
			)
			(layer "F.Fab")
		)
		(fp_line
			(start -0.508 -0.3048)
			(end -0.508 0.3048)
			(stroke
				(width 0.1)
				(type default)
			)
			(layer "F.Fab")
		)
		(pad "1" smd rect
			(at -0.5334 0 180)
			(size 0.7112 0.6096)
			(layers "F.Cu" "F.Mask" "F.Paste")
			(net "MHZ200CLKN_CLKIN")
		)
		(pad "2" smd rect
			(at 0.5334 0 180)
			(size 0.7112 0.6096)
			(layers "F.Cu" "F.Mask" "F.Paste")
			(net "SG")
		)
		(zone
			(layer "F.Cu")
			(hatch none 0.5)
			(connect_pads
				(clearance 0)
			)
			(min_thickness 0.25)
			(keepout
				(tracks not_allowed)
				(vias allowed)
				(pads allowed)
				(copperpour not_allowed)
				(footprints allowed)
			)
			(placement
				(enabled no)
				(sheetname "")
			)
			(fill
				(thermal_gap 0.5)
				(thermal_bridge_width 0.5)
				(island_removal_mode 0)
			)
			(polygon
				(pts
					(xy 110.4519 -28.829) (xy 110.2995 -28.829) (xy 110.2995 -28.2194) (xy 110.4519 -28.2194)
				)
			)
		)
		(zone
			(layer "F.Cu")
			(hatch none 0.5)
			(connect_pads
				(clearance 0)
			)
			(min_thickness 0.25)
			(keepout
				(tracks allowed)
				(vias not_allowed)
				(pads allowed)
				(copperpour not_allowed)
				(footprints allowed)
			)
			(placement
				(enabled no)
				(sheetname "")
			)
			(fill
				(thermal_gap 0.5)
				(thermal_bridge_width 0.5)
				(island_removal_mode 0)
			)
			(polygon
				(pts
					(xy 110.4519 -28.829) (xy 110.2995 -28.829) (xy 110.2995 -28.2194) (xy 110.4519 -28.2194)
				)
			)
		)
	)
	(footprint ""
		(layer "F.Cu")
		(at 18.034 -83.947 -90)
		(property "Reference" "TP4"
			(at 0 0 270)
			(layer "F.SilkS")
			(hide yes)
			(effects
				(font
					(size 1.27 1.27)
				)
			)
		)
		(property "Value" ""
			(at 0 0 270)
			(layer "F.Fab")
			(effects
				(font
					(size 1.27 1.27)
				)
			)
		)
		(property "Device Type" "TP_PIONT-TP010CT020B030_PTH-TPA"
			(at -1.341882 0.996696 270)
			(unlocked yes)
			(layer "F.Fab")
			(hide yes)
			(effects
				(font
					(size 0.7874 0.5842)
					(thickness 0.1524)
				)
				(justify left)
			)
		)
		(duplicate_pad_numbers_are_jumpers no)
		(fp_poly
			(pts
				(arc
					(start 0 -0.889)
					(mid 0 0.889)
					(end 0 -0.889)
				)
			)
			(stroke
				(width 0)
				(type default)
			)
			(fill no)
			(layer "B.CrtYd")
		)
		(fp_poly
			(pts
				(arc
					(start 0 -0.889)
					(mid 0 0.889)
					(end 0 -0.889)
				)
			)
			(stroke
				(width 0)
				(type default)
			)
			(fill no)
			(layer "F.CrtYd")
		)
		(pad "1" thru_hole circle
			(at 0 0 270)
			(size 0.508 0.508)
			(drill 0.254)
			(layers "*.Cu" "*.Mask")
			(remove_unused_layers no)
			(net "XP5R0V_FT4232")
			(clearance 0.1016)
			(padstack
				(mode front_inner_back)
				(layer "Inner"
					(shape circle)
					(size 0.508 0.508)
					(clearance 0.1016)
				)
				(layer "B.Cu"
					(shape circle)
					(size 0.762 0.762)
					(clearance -0.0254)
				)
			)
		)
	)
	(footprint ""
		(layer "F.Cu")
		(at 25.273 -93.98)
		(property "Reference" "TP11"
			(at -0.08763 -0.8128 90)
			(unlocked yes)
			(layer "F.SilkS")
			(effects
				(font
					(size 0.7874 0.5842)
					(thickness 0.1524)
				)
				(justify left)
			)
		)
		(property "Value" ""
			(at 0 0 0)
			(layer "F.Fab")
			(effects
				(font
					(size 1.27 1.27)
				)
			)
		)
		(property "Device Type" "TP_PIONT-TP010CT020B030_PTH-TPA"
			(at -1.341882 0.996696 0)
			(unlocked yes)
			(layer "F.Fab")
			(hide yes)
			(effects
				(font
					(size 0.7874 0.5842)
					(thickness 0.000001)
				)
				(justify left)
			)
		)
		(duplicate_pad_numbers_are_jumpers no)
		(fp_poly
			(pts
				(arc
					(start 0.889 0)
					(mid -0.889 0)
					(end 0.889 0)
				)
			)
			(stroke
				(width 0)
				(type default)
			)
			(fill no)
			(layer "B.CrtYd")
		)
		(fp_poly
			(pts
				(arc
					(start 0.889 0)
					(mid -0.889 0)
					(end 0.889 0)
				)
			)
			(stroke
				(width 0)
				(type default)
			)
			(fill no)
			(layer "F.CrtYd")
		)
		(pad "1" thru_hole circle
			(at 0 0)
			(size 0.508 0.508)
			(drill 0.254)
			(layers "*.Cu" "*.Mask")
			(remove_unused_layers no)
			(net "FT_USB_DETECT")
			(clearance 0.1016)
			(padstack
				(mode front_inner_back)
				(layer "Inner"
					(shape circle)
					(size 0.508 0.508)
					(clearance 0.1016)
				)
				(layer "B.Cu"
					(shape circle)
					(size 0.762 0.762)
					(clearance -0.0254)
				)
			)
		)
	)
	(footprint ""
		(layer "F.Cu")
		(at 145.8214 -88.0618 180)
		(property "Reference" "R4"
			(at 0.2794 -7.71017 0)
			(unlocked yes)
			(layer "F.SilkS")
			(effects
				(font
					(size 0.7874 0.5842)
					(thickness 0.1524)
				)
			)
		)
		(property "Value" "VAL*"
			(at 0.02032 2.13233 180)
			(unlocked yes)
			(layer "F.Fab")
			(hide yes)
			(effects
				(font
					(size 0.7874 0.5842)
					(thickness 0.1524)
				)
			)
		)
		(property "Device Type" "RESISTOR-G155-11002-01,10KOHM,A"
			(at 0.008382 1.210564 180)
			(unlocked yes)
			(layer "F.Fab")
			(hide yes)
			(effects
				(font
					(size 0.7874 0.5842)
					(thickness 0.1524)
				)
			)
		)
		(property "User Part Number" "PARTNUM*"
			(at 0.02032 4.024884 180)
			(unlocked yes)
			(layer "Cmts.User")
			(hide yes)
			(effects
				(font
					(size 0.7874 0.5842)
					(thickness 0.1524)
				)
			)
		)
		(property "Tolerance" "TOL*"
			(at 0.044704 3.05435 180)
			(unlocked yes)
			(layer "Cmts.User")
			(hide yes)
			(effects
				(font
					(size 0.7874 0.5842)
					(thickness 0.1524)
				)
			)
		)
		(duplicate_pad_numbers_are_jumpers no)
		(fp_line
			(start 1.143 0.5588)
			(end 1.143 -0.5588)
			(stroke
				(width 0.1)
				(type default)
			)
			(layer "F.SilkS")
		)
		(fp_line
			(start 1.143 -0.5588)
			(end -1.143 -0.5588)
			(stroke
				(width 0.1)
				(type default)
			)
			(layer "F.SilkS")
		)
		(fp_line
			(start -1.143 0.5588)
			(end 1.143 0.5588)
			(stroke
				(width 0.1)
				(type default)
			)
			(layer "F.SilkS")
		)
		(fp_line
			(start -1.143 -0.5588)
			(end -1.143 0.5588)
			(stroke
				(width 0.1)
				(type default)
			)
			(layer "F.SilkS")
		)
		(fp_rect
			(start 1.143 0.5588)
			(end -1.143 -0.5588)
			(stroke
				(width 0)
				(type default)
			)
			(fill no)
			(layer "F.CrtYd")
		)
		(fp_line
			(start 0.508 0.3048)
			(end 0.508 -0.3048)
			(stroke
				(width 0.1)
				(type default)
			)
			(layer "F.Fab")
		)
		(fp_line
			(start 0.508 -0.3048)
			(end -0.508 -0.3048)
			(stroke
				(width 0.1)
				(type default)
			)
			(layer "F.Fab")
		)
		(fp_line
			(start -0.508 0.3048)
			(end 0.508 0.3048)
			(stroke
				(width 0.1)
				(type default)
			)
			(layer "F.Fab")
		)
		(fp_line
			(start -0.508 -0.3048)
			(end -0.508 0.3048)
			(stroke
				(width 0.1)
				(type default)
			)
			(layer "F.Fab")
		)
		(pad "1" smd rect
			(at -0.5334 0 180)
			(size 0.7112 0.6096)
			(layers "F.Cu" "F.Mask" "F.Paste")
			(net "XP12R0V_IN")
		)
		(pad "2" smd rect
			(at 0.5334 0 180)
			(size 0.7112 0.6096)
			(layers "F.Cu" "F.Mask" "F.Paste")
			(net "XP12R0V_A_EN")
		)
		(zone
			(layer "F.Cu")
			(hatch none 0.5)
			(connect_pads
				(clearance 0)
			)
			(min_thickness 0.25)
			(keepout
				(tracks allowed)
				(vias not_allowed)
				(pads allowed)
				(copperpour not_allowed)
				(footprints allowed)
			)
			(placement
				(enabled no)
				(sheetname "")
			)
			(fill
				(thermal_gap 0.5)
				(thermal_bridge_width 0.5)
				(island_removal_mode 0)
			)
			(polygon
				(pts
					(xy 145.7452 -88.3666) (xy 145.7452 -87.757) (xy 145.8976 -87.757) (xy 145.8976 -88.3666)
				)
			)
		)
	)
	(footprint ""
		(layer "F.Cu")
		(at 81.0006 -49.911 180)
		(property "Reference" "R86"
			(at 1.016 -14.64437 0)
			(unlocked yes)
			(layer "F.SilkS")
			(effects
				(font
					(size 0.7874 0.5842)
					(thickness 0.1524)
				)
			)
		)
		(property "Value" "VAL*"
			(at 0.02032 2.13233 180)
			(unlocked yes)
			(layer "F.Fab")
			(hide yes)
			(effects
				(font
					(size 0.7874 0.5842)
					(thickness 0.1524)
				)
			)
		)
		(property "Tolerance" "TOL*"
			(at 0.044704 3.05435 180)
			(unlocked yes)
			(layer "Cmts.User")
			(hide yes)
			(effects
				(font
					(size 0.7874 0.5842)
					(thickness 0.1524)
				)
			)
		)
		(property "User Part Number" "PARTNUM*"
			(at 0.02032 4.024884 180)
			(unlocked yes)
			(layer "Cmts.User")
			(hide yes)
			(effects
				(font
					(size 0.7874 0.5842)
					(thickness 0.1524)
				)
			)
		)
		(property "Device Type" "RESISTOR-G155-100R0-J0,0OHM,-"
			(at 0.008382 1.210564 180)
			(unlocked yes)
			(layer "F.Fab")
			(hide yes)
			(effects
				(font
					(size 0.7874 0.5842)
					(thickness 0.1524)
				)
			)
		)
		(duplicate_pad_numbers_are_jumpers no)
		(fp_line
			(start 1.143 0.5588)
			(end 1.143 -0.5588)
			(stroke
				(width 0.1)
				(type default)
			)
			(layer "F.SilkS")
		)
		(fp_line
			(start 1.143 -0.5588)
			(end -1.143 -0.5588)
			(stroke
				(width 0.1)
				(type default)
			)
			(layer "F.SilkS")
		)
		(fp_line
			(start -1.143 0.5588)
			(end 1.143 0.5588)
			(stroke
				(width 0.1)
				(type default)
			)
			(layer "F.SilkS")
		)
		(fp_line
			(start -1.143 -0.5588)
			(end -1.143 0.5588)
			(stroke
				(width 0.1)
				(type default)
			)
			(layer "F.SilkS")
		)
		(fp_rect
			(start 1.143 -0.5588)
			(end -1.143 0.5588)
			(stroke
				(width 0)
				(type default)
			)
			(fill no)
			(layer "F.CrtYd")
		)
		(fp_line
			(start 0.508 0.3048)
			(end 0.508 -0.3048)
			(stroke
				(width 0.1)
				(type default)
			)
			(layer "F.Fab")
		)
		(fp_line
			(start 0.508 -0.3048)
			(end -0.508 -0.3048)
			(stroke
				(width 0.1)
				(type default)
			)
			(layer "F.Fab")
		)
		(fp_line
			(start -0.508 0.3048)
			(end 0.508 0.3048)
			(stroke
				(width 0.1)
				(type default)
			)
			(layer "F.Fab")
		)
		(fp_line
			(start -0.508 -0.3048)
			(end -0.508 0.3048)
			(stroke
				(width 0.1)
				(type default)
			)
			(layer "F.Fab")
		)
		(pad "1" smd rect
			(at -0.5334 0 180)
			(size 0.7112 0.6096)
			(layers "F.Cu" "F.Mask" "F.Paste")
			(net "FPGA_OUT_MAC_PPS_IN0N")
		)
		(pad "2" smd rect
			(at 0.5334 0 180)
			(size 0.7112 0.6096)
			(layers "F.Cu" "F.Mask" "F.Paste")
			(net "R_MAC_PPS_IN0N")
		)
		(zone
			(layer "F.Cu")
			(hatch none 0.5)
			(connect_pads
				(clearance 0)
			)
			(min_thickness 0.25)
			(keepout
				(tracks allowed)
				(vias not_allowed)
				(pads allowed)
				(copperpour not_allowed)
				(footprints allowed)
			)
			(placement
				(enabled no)
				(sheetname "")
			)
			(fill
				(thermal_gap 0.5)
				(thermal_bridge_width 0.5)
				(island_removal_mode 0)
			)
			(polygon
				(pts
					(xy 80.9244 -49.6062) (xy 81.0768 -49.6062) (xy 81.0768 -50.2158) (xy 80.9244 -50.2158)
				)
			)
		)
	)
	(footprint ""
		(layer "F.Cu")
		(at 150.381462 -58.014108 180)
		(property "Reference" "R297"
			(at 1.410462 3.541522 0)
			(unlocked yes)
			(layer "F.SilkS")
			(effects
				(font
					(size 0.7874 0.5842)
					(thickness 0.1524)
				)
			)
		)
		(property "Value" "VAL*"
			(at 0.02032 2.13233 180)
			(unlocked yes)
			(layer "F.Fab")
			(hide yes)
			(effects
				(font
					(size 0.7874 0.5842)
					(thickness 0.1524)
				)
			)
		)
		(property "Tolerance" "TOL*"
			(at 0.044704 3.05435 180)
			(unlocked yes)
			(layer "Cmts.User")
			(hide yes)
			(effects
				(font
					(size 0.7874 0.5842)
					(thickness 0.1524)
				)
			)
		)
		(property "User Part Number" "PARTNUM*"
			(at 0.02032 4.024884 180)
			(unlocked yes)
			(layer "Cmts.User")
			(hide yes)
			(effects
				(font
					(size 0.7874 0.5842)
					(thickness 0.1524)
				)
			)
		)
		(property "Device Type" "RESISTOR-G155-14701-01,4.7KOHMA"
			(at 0.008382 1.210564 180)
			(unlocked yes)
			(layer "F.Fab")
			(hide yes)
			(effects
				(font
					(size 0.7874 0.5842)
					(thickness 0.1524)
				)
			)
		)
		(duplicate_pad_numbers_are_jumpers no)
		(fp_line
			(start 1.143 0.5588)
			(end 1.143 -0.5588)
			(stroke
				(width 0.1)
				(type default)
			)
			(layer "F.SilkS")
		)
		(fp_line
			(start 1.143 -0.5588)
			(end -1.143 -0.5588)
			(stroke
				(width 0.1)
				(type default)
			)
			(layer "F.SilkS")
		)
		(fp_line
			(start -1.143 0.5588)
			(end 1.143 0.5588)
			(stroke
				(width 0.1)
				(type default)
			)
			(layer "F.SilkS")
		)
		(fp_line
			(start -1.143 -0.5588)
			(end -1.143 0.5588)
			(stroke
				(width 0.1)
				(type default)
			)
			(layer "F.SilkS")
		)
		(fp_rect
			(start -1.143 0.5588)
			(end 1.143 -0.5588)
			(stroke
				(width 0)
				(type default)
			)
			(fill no)
			(layer "F.CrtYd")
		)
		(fp_line
			(start 0.508 0.3048)
			(end 0.508 -0.3048)
			(stroke
				(width 0.1)
				(type default)
			)
			(layer "F.Fab")
		)
		(fp_line
			(start 0.508 -0.3048)
			(end -0.508 -0.3048)
			(stroke
				(width 0.1)
				(type default)
			)
			(layer "F.Fab")
		)
		(fp_line
			(start -0.508 0.3048)
			(end 0.508 0.3048)
			(stroke
				(width 0.1)
				(type default)
			)
			(layer "F.Fab")
		)
		(fp_line
			(start -0.508 -0.3048)
			(end -0.508 0.3048)
			(stroke
				(width 0.1)
				(type default)
			)
			(layer "F.Fab")
		)
		(pad "1" smd rect
			(at -0.5334 0 180)
			(size 0.7112 0.6096)
			(layers "F.Cu" "F.Mask" "F.Paste")
			(net "R_SHT3X_RST_N")
		)
		(pad "2" smd rect
			(at 0.5334 0 180)
			(size 0.7112 0.6096)
			(layers "F.Cu" "F.Mask" "F.Paste")
			(net "SG")
		)
		(zone
			(layer "F.Cu")
			(hatch none 0.5)
			(connect_pads
				(clearance 0)
			)
			(min_thickness 0.25)
			(keepout
				(tracks allowed)
				(vias not_allowed)
				(pads allowed)
				(copperpour not_allowed)
				(footprints allowed)
			)
			(placement
				(enabled no)
				(sheetname "")
			)
			(fill
				(thermal_gap 0.5)
				(thermal_bridge_width 0.5)
				(island_removal_mode 0)
			)
			(polygon
				(pts
					(xy 150.457662 -58.318908) (xy 150.305262 -58.318908) (xy 150.305262 -57.709308) (xy 150.457662 -57.709308)
				)
			)
		)
	)
	(footprint ""
		(layer "F.Cu")
		(at 145.8214 -99.2378 180)
		(property "Reference" "R15"
			(at -3.0226 0.16383 0)
			(unlocked yes)
			(layer "F.SilkS")
			(effects
				(font
					(size 0.7874 0.5842)
					(thickness 0.1524)
				)
			)
		)
		(property "Value" "VAL*"
			(at 0.02032 2.13233 180)
			(unlocked yes)
			(layer "F.Fab")
			(hide yes)
			(effects
				(font
					(size 0.7874 0.5842)
					(thickness 0.1524)
				)
			)
		)
		(property "Device Type" "RESISTOR-G155-11002-01,10KOHM,A"
			(at 0.008382 1.210564 180)
			(unlocked yes)
			(layer "F.Fab")
			(hide yes)
			(effects
				(font
					(size 0.7874 0.5842)
					(thickness 0.1524)
				)
			)
		)
		(property "User Part Number" "PARTNUM*"
			(at 0.02032 4.024884 180)
			(unlocked yes)
			(layer "Cmts.User")
			(hide yes)
			(effects
				(font
					(size 0.7874 0.5842)
					(thickness 0.1524)
				)
			)
		)
		(property "Tolerance" "TOL*"
			(at 0.044704 3.05435 180)
			(unlocked yes)
			(layer "Cmts.User")
			(hide yes)
			(effects
				(font
					(size 0.7874 0.5842)
					(thickness 0.1524)
				)
			)
		)
		(duplicate_pad_numbers_are_jumpers no)
		(fp_line
			(start 1.143 0.5588)
			(end 1.143 -0.5588)
			(stroke
				(width 0.1)
				(type default)
			)
			(layer "F.SilkS")
		)
		(fp_line
			(start 1.143 -0.5588)
			(end -1.143 -0.5588)
			(stroke
				(width 0.1)
				(type default)
			)
			(layer "F.SilkS")
		)
		(fp_line
			(start -1.143 0.5588)
			(end 1.143 0.5588)
			(stroke
				(width 0.1)
				(type default)
			)
			(layer "F.SilkS")
		)
		(fp_line
			(start -1.143 -0.5588)
			(end -1.143 0.5588)
			(stroke
				(width 0.1)
				(type default)
			)
			(layer "F.SilkS")
		)
		(fp_rect
			(start 1.143 -0.5588)
			(end -1.143 0.5588)
			(stroke
				(width 0)
				(type default)
			)
			(fill no)
			(layer "F.CrtYd")
		)
		(fp_line
			(start 0.508 0.3048)
			(end 0.508 -0.3048)
			(stroke
				(width 0.1)
				(type default)
			)
			(layer "F.Fab")
		)
		(fp_line
			(start 0.508 -0.3048)
			(end -0.508 -0.3048)
			(stroke
				(width 0.1)
				(type default)
			)
			(layer "F.Fab")
		)
		(fp_line
			(start -0.508 0.3048)
			(end 0.508 0.3048)
			(stroke
				(width 0.1)
				(type default)
			)
			(layer "F.Fab")
		)
		(fp_line
			(start -0.508 -0.3048)
			(end -0.508 0.3048)
			(stroke
				(width 0.1)
				(type default)
			)
			(layer "F.Fab")
		)
		(pad "1" smd rect
			(at -0.5334 0 180)
			(size 0.7112 0.6096)
			(layers "F.Cu" "F.Mask" "F.Paste")
			(net "XP12R0V")
		)
		(pad "2" smd rect
			(at 0.5334 0 180)
			(size 0.7112 0.6096)
			(layers "F.Cu" "F.Mask" "F.Paste")
			(net "XP12R0V_A_FLTB")
		)
		(zone
			(layer "F.Cu")
			(hatch none 0.5)
			(connect_pads
				(clearance 0)
			)
			(min_thickness 0.25)
			(keepout
				(tracks allowed)
				(vias not_allowed)
				(pads allowed)
				(copperpour not_allowed)
				(footprints allowed)
			)
			(placement
				(enabled no)
				(sheetname "")
			)
			(fill
				(thermal_gap 0.5)
				(thermal_bridge_width 0.5)
				(island_removal_mode 0)
			)
			(polygon
				(pts
					(xy 145.7452 -98.933) (xy 145.8976 -98.933) (xy 145.8976 -99.5426) (xy 145.7452 -99.5426)
				)
			)
		)
	)
	(footprint ""
		(layer "F.Cu")
		(at 147.049998 -107.849924 -90)
		(property "Reference" "DS4"
			(at -0.862076 -1.706372 90)
			(unlocked yes)
			(layer "F.SilkS")
			(effects
				(font
					(size 0.7874 0.5842)
					(thickness 0.1524)
				)
			)
		)
		(property "Value" ""
			(at 0 0 270)
			(layer "F.Fab")
			(effects
				(font
					(size 1.27 1.27)
				)
			)
		)
		(property "User Part Number" "PARTNUM*"
			(at 0.1778 2.422881 270)
			(unlocked yes)
			(layer "Cmts.User")
			(hide yes)
			(effects
				(font
					(size 0.786892 0.583946)
					(thickness 0.000001)
				)
			)
		)
		(property "Device Type" "OPTICAL-G170-10143-01"
			(at 0.1778 1.483081 270)
			(unlocked yes)
			(layer "F.Fab")
			(hide yes)
			(effects
				(font
					(size 0.786892 0.583946)
					(thickness 0.000001)
				)
			)
		)
		(duplicate_pad_numbers_are_jumpers no)
		(fp_line
			(start -1.3208 1.0922)
			(end -2.5908 1.0922)
			(stroke
				(width 0.1)
				(type default)
			)
			(layer "F.SilkS")
		)
		(fp_line
			(start -1.397508 0.704088)
			(end -1.397508 -0.704088)
			(stroke
				(width 0.1)
				(type default)
			)
			(layer "F.SilkS")
		)
		(fp_line
			(start 1.397508 0.704088)
			(end -1.397508 0.704088)
			(stroke
				(width 0.1)
				(type default)
			)
			(layer "F.SilkS")
		)
		(fp_line
			(start -1.9558 0.4572)
			(end -1.9558 1.7272)
			(stroke
				(width 0.1)
				(type default)
			)
			(layer "F.SilkS")
		)
		(fp_line
			(start -1.397508 -0.704088)
			(end 1.397508 -0.704088)
			(stroke
				(width 0.1)
				(type default)
			)
			(layer "F.SilkS")
		)
		(fp_line
			(start 1.397508 -0.704088)
			(end 1.397508 0.704088)
			(stroke
				(width 0.1)
				(type default)
			)
			(layer "F.SilkS")
		)
		(fp_rect
			(start 1.905508 0.704088)
			(end 1.397508 -0.704088)
			(stroke
				(width 0)
				(type default)
			)
			(fill yes)
			(layer "F.SilkS")
		)
		(fp_rect
			(start 1.905508 0.958088)
			(end -1.651508 -0.958088)
			(stroke
				(width 0)
				(type default)
			)
			(fill no)
			(layer "F.CrtYd")
		)
		(fp_line
			(start -1.4478 0.9652)
			(end -2.7178 0.9652)
			(stroke
				(width 0.1)
				(type default)
			)
			(layer "F.Fab")
		)
		(fp_line
			(start -0.850138 0.450088)
			(end 0.850138 0.450088)
			(stroke
				(width 0.1)
				(type default)
			)
			(layer "F.Fab")
		)
		(fp_line
			(start 0.850138 0.450088)
			(end 0.850138 -0.450088)
			(stroke
				(width 0.1)
				(type default)
			)
			(layer "F.Fab")
		)
		(fp_line
			(start -2.0828 0.3302)
			(end -2.0828 1.6002)
			(stroke
				(width 0.1)
				(type default)
			)
			(layer "F.Fab")
		)
		(fp_line
			(start -0.850138 -0.450088)
			(end -0.850138 0.450088)
			(stroke
				(width 0.1)
				(type default)
			)
			(layer "F.Fab")
		)
		(fp_line
			(start 0.850138 -0.450088)
			(end -0.850138 -0.450088)
			(stroke
				(width 0.1)
				(type default)
			)
			(layer "F.Fab")
		)
		(fp_rect
			(start 0.850138 0.450088)
			(end 0.342138 -0.450088)
			(stroke
				(width 0)
				(type default)
			)
			(fill yes)
			(layer "F.Fab")
		)
		(fp_text user "A"
			(at -1.846326 -0.778002 0)
			(unlocked yes)
			(layer "F.SilkS")
			(effects
				(font
					(size 0.635 0.4064)
					(thickness 0.1524)
				)
			)
		)
		(fp_text user "C"
			(at 1.201674 -1.540002 0)
			(unlocked yes)
			(layer "F.SilkS")
			(effects
				(font
					(size 0.635 0.4064)
					(thickness 0.1524)
				)
			)
		)
		(fp_text user "A"
			(at -1.700276 0.032004 0)
			(unlocked yes)
			(layer "F.Fab")
			(effects
				(font
					(size 0.7874 0.5842)
					(thickness 0.1524)
				)
			)
		)
		(fp_text user "C"
			(at 0.828294 -1.159002 0)
			(unlocked yes)
			(layer "F.Fab")
			(effects
				(font
					(size 0.7874 0.5842)
					(thickness 0.1524)
				)
			)
		)
		(pad "A" smd rect
			(at -0.749808 0 270)
			(size 0.7874 0.7874)
			(layers "F.Cu" "F.Mask" "F.Paste")
			(net "UNNAMED_14_OPTICAL_I137_A")
		)
		(pad "C" smd rect
			(at 0.749808 0 270)
			(size 0.7874 0.7874)
			(layers "F.Cu" "F.Mask" "F.Paste")
			(net "LED_DATOUT0")
		)
	)
	(footprint ""
		(layer "F.Cu")
		(at 56.3372 -74.9808 90)
		(property "Reference" "C306"
			(at -0.5588 4.15417 90)
			(unlocked yes)
			(layer "F.SilkS")
			(effects
				(font
					(size 0.7874 0.5842)
					(thickness 0.1524)
				)
			)
		)
		(property "Value" "VAL*"
			(at 0.0762 2.067306 90)
			(unlocked yes)
			(layer "F.Fab")
			(hide yes)
			(effects
				(font
					(size 0.7874 0.5842)
					(thickness 0.1524)
				)
			)
		)
		(property "Tolerance" "TOL*"
			(at 0.0762 3.032506 90)
			(unlocked yes)
			(layer "Cmts.User")
			(hide yes)
			(effects
				(font
					(size 0.7874 0.5842)
					(thickness 0.1524)
				)
			)
		)
		(property "User Part Number" "PARTNUM*"
			(at 0.1016 4.023106 90)
			(unlocked yes)
			(layer "Cmts.User")
			(hide yes)
			(effects
				(font
					(size 0.7874 0.5842)
					(thickness 0.1524)
				)
			)
		)
		(property "Device Type" "CAPACITOR-G105-0B104-EK,0.1UF,A"
			(at 0.0508 1.127506 90)
			(unlocked yes)
			(layer "F.Fab")
			(hide yes)
			(effects
				(font
					(size 0.7874 0.5842)
					(thickness 0.1524)
				)
			)
		)
		(duplicate_pad_numbers_are_jumpers no)
		(fp_line
			(start 1.143 -0.5588)
			(end -1.143 -0.5588)
			(stroke
				(width 0.1)
				(type default)
			)
			(layer "F.SilkS")
		)
		(fp_line
			(start -1.143 -0.5588)
			(end -1.143 0.5588)
			(stroke
				(width 0.1)
				(type default)
			)
			(layer "F.SilkS")
		)
		(fp_line
			(start 1.143 0.5588)
			(end 1.143 -0.5588)
			(stroke
				(width 0.1)
				(type default)
			)
			(layer "F.SilkS")
		)
		(fp_line
			(start -1.143 0.5588)
			(end 1.143 0.5588)
			(stroke
				(width 0.1)
				(type default)
			)
			(layer "F.SilkS")
		)
		(fp_rect
			(start -1.143 0.5588)
			(end 1.143 -0.5588)
			(stroke
				(width 0)
				(type default)
			)
			(fill no)
			(layer "F.CrtYd")
		)
		(fp_line
			(start 0.508 -0.3048)
			(end -0.508 -0.3048)
			(stroke
				(width 0.1)
				(type default)
			)
			(layer "F.Fab")
		)
		(fp_line
			(start -0.508 -0.3048)
			(end -0.508 0.3048)
			(stroke
				(width 0.1)
				(type default)
			)
			(layer "F.Fab")
		)
		(fp_line
			(start 0.508 0.3048)
			(end 0.508 -0.3048)
			(stroke
				(width 0.1)
				(type default)
			)
			(layer "F.Fab")
		)
		(fp_line
			(start -0.508 0.3048)
			(end 0.508 0.3048)
			(stroke
				(width 0.1)
				(type default)
			)
			(layer "F.Fab")
		)
		(pad "1" smd rect
			(at -0.5334 0 90)
			(size 0.7112 0.6096)
			(layers "F.Cu" "F.Mask" "F.Paste")
			(net "SG")
		)
		(pad "2" smd rect
			(at 0.5334 0 90)
			(size 0.7112 0.6096)
			(layers "F.Cu" "F.Mask" "F.Paste")
			(net "XP3R3V_FPGA")
		)
		(zone
			(layer "F.Cu")
			(hatch none 0.5)
			(connect_pads
				(clearance 0)
			)
			(min_thickness 0.25)
			(keepout
				(tracks allowed)
				(vias not_allowed)
				(pads allowed)
				(copperpour not_allowed)
				(footprints allowed)
			)
			(placement
				(enabled no)
				(sheetname "")
			)
			(fill
				(thermal_gap 0.5)
				(thermal_bridge_width 0.5)
				(island_removal_mode 0)
			)
			(polygon
				(pts
					(xy 56.642 -74.9046) (xy 56.642 -75.057) (xy 56.0324 -75.057) (xy 56.0324 -74.9046)
				)
			)
		)
		(zone
			(layer "F.Cu")
			(hatch none 0.5)
			(connect_pads
				(clearance 0)
			)
			(min_thickness 0.25)
			(keepout
				(tracks not_allowed)
				(vias allowed)
				(pads allowed)
				(copperpour not_allowed)
				(footprints allowed)
			)
			(placement
				(enabled no)
				(sheetname "")
			)
			(fill
				(thermal_gap 0.5)
				(thermal_bridge_width 0.5)
				(island_removal_mode 0)
			)
			(polygon
				(pts
					(xy 56.642 -74.9046) (xy 56.642 -75.057) (xy 56.0324 -75.057) (xy 56.0324 -74.9046)
				)
			)
		)
	)
	(footprint ""
		(layer "F.Cu")
		(at 111.506 -69.088 -90)
		(property "Reference" "C233"
			(at 0.254 -3.34137 90)
			(unlocked yes)
			(layer "F.SilkS")
			(effects
				(font
					(size 0.7874 0.5842)
					(thickness 0.1524)
				)
			)
		)
		(property "Value" "VAL*"
			(at 0.0762 2.067306 270)
			(unlocked yes)
			(layer "F.Fab")
			(hide yes)
			(effects
				(font
					(size 0.7874 0.5842)
					(thickness 0.1524)
				)
			)
		)
		(property "Tolerance" "TOL*"
			(at 0.0762 3.032506 270)
			(unlocked yes)
			(layer "Cmts.User")
			(hide yes)
			(effects
				(font
					(size 0.7874 0.5842)
					(thickness 0.1524)
				)
			)
		)
		(property "User Part Number" "PARTNUM*"
			(at 0.1016 4.023106 270)
			(unlocked yes)
			(layer "Cmts.User")
			(hide yes)
			(effects
				(font
					(size 0.7874 0.5842)
					(thickness 0.1524)
				)
			)
		)
		(property "Device Type" "CAPACITOR-G105-0B104-CK,0.1UF,A"
			(at 0.0508 1.127506 270)
			(unlocked yes)
			(layer "F.Fab")
			(hide yes)
			(effects
				(font
					(size 0.7874 0.5842)
					(thickness 0.1524)
				)
			)
		)
		(duplicate_pad_numbers_are_jumpers no)
		(fp_line
			(start -1.143 0.5588)
			(end 1.143 0.5588)
			(stroke
				(width 0.1)
				(type default)
			)
			(layer "F.SilkS")
		)
		(fp_line
			(start 1.143 0.5588)
			(end 1.143 -0.5588)
			(stroke
				(width 0.1)
				(type default)
			)
			(layer "F.SilkS")
		)
		(fp_line
			(start -1.143 -0.5588)
			(end -1.143 0.5588)
			(stroke
				(width 0.1)
				(type default)
			)
			(layer "F.SilkS")
		)
		(fp_line
			(start 1.143 -0.5588)
			(end -1.143 -0.5588)
			(stroke
				(width 0.1)
				(type default)
			)
			(layer "F.SilkS")
		)
		(fp_rect
			(start 1.143 -0.5588)
			(end -1.143 0.5588)
			(stroke
				(width 0)
				(type default)
			)
			(fill no)
			(layer "F.CrtYd")
		)
		(fp_line
			(start -0.508 0.3048)
			(end 0.508 0.3048)
			(stroke
				(width 0.1)
				(type default)
			)
			(layer "F.Fab")
		)
		(fp_line
			(start 0.508 0.3048)
			(end 0.508 -0.3048)
			(stroke
				(width 0.1)
				(type default)
			)
			(layer "F.Fab")
		)
		(fp_line
			(start -0.508 -0.3048)
			(end -0.508 0.3048)
			(stroke
				(width 0.1)
				(type default)
			)
			(layer "F.Fab")
		)
		(fp_line
			(start 0.508 -0.3048)
			(end -0.508 -0.3048)
			(stroke
				(width 0.1)
				(type default)
			)
			(layer "F.Fab")
		)
		(pad "1" smd rect
			(at -0.5334 0 270)
			(size 0.7112 0.6096)
			(layers "F.Cu" "F.Mask" "F.Paste")
			(net "XP3R3V")
		)
		(pad "2" smd rect
			(at 0.5334 0 270)
			(size 0.7112 0.6096)
			(layers "F.Cu" "F.Mask" "F.Paste")
			(net "SG")
		)
		(zone
			(layer "F.Cu")
			(hatch none 0.5)
			(connect_pads
				(clearance 0)
			)
			(min_thickness 0.25)
			(keepout
				(tracks allowed)
				(vias not_allowed)
				(pads allowed)
				(copperpour not_allowed)
				(footprints allowed)
			)
			(placement
				(enabled no)
				(sheetname "")
			)
			(fill
				(thermal_gap 0.5)
				(thermal_bridge_width 0.5)
				(island_removal_mode 0)
			)
			(polygon
				(pts
					(xy 111.8108 -69.0118) (xy 111.8108 -69.1642) (xy 111.2012 -69.1642) (xy 111.2012 -69.0118)
				)
			)
		)
	)
	(footprint ""
		(layer "F.Cu")
		(at 8.4328 -68.201032 90)
		(property "Reference" "R393"
			(at 3.553968 -0.51943 90)
			(unlocked yes)
			(layer "F.SilkS")
			(effects
				(font
					(size 0.7874 0.5842)
					(thickness 0.1524)
				)
			)
		)
		(property "Value" "VAL*"
			(at 0.02032 2.13233 90)
			(unlocked yes)
			(layer "F.Fab")
			(hide yes)
			(effects
				(font
					(size 0.7874 0.5842)
					(thickness 0.1524)
				)
			)
		)
		(property "Tolerance" "TOL*"
			(at 0.044704 3.05435 90)
			(unlocked yes)
			(layer "Cmts.User")
			(hide yes)
			(effects
				(font
					(size 0.7874 0.5842)
					(thickness 0.1524)
				)
			)
		)
		(property "User Part Number" "PARTNUM*"
			(at 0.02032 4.024884 90)
			(unlocked yes)
			(layer "Cmts.User")
			(hide yes)
			(effects
				(font
					(size 0.7874 0.5842)
					(thickness 0.1524)
				)
			)
		)
		(property "Device Type" "RESISTOR-G155-133R0-01,33OHM,1%"
			(at 0.008382 1.210564 90)
			(unlocked yes)
			(layer "F.Fab")
			(hide yes)
			(effects
				(font
					(size 0.7874 0.5842)
					(thickness 0.1524)
				)
			)
		)
		(duplicate_pad_numbers_are_jumpers no)
		(fp_line
			(start 1.143 -0.5588)
			(end -1.143 -0.5588)
			(stroke
				(width 0.1)
				(type default)
			)
			(layer "F.SilkS")
		)
		(fp_line
			(start -1.143 -0.5588)
			(end -1.143 0.5588)
			(stroke
				(width 0.1)
				(type default)
			)
			(layer "F.SilkS")
		)
		(fp_line
			(start 1.143 0.5588)
			(end 1.143 -0.5588)
			(stroke
				(width 0.1)
				(type default)
			)
			(layer "F.SilkS")
		)
		(fp_line
			(start -1.143 0.5588)
			(end 1.143 0.5588)
			(stroke
				(width 0.1)
				(type default)
			)
			(layer "F.SilkS")
		)
		(fp_rect
			(start -1.143 -0.5588)
			(end 1.143 0.5588)
			(stroke
				(width 0)
				(type default)
			)
			(fill no)
			(layer "F.CrtYd")
		)
		(fp_line
			(start 0.508 -0.3048)
			(end -0.508 -0.3048)
			(stroke
				(width 0.1)
				(type default)
			)
			(layer "F.Fab")
		)
		(fp_line
			(start -0.508 -0.3048)
			(end -0.508 0.3048)
			(stroke
				(width 0.1)
				(type default)
			)
			(layer "F.Fab")
		)
		(fp_line
			(start 0.508 0.3048)
			(end 0.508 -0.3048)
			(stroke
				(width 0.1)
				(type default)
			)
			(layer "F.Fab")
		)
		(fp_line
			(start -0.508 0.3048)
			(end 0.508 0.3048)
			(stroke
				(width 0.1)
				(type default)
			)
			(layer "F.Fab")
		)
		(pad "1" smd rect
			(at -0.5334 0 90)
			(size 0.7112 0.6096)
			(layers "F.Cu" "F.Mask" "F.Paste")
			(net "SMA3_LED_RED_N")
		)
		(pad "2" smd rect
			(at 0.5334 0 90)
			(size 0.7112 0.6096)
			(layers "F.Cu" "F.Mask" "F.Paste")
			(net "UNNAMED_14_LED4PV14_I267_3")
		)
		(zone
			(layer "F.Cu")
			(hatch none 0.5)
			(connect_pads
				(clearance 0)
			)
			(min_thickness 0.25)
			(keepout
				(tracks not_allowed)
				(vias allowed)
				(pads allowed)
				(copperpour not_allowed)
				(footprints allowed)
			)
			(placement
				(enabled no)
				(sheetname "")
			)
			(fill
				(thermal_gap 0.5)
				(thermal_bridge_width 0.5)
				(island_removal_mode 0)
			)
			(polygon
				(pts
					(xy 8.128 -68.124832) (xy 8.7376 -68.124832) (xy 8.7376 -68.277232) (xy 8.128 -68.277232)
				)
			)
		)
		(zone
			(layer "F.Cu")
			(hatch none 0.5)
			(connect_pads
				(clearance 0)
			)
			(min_thickness 0.25)
			(keepout
				(tracks allowed)
				(vias not_allowed)
				(pads allowed)
				(copperpour not_allowed)
				(footprints allowed)
			)
			(placement
				(enabled no)
				(sheetname "")
			)
			(fill
				(thermal_gap 0.5)
				(thermal_bridge_width 0.5)
				(island_removal_mode 0)
			)
			(polygon
				(pts
					(xy 8.128 -68.124832) (xy 8.7376 -68.124832) (xy 8.7376 -68.277232) (xy 8.128 -68.277232)
				)
			)
		)
	)
	(footprint ""
		(layer "F.Cu")
		(at 87.503 -67.31)
		(property "Reference" "TP19"
			(at -0.7874 -0.85725 0)
			(unlocked yes)
			(layer "F.SilkS")
			(effects
				(font
					(size 0.635 0.4064)
					(thickness 0.1524)
				)
				(justify left)
			)
		)
		(property "Value" ""
			(at 0 0 0)
			(layer "F.Fab")
			(effects
				(font
					(size 1.27 1.27)
				)
			)
		)
		(property "Device Type" "TP_PIONT-TP010CT020B030_PTH-TPA"
			(at -1.341882 0.996696 0)
			(unlocked yes)
			(layer "F.Fab")
			(hide yes)
			(effects
				(font
					(size 0.7874 0.5842)
					(thickness 0.000001)
				)
				(justify left)
			)
		)
		(duplicate_pad_numbers_are_jumpers no)
		(fp_poly
			(pts
				(arc
					(start 0.889 0)
					(mid -0.889 0)
					(end 0.889 0)
				)
			)
			(stroke
				(width 0)
				(type default)
			)
			(fill no)
			(layer "B.CrtYd")
		)
		(fp_poly
			(pts
				(arc
					(start 0.889 0)
					(mid -0.889 0)
					(end 0.889 0)
				)
			)
			(stroke
				(width 0)
				(type default)
			)
			(fill no)
			(layer "F.CrtYd")
		)
		(pad "1" thru_hole circle
			(at 0 0)
			(size 0.508 0.508)
			(drill 0.254)
			(layers "*.Cu" "*.Mask")
			(remove_unused_layers no)
			(net "SN_EEPROM_WP")
			(clearance 0.1016)
			(padstack
				(mode front_inner_back)
				(layer "Inner"
					(shape circle)
					(size 0.508 0.508)
					(clearance 0.1016)
				)
				(layer "B.Cu"
					(shape circle)
					(size 0.762 0.762)
					(clearance -0.0254)
				)
			)
		)
	)
	(footprint ""
		(layer "F.Cu")
		(at 134.1882 -106.172254 -90)
		(property "Reference" "DS9"
			(at -0.126746 2.19583 90)
			(unlocked yes)
			(layer "F.SilkS")
			(effects
				(font
					(size 0.7874 0.5842)
					(thickness 0.1524)
				)
			)
		)
		(property "Value" ""
			(at 0 0 270)
			(layer "F.Fab")
			(effects
				(font
					(size 1.27 1.27)
				)
			)
		)
		(property "User Part Number" "PARTNUM*"
			(at 0.1778 2.422881 270)
			(unlocked yes)
			(layer "Cmts.User")
			(hide yes)
			(effects
				(font
					(size 0.786892 0.583946)
					(thickness 0.000001)
				)
			)
		)
		(property "Device Type" "OPTICAL-G170-10143-01"
			(at 0.1778 1.483081 270)
			(unlocked yes)
			(layer "F.Fab")
			(hide yes)
			(effects
				(font
					(size 0.786892 0.583946)
					(thickness 0.000001)
				)
			)
		)
		(duplicate_pad_numbers_are_jumpers no)
		(fp_line
			(start -1.3208 1.3462)
			(end -2.5908 1.3462)
			(stroke
				(width 0.1)
				(type default)
			)
			(layer "F.SilkS")
		)
		(fp_line
			(start -1.9558 0.7112)
			(end -1.9558 1.9812)
			(stroke
				(width 0.1)
				(type default)
			)
			(layer "F.SilkS")
		)
		(fp_line
			(start -1.397508 0.704088)
			(end -1.397508 -0.704088)
			(stroke
				(width 0.1)
				(type default)
			)
			(layer "F.SilkS")
		)
		(fp_line
			(start 1.397508 0.704088)
			(end -1.397508 0.704088)
			(stroke
				(width 0.1)
				(type default)
			)
			(layer "F.SilkS")
		)
		(fp_line
			(start -1.397508 -0.704088)
			(end 1.397508 -0.704088)
			(stroke
				(width 0.1)
				(type default)
			)
			(layer "F.SilkS")
		)
		(fp_line
			(start 1.397508 -0.704088)
			(end 1.397508 0.704088)
			(stroke
				(width 0.1)
				(type default)
			)
			(layer "F.SilkS")
		)
		(fp_rect
			(start 1.905508 0.704088)
			(end 1.397508 -0.704088)
			(stroke
				(width 0)
				(type default)
			)
			(fill yes)
			(layer "F.SilkS")
		)
		(fp_rect
			(start 1.905508 0.958088)
			(end -1.651508 -0.958088)
			(stroke
				(width 0)
				(type default)
			)
			(fill no)
			(layer "F.CrtYd")
		)
		(fp_line
			(start -0.850138 0.450088)
			(end 0.850138 0.450088)
			(stroke
				(width 0.1)
				(type default)
			)
			(layer "F.Fab")
		)
		(fp_line
			(start 0.850138 0.450088)
			(end 0.850138 -0.450088)
			(stroke
				(width 0.1)
				(type default)
			)
			(layer "F.Fab")
		)
		(fp_line
			(start -2.2098 0.0762)
			(end -3.4798 0.0762)
			(stroke
				(width 0.1)
				(type default)
			)
			(layer "F.Fab")
		)
		(fp_line
			(start -0.850138 -0.450088)
			(end -0.850138 0.450088)
			(stroke
				(width 0.1)
				(type default)
			)
			(layer "F.Fab")
		)
		(fp_line
			(start 0.850138 -0.450088)
			(end -0.850138 -0.450088)
			(stroke
				(width 0.1)
				(type default)
			)
			(layer "F.Fab")
		)
		(fp_line
			(start -2.8448 -0.5588)
			(end -2.8448 0.7112)
			(stroke
				(width 0.1)
				(type default)
			)
			(layer "F.Fab")
		)
		(fp_rect
			(start 0.850138 0.450088)
			(end 0.342138 -0.450088)
			(stroke
				(width 0)
				(type default)
			)
			(fill yes)
			(layer "F.Fab")
		)
		(fp_text user "C"
			(at 2.013204 1.4732 0)
			(unlocked yes)
			(layer "F.SilkS")
			(effects
				(font
					(size 0.635 0.4064)
					(thickness 0.1524)
				)
			)
		)
		(fp_text user "A"
			(at -2.126996 0.2032 0)
			(unlocked yes)
			(layer "F.SilkS")
			(effects
				(font
					(size 0.635 0.4064)
					(thickness 0.1524)
				)
			)
		)
		(fp_text user "A"
			(at -1.497076 0.0762 0)
			(unlocked yes)
			(layer "F.Fab")
			(effects
				(font
					(size 0.7874 0.5842)
					(thickness 0.1524)
				)
			)
		)
		(fp_text user "C"
			(at 1.677924 0.0762 0)
			(unlocked yes)
			(layer "F.Fab")
			(effects
				(font
					(size 0.7874 0.5842)
					(thickness 0.1524)
				)
			)
		)
		(pad "A" smd rect
			(at -0.749808 0 270)
			(size 0.7874 0.7874)
			(layers "F.Cu" "F.Mask" "F.Paste")
			(net "UNNAMED_14_OPTICAL_I292_A")
		)
		(pad "C" smd rect
			(at 0.749808 0 270)
			(size 0.7874 0.7874)
			(layers "F.Cu" "F.Mask" "F.Paste")
			(net "SG")
		)
	)
	(footprint ""
		(layer "F.Cu")
		(at 50.165 -126.873)
		(property "Reference" "SP54"
			(at 0 0 0)
			(layer "F.SilkS")
			(hide yes)
			(effects
				(font
					(size 1.27 1.27)
				)
			)
		)
		(property "Value" ""
			(at 0 0 0)
			(layer "F.Fab")
			(effects
				(font
					(size 1.27 1.27)
				)
			)
		)
		(duplicate_pad_numbers_are_jumpers no)
	)
	(footprint ""
		(layer "F.Cu")
		(at 140.6144 -94.9198 180)
		(property "Reference" "U1"
			(at 3.0734 0.29083 0)
			(unlocked yes)
			(layer "F.SilkS")
			(effects
				(font
					(size 0.7874 0.5842)
					(thickness 0.1524)
				)
			)
		)
		(property "Value" ""
			(at 0 0 180)
			(layer "F.Fab")
			(effects
				(font
					(size 1.27 1.27)
				)
			)
		)
		(property "Device Type" "MP5022CGQV_Z_QFN22-G220-10510-A"
			(at 0.130556 4.082542 180)
			(unlocked yes)
			(layer "F.Fab")
			(hide yes)
			(effects
				(font
					(size 0.7874 0.5842)
					(thickness 0.1524)
				)
			)
		)
		(property "User Part Number" "PARTNUM*"
			(at 0.022352 5.136896 180)
			(unlocked yes)
			(layer "Cmts.User")
			(hide yes)
			(effects
				(font
					(size 0.7874 0.5842)
					(thickness 0.1524)
				)
			)
		)
		(duplicate_pad_numbers_are_jumpers no)
		(fp_line
			(start 2.291334 3.290824)
			(end -2.291334 3.290824)
			(stroke
				(width 0.1)
				(type default)
			)
			(layer "F.SilkS")
		)
		(fp_line
			(start 2.291334 -3.290824)
			(end 2.291334 3.290824)
			(stroke
				(width 0.1)
				(type default)
			)
			(layer "F.SilkS")
		)
		(fp_line
			(start -2.291334 3.290824)
			(end -2.291334 -3.290824)
			(stroke
				(width 0.1)
				(type default)
			)
			(layer "F.SilkS")
		)
		(fp_line
			(start -2.291334 -3.290824)
			(end 2.291334 -3.290824)
			(stroke
				(width 0.1)
				(type default)
			)
			(layer "F.SilkS")
		)
		(fp_poly
			(pts
				(arc
					(start -3.530854 -2.4638)
					(mid -2.514346 -2.4638)
					(end -3.530854 -2.4638)
				)
			)
			(stroke
				(width 0)
				(type default)
			)
			(fill yes)
			(layer "F.SilkS")
		)
		(fp_rect
			(start -0.6223 1.726946)
			(end 0.6223 1.472946)
			(stroke
				(width 0)
				(type default)
			)
			(fill yes)
			(layer "F.Paste")
		)
		(fp_rect
			(start -0.6223 0.827024)
			(end 0.6223 0.573024)
			(stroke
				(width 0)
				(type default)
			)
			(fill yes)
			(layer "F.Paste")
		)
		(fp_rect
			(start -0.6223 -0.072898)
			(end 0.6223 -0.326898)
			(stroke
				(width 0)
				(type default)
			)
			(fill yes)
			(layer "F.Paste")
		)
		(fp_rect
			(start -0.6223 -0.973074)
			(end 0.6223 -1.227074)
			(stroke
				(width 0)
				(type default)
			)
			(fill yes)
			(layer "F.Paste")
		)
		(fp_poly
			(pts
				(xy -2.545334 3.544824) (xy 2.545334 3.544824) (xy 2.545334 -3.544824) (xy -2.545334 -3.544824)
			)
			(stroke
				(width 0)
				(type default)
			)
			(fill no)
			(layer "F.CrtYd")
		)
		(fp_line
			(start 1.549908 2.549906)
			(end 1.549908 -2.549906)
			(stroke
				(width 0.1)
				(type default)
			)
			(layer "F.Fab")
		)
		(fp_line
			(start 1.549908 -2.549906)
			(end -1.549908 -2.549906)
			(stroke
				(width 0.1)
				(type default)
			)
			(layer "F.Fab")
		)
		(fp_line
			(start -1.549908 2.549906)
			(end 1.549908 2.549906)
			(stroke
				(width 0.1)
				(type default)
			)
			(layer "F.Fab")
		)
		(fp_line
			(start -1.549908 -2.549906)
			(end -1.549908 2.549906)
			(stroke
				(width 0.1)
				(type default)
			)
			(layer "F.Fab")
		)
		(fp_poly
			(pts
				(arc
					(start -3.709162 -1.999996)
					(mid -2.692654 -1.999996)
					(end -3.709162 -1.999996)
				)
			)
			(stroke
				(width 0)
				(type default)
			)
			(fill yes)
			(layer "F.Fab")
		)
		(fp_text user "20"
			(at 3.0734 -1.60655 0)
			(unlocked yes)
			(layer "F.SilkS")
			(effects
				(font
					(size 0.635 0.4064)
					(thickness 0.1524)
				)
			)
		)
		(fp_text user "12"
			(at 2.9464 2.20345 0)
			(unlocked yes)
			(layer "F.SilkS")
			(effects
				(font
					(size 0.635 0.4064)
					(thickness 0.1524)
				)
			)
		)
		(fp_text user "9"
			(at -2.8956 2.20345 0)
			(unlocked yes)
			(layer "F.SilkS")
			(effects
				(font
					(size 0.635 0.4064)
					(thickness 0.1524)
				)
			)
		)
		(fp_text user "12"
			(at 3.193034 2.210054 0)
			(unlocked yes)
			(layer "F.Fab")
			(effects
				(font
					(size 0.7874 0.5842)
					(thickness 0.1524)
				)
			)
		)
		(fp_text user "20"
			(at 3.193034 -1.789938 0)
			(unlocked yes)
			(layer "F.Fab")
			(effects
				(font
					(size 0.7874 0.5842)
					(thickness 0.1524)
				)
			)
		)
		(fp_text user "9"
			(at -3.193034 2.210054 0)
			(unlocked yes)
			(layer "F.Fab")
			(effects
				(font
					(size 0.7874 0.5842)
					(thickness 0.1524)
				)
			)
		)
		(pad "1" smd rect
			(at -1.440434 -1.999996 180)
			(size 1.1938 0.3048)
			(layers "F.Cu" "F.Mask" "F.Paste")
			(net "XP12R0V_A_EN")
		)
		(pad "2" smd rect
			(at -1.440434 -1.500124 180)
			(size 1.1938 0.3048)
			(layers "F.Cu" "F.Mask" "F.Paste")
			(net "UNNAMED_15_MP5022CGQVZQFN22_I_2")
		)
		(pad "3" smd rect
			(at -1.440434 -0.999998 180)
			(size 1.1938 0.3048)
			(layers "F.Cu" "F.Mask" "F.Paste")
			(net "UNNAMED_15_MP5022CGQVZQFN22_I21")
		)
		(pad "4" smd rect
			(at -1.440434 -0.500126 180)
			(size 1.1938 0.3048)
			(layers "F.Cu" "F.Mask" "F.Paste")
			(net "XP12R0V_A_TIMER")
		)
		(pad "5" smd rect
			(at -1.440434 0 180)
			(size 1.1938 0.3048)
			(layers "F.Cu" "F.Mask" "F.Paste")
			(net "XP12R0V_A_ISET")
		)
		(pad "6" smd rect
			(at -1.440434 0.500126 180)
			(size 1.1938 0.3048)
			(layers "F.Cu" "F.Mask" "F.Paste")
			(net "XP12R0V_A_SS")
		)
		(pad "7" smd rect
			(at -1.440434 0.999998 180)
			(size 1.1938 0.3048)
			(layers "F.Cu" "F.Mask" "F.Paste")
			(net "SG")
		)
		(pad "8" smd rect
			(at -1.440434 1.500124 180)
			(size 1.1938 0.3048)
			(layers "F.Cu" "F.Mask" "F.Paste")
			(net "XP12R0V_A_IMON")
		)
		(pad "9" smd rect
			(at -1.440434 1.999996 180)
			(size 1.1938 0.3048)
			(layers "F.Cu" "F.Mask" "F.Paste")
			(net "XP12R0V_A_FLTB")
		)
		(pad "10" smd rect
			(at -0.500126 2.478024 180)
			(size 0.3302 1.1176)
			(layers "F.Cu" "F.Mask" "F.Paste")
			(net "XP12R0V_A_PG")
		)
		(pad "11" smd rect
			(at 0.500126 2.478024 180)
			(size 0.3302 1.1176)
			(layers "F.Cu" "F.Mask" "F.Paste")
			(net "XP12R0V_A_OV")
		)
		(pad "12" smd rect
			(at 1.440434 1.999996 180)
			(size 1.1938 0.3048)
			(layers "F.Cu" "F.Mask" "F.Paste")
			(net "XP12R0V_A_AVIN")
		)
		(pad "13" smd rect
			(at 1.440434 1.500124 180)
			(size 1.1938 0.3048)
			(layers "F.Cu" "F.Mask" "F.Paste")
			(net "XP12R0V")
		)
		(pad "14" smd rect
			(at 1.440434 0.999998 180)
			(size 1.1938 0.3048)
			(layers "F.Cu" "F.Mask" "F.Paste")
			(net "XP12R0V")
		)
		(pad "15" smd rect
			(at 1.440434 0.500126 180)
			(size 1.1938 0.3048)
			(layers "F.Cu" "F.Mask" "F.Paste")
			(net "XP12R0V")
		)
		(pad "16" smd rect
			(at 1.440434 0 180)
			(size 1.1938 0.3048)
			(layers "F.Cu" "F.Mask" "F.Paste")
			(net "XP12R0V")
		)
		(pad "17" smd rect
			(at 1.440434 -0.500126 180)
			(size 1.1938 0.3048)
			(layers "F.Cu" "F.Mask" "F.Paste")
			(net "XP12R0V")
		)
		(pad "18" smd rect
			(at 1.440434 -0.999998 180)
			(size 1.1938 0.3048)
			(layers "F.Cu" "F.Mask" "F.Paste")
			(net "XP12R0V")
		)
		(pad "19" smd rect
			(at 1.440434 -1.500124 180)
			(size 1.1938 0.3048)
			(layers "F.Cu" "F.Mask" "F.Paste")
			(net "XP12R0V")
		)
		(pad "20" smd rect
			(at 1.440434 -1.999996 180)
			(size 1.1938 0.3048)
			(layers "F.Cu" "F.Mask" "F.Paste")
			(net "XP12R0V")
		)
		(pad "21" smd circle
			(at 0 -2.003298 180)
			(size 0 0)
			(layers "F.Cu" "F.Mask" "F.Paste")
			(net "XP12R0V_IN")
		)
		(pad "22" smd rect
			(at -0.509778 -2.64033 180)
			(size 0.0254 0.0254)
			(layers "F.Cu" "F.Mask" "F.Paste")
			(net "XP12R0V_IN")
		)
		(pad "23" smd rect
			(at 0 -1.100074 180)
			(size 1.2446 0.254)
			(layers "F.Cu" "F.Mask" "F.Paste")
			(net "XP12R0V_IN")
		)
		(pad "24" smd rect
			(at 0 -0.199898 180)
			(size 1.2446 0.254)
			(layers "F.Cu" "F.Mask" "F.Paste")
			(net "XP12R0V_IN")
		)
		(pad "25" smd rect
			(at 0 0.700024 180)
			(size 1.2446 0.254)
			(layers "F.Cu" "F.Mask" "F.Paste")
			(net "XP12R0V_IN")
		)
		(pad "26" smd rect
			(at 0 1.599946 180)
			(size 1.2446 0.254)
			(layers "F.Cu" "F.Mask" "F.Paste")
			(net "XP12R0V_IN")
		)
	)
	(footprint ""
		(layer "F.Cu")
		(at 134.0612 -66.8528 90)
		(property "Reference" "R187"
			(at -4.8768 0.59817 90)
			(unlocked yes)
			(layer "F.SilkS")
			(effects
				(font
					(size 0.7874 0.5842)
					(thickness 0.1524)
				)
			)
		)
		(property "Value" "VAL*"
			(at 0.0508 2.245106 90)
			(unlocked yes)
			(layer "F.Fab")
			(hide yes)
			(effects
				(font
					(size 0.7874 0.5842)
					(thickness 0.1524)
				)
			)
		)
		(property "User Part Number" "PARTNUM*"
			(at 0.0762 4.302506 90)
			(unlocked yes)
			(layer "Cmts.User")
			(hide yes)
			(effects
				(font
					(size 0.7874 0.5842)
					(thickness 0.1524)
				)
			)
		)
		(property "Device Type" "RESISTOR-G155-04221-01,4.22KOHA"
			(at 0.0762 1.254506 90)
			(unlocked yes)
			(layer "F.Fab")
			(hide yes)
			(effects
				(font
					(size 0.7874 0.5842)
					(thickness 0.1524)
				)
			)
		)
		(property "Tolerance" "TOL*"
			(at 0.0508 3.261106 90)
			(unlocked yes)
			(layer "Cmts.User")
			(hide yes)
			(effects
				(font
					(size 0.7874 0.5842)
					(thickness 0.1524)
				)
			)
		)
		(duplicate_pad_numbers_are_jumpers no)
		(fp_line
			(start 1.143 -0.5588)
			(end -1.143 -0.5588)
			(stroke
				(width 0.1)
				(type default)
			)
			(layer "F.SilkS")
		)
		(fp_line
			(start -1.143 -0.5588)
			(end -1.143 0.5588)
			(stroke
				(width 0.1)
				(type default)
			)
			(layer "F.SilkS")
		)
		(fp_line
			(start 1.143 0.5588)
			(end 1.143 -0.5588)
			(stroke
				(width 0.1)
				(type default)
			)
			(layer "F.SilkS")
		)
		(fp_line
			(start -1.143 0.5588)
			(end 1.143 0.5588)
			(stroke
				(width 0.1)
				(type default)
			)
			(layer "F.SilkS")
		)
		(fp_rect
			(start 1.143 0.5588)
			(end -1.143 -0.5588)
			(stroke
				(width 0)
				(type default)
			)
			(fill no)
			(layer "F.CrtYd")
		)
		(fp_line
			(start 0.508 -0.3048)
			(end -0.508 -0.3048)
			(stroke
				(width 0.1)
				(type default)
			)
			(layer "F.Fab")
		)
		(fp_line
			(start -0.508 -0.3048)
			(end -0.508 0.3048)
			(stroke
				(width 0.1)
				(type default)
			)
			(layer "F.Fab")
		)
		(fp_line
			(start 0.508 0.3048)
			(end 0.508 -0.3048)
			(stroke
				(width 0.1)
				(type default)
			)
			(layer "F.Fab")
		)
		(fp_line
			(start -0.508 0.3048)
			(end 0.508 0.3048)
			(stroke
				(width 0.1)
				(type default)
			)
			(layer "F.Fab")
		)
		(pad "1" smd rect
			(at -0.5334 0 90)
			(size 0.7112 0.6096)
			(layers "F.Cu" "F.Mask" "F.Paste")
			(net "XP1R8V_FPGA")
		)
		(pad "2" smd rect
			(at 0.5334 0 90)
			(size 0.7112 0.6096)
			(layers "F.Cu" "F.Mask" "F.Paste")
			(net "XP1R8V_FB")
		)
		(zone
			(layer "F.Cu")
			(hatch none 0.5)
			(connect_pads
				(clearance 0)
			)
			(min_thickness 0.25)
			(keepout
				(tracks allowed)
				(vias not_allowed)
				(pads allowed)
				(copperpour not_allowed)
				(footprints allowed)
			)
			(placement
				(enabled no)
				(sheetname "")
			)
			(fill
				(thermal_gap 0.5)
				(thermal_bridge_width 0.5)
				(island_removal_mode 0)
			)
			(polygon
				(pts
					(xy 134.366 -66.929) (xy 133.7564 -66.929) (xy 133.7564 -66.7766) (xy 134.366 -66.7766)
				)
			)
		)
	)
	(footprint ""
		(layer "F.Cu")
		(at 16.852392 -66.3956 180)
		(property "Reference" "R347"
			(at -0.927608 -1.53035 0)
			(unlocked yes)
			(layer "F.SilkS")
			(effects
				(font
					(size 0.635 0.4064)
					(thickness 0.1524)
				)
			)
		)
		(property "Value" "VAL*"
			(at 0.02032 2.13233 180)
			(unlocked yes)
			(layer "F.Fab")
			(hide yes)
			(effects
				(font
					(size 0.7874 0.5842)
					(thickness 0.1524)
				)
			)
		)
		(property "Tolerance" "TOL*"
			(at 0.044704 3.05435 180)
			(unlocked yes)
			(layer "Cmts.User")
			(hide yes)
			(effects
				(font
					(size 0.7874 0.5842)
					(thickness 0.1524)
				)
			)
		)
		(property "User Part Number" "PARTNUM*"
			(at 0.02032 4.024884 180)
			(unlocked yes)
			(layer "Cmts.User")
			(hide yes)
			(effects
				(font
					(size 0.7874 0.5842)
					(thickness 0.1524)
				)
			)
		)
		(property "Device Type" "RESISTOR-G155-100R0-J0,0OHM,-"
			(at 0.008382 1.210564 180)
			(unlocked yes)
			(layer "F.Fab")
			(hide yes)
			(effects
				(font
					(size 0.7874 0.5842)
					(thickness 0.1524)
				)
			)
		)
		(duplicate_pad_numbers_are_jumpers no)
		(fp_line
			(start 1.143 0.5588)
			(end 1.143 -0.5588)
			(stroke
				(width 0.1)
				(type default)
			)
			(layer "F.SilkS")
		)
		(fp_line
			(start 1.143 -0.5588)
			(end -1.143 -0.5588)
			(stroke
				(width 0.1)
				(type default)
			)
			(layer "F.SilkS")
		)
		(fp_line
			(start -1.143 0.5588)
			(end 1.143 0.5588)
			(stroke
				(width 0.1)
				(type default)
			)
			(layer "F.SilkS")
		)
		(fp_line
			(start -1.143 -0.5588)
			(end -1.143 0.5588)
			(stroke
				(width 0.1)
				(type default)
			)
			(layer "F.SilkS")
		)
		(fp_poly
			(pts
				(xy -1.143 0.5588) (xy 1.143 0.5588) (xy 1.143 -0.5588) (xy -1.143 -0.5588)
			)
			(stroke
				(width 0)
				(type default)
			)
			(fill no)
			(layer "F.CrtYd")
		)
		(fp_line
			(start 0.508 0.3048)
			(end 0.508 -0.3048)
			(stroke
				(width 0.1)
				(type default)
			)
			(layer "F.Fab")
		)
		(fp_line
			(start 0.508 -0.3048)
			(end -0.508 -0.3048)
			(stroke
				(width 0.1)
				(type default)
			)
			(layer "F.Fab")
		)
		(fp_line
			(start -0.508 0.3048)
			(end 0.508 0.3048)
			(stroke
				(width 0.1)
				(type default)
			)
			(layer "F.Fab")
		)
		(fp_line
			(start -0.508 -0.3048)
			(end -0.508 0.3048)
			(stroke
				(width 0.1)
				(type default)
			)
			(layer "F.Fab")
		)
		(pad "1" smd rect
			(at -0.5334 0 180)
			(size 0.7112 0.6096)
			(layers "F.Cu" "F.Mask" "F.Paste")
			(net "UNNAMED_8_ICP10100LGA10_I24_R_2")
		)
		(pad "2" smd rect
			(at 0.5334 0 180)
			(size 0.7112 0.6096)
			(layers "F.Cu" "F.Mask" "F.Paste")
			(net "XP1R8V_ICP10100")
		)
		(zone
			(layer "F.Cu")
			(hatch none 0.5)
			(connect_pads
				(clearance 0)
			)
			(min_thickness 0.25)
			(keepout
				(tracks allowed)
				(vias not_allowed)
				(pads allowed)
				(copperpour not_allowed)
				(footprints allowed)
			)
			(placement
				(enabled no)
				(sheetname "")
			)
			(fill
				(thermal_gap 0.5)
				(thermal_bridge_width 0.5)
				(island_removal_mode 0)
			)
			(polygon
				(pts
					(xy 16.928592 -66.7004) (xy 16.776192 -66.7004) (xy 16.776192 -66.0908) (xy 16.928592 -66.0908)
				)
			)
		)
		(zone
			(layer "F.Cu")
			(hatch none 0.5)
			(connect_pads
				(clearance 0)
			)
			(min_thickness 0.25)
			(keepout
				(tracks not_allowed)
				(vias allowed)
				(pads allowed)
				(copperpour not_allowed)
				(footprints allowed)
			)
			(placement
				(enabled no)
				(sheetname "")
			)
			(fill
				(thermal_gap 0.5)
				(thermal_bridge_width 0.5)
				(island_removal_mode 0)
			)
			(polygon
				(pts
					(xy 16.928592 -66.7004) (xy 16.776192 -66.7004) (xy 16.776192 -66.0908) (xy 16.928592 -66.0908)
				)
			)
		)
	)
	(footprint ""
		(layer "F.Cu")
		(at 77.47 -98.171 -90)
		(property "Reference" "L2"
			(at 0.127 5.04063 90)
			(unlocked yes)
			(layer "F.SilkS")
			(effects
				(font
					(size 0.7874 0.5842)
					(thickness 0.1524)
				)
			)
		)
		(property "Value" "VAL*"
			(at -0.035306 8.510778 270)
			(unlocked yes)
			(layer "F.Fab")
			(hide yes)
			(effects
				(font
					(size 0.7874 0.5842)
					(thickness 0.1524)
				)
			)
		)
		(property "Tolerance" "TOL*"
			(at -0.061722 7.222744 270)
			(unlocked yes)
			(layer "Cmts.User")
			(hide yes)
			(effects
				(font
					(size 0.7874 0.5842)
					(thickness 0.1524)
				)
			)
		)
		(property "User Part Number" "PARTNUM*"
			(at 0 6.106668 270)
			(unlocked yes)
			(layer "Cmts.User")
			(hide yes)
			(effects
				(font
					(size 0.7874 0.5842)
					(thickness 0.1524)
				)
			)
		)
		(property "Device Type" "INDUCTOR_2-G190-10424-01,4.7UHA"
			(at 0 4.912868 270)
			(unlocked yes)
			(layer "F.Fab")
			(hide yes)
			(effects
				(font
					(size 0.7874 0.5842)
					(thickness 0.1524)
				)
			)
		)
		(duplicate_pad_numbers_are_jumpers no)
		(fp_line
			(start -4.448302 3.803904)
			(end -4.448302 -3.803904)
			(stroke
				(width 0.1)
				(type default)
			)
			(layer "F.SilkS")
		)
		(fp_line
			(start 4.448302 3.803904)
			(end -4.448302 3.803904)
			(stroke
				(width 0.1)
				(type default)
			)
			(layer "F.SilkS")
		)
		(fp_line
			(start -4.448302 -3.803904)
			(end 4.448302 -3.803904)
			(stroke
				(width 0.1)
				(type default)
			)
			(layer "F.SilkS")
		)
		(fp_line
			(start 4.448302 -3.803904)
			(end 4.448302 3.803904)
			(stroke
				(width 0.1)
				(type default)
			)
			(layer "F.SilkS")
		)
		(fp_rect
			(start 4.702302 -4.057904)
			(end -4.702302 4.057904)
			(stroke
				(width 0)
				(type default)
			)
			(fill no)
			(layer "F.CrtYd")
		)
		(fp_line
			(start -3.800094 3.549904)
			(end -3.800094 -3.549904)
			(stroke
				(width 0.1)
				(type default)
			)
			(layer "F.Fab")
		)
		(fp_line
			(start 3.800094 3.549904)
			(end -3.800094 3.549904)
			(stroke
				(width 0.1)
				(type default)
			)
			(layer "F.Fab")
		)
		(fp_line
			(start -3.800094 -3.549904)
			(end 3.800094 -3.549904)
			(stroke
				(width 0.1)
				(type default)
			)
			(layer "F.Fab")
		)
		(fp_line
			(start 3.800094 -3.549904)
			(end 3.800094 3.549904)
			(stroke
				(width 0.1)
				(type default)
			)
			(layer "F.Fab")
		)
		(fp_text user "1"
			(at -5.42163 0 0)
			(unlocked yes)
			(layer "F.SilkS")
			(effects
				(font
					(size 0.7874 0.5842)
					(thickness 0.1524)
				)
			)
		)
		(fp_text user "2"
			(at 5.50037 -0.254 0)
			(unlocked yes)
			(layer "F.SilkS")
			(effects
				(font
					(size 0.7874 0.5842)
					(thickness 0.1524)
				)
			)
		)
		(fp_text user "1"
			(at -4.67233 0 0)
			(unlocked yes)
			(layer "F.Fab")
			(effects
				(font
					(size 0.7874 0.5842)
					(thickness 0.1524)
				)
			)
		)
		(fp_text user "2"
			(at 4.59867 0 0)
			(unlocked yes)
			(layer "F.Fab")
			(effects
				(font
					(size 0.7874 0.5842)
					(thickness 0.1524)
				)
			)
		)
		(pad "1" smd rect
			(at -2.975102 0 270)
			(size 2.4384 3.7084)
			(layers "F.Cu" "F.Mask" "F.Paste")
			(net "XP3R3V_SW")
		)
		(pad "2" smd rect
			(at 2.975102 0 270)
			(size 2.4384 3.7084)
			(layers "F.Cu" "F.Mask" "F.Paste")
			(net "XP3R3V")
		)
		(zone
			(layer "F.Cu")
			(hatch none 0.5)
			(connect_pads
				(clearance 0)
			)
			(min_thickness 0.25)
			(keepout
				(tracks allowed)
				(vias not_allowed)
				(pads allowed)
				(copperpour not_allowed)
				(footprints allowed)
			)
			(placement
				(enabled no)
				(sheetname "")
			)
			(fill
				(thermal_gap 0.5)
				(thermal_bridge_width 0.5)
				(island_removal_mode 0)
			)
			(polygon
				(pts
					(xy 73.920096 -101.971094) (xy 75.6158 -101.971094) (xy 75.6158 -99.926902) (xy 79.3242 -99.926902)
					(xy 79.3242 -101.971094) (xy 81.019904 -101.971094) (xy 81.019904 -94.370906) (xy 79.3242 -94.370906)
					(xy 79.3242 -96.415098) (xy 75.6158 -96.415098) (xy 75.6158 -94.370906) (xy 73.920096 -94.370906)
				)
			)
		)
	)
	(footprint ""
		(layer "F.Cu")
		(at 48.768 -122.555)
		(property "Reference" "SP77"
			(at 0 0 0)
			(layer "F.SilkS")
			(hide yes)
			(effects
				(font
					(size 1.27 1.27)
				)
			)
		)
		(property "Value" ""
			(at 0 0 0)
			(layer "F.Fab")
			(effects
				(font
					(size 1.27 1.27)
				)
			)
		)
		(duplicate_pad_numbers_are_jumpers no)
	)
	(footprint ""
		(layer "F.Cu")
		(at 84.0232 -105.0798 180)
		(property "Reference" "C53"
			(at 2.794 -0.16637 0)
			(unlocked yes)
			(layer "F.SilkS")
			(effects
				(font
					(size 0.7874 0.5842)
					(thickness 0.1524)
				)
			)
		)
		(property "Value" "VAL*"
			(at 0.0762 2.067306 180)
			(unlocked yes)
			(layer "F.Fab")
			(hide yes)
			(effects
				(font
					(size 0.7874 0.5842)
					(thickness 0.1524)
				)
			)
		)
		(property "Tolerance" "TOL*"
			(at 0.0762 3.032506 180)
			(unlocked yes)
			(layer "Cmts.User")
			(hide yes)
			(effects
				(font
					(size 0.7874 0.5842)
					(thickness 0.1524)
				)
			)
		)
		(property "User Part Number" "PARTNUM*"
			(at 0.1016 4.023106 180)
			(unlocked yes)
			(layer "Cmts.User")
			(hide yes)
			(effects
				(font
					(size 0.7874 0.5842)
					(thickness 0.1524)
				)
			)
		)
		(property "Device Type" "CAPACITOR-G105-0B104-EK,0.1UF,A"
			(at 0.0508 1.127506 180)
			(unlocked yes)
			(layer "F.Fab")
			(hide yes)
			(effects
				(font
					(size 0.7874 0.5842)
					(thickness 0.1524)
				)
			)
		)
		(duplicate_pad_numbers_are_jumpers no)
		(fp_line
			(start 1.143 0.5588)
			(end 1.143 -0.5588)
			(stroke
				(width 0.1)
				(type default)
			)
			(layer "F.SilkS")
		)
		(fp_line
			(start 1.143 -0.5588)
			(end -1.143 -0.5588)
			(stroke
				(width 0.1)
				(type default)
			)
			(layer "F.SilkS")
		)
		(fp_line
			(start -1.143 0.5588)
			(end 1.143 0.5588)
			(stroke
				(width 0.1)
				(type default)
			)
			(layer "F.SilkS")
		)
		(fp_line
			(start -1.143 -0.5588)
			(end -1.143 0.5588)
			(stroke
				(width 0.1)
				(type default)
			)
			(layer "F.SilkS")
		)
		(fp_rect
			(start 1.143 -0.5588)
			(end -1.143 0.5588)
			(stroke
				(width 0)
				(type default)
			)
			(fill no)
			(layer "F.CrtYd")
		)
		(fp_line
			(start 0.508 0.3048)
			(end 0.508 -0.3048)
			(stroke
				(width 0.1)
				(type default)
			)
			(layer "F.Fab")
		)
		(fp_line
			(start 0.508 -0.3048)
			(end -0.508 -0.3048)
			(stroke
				(width 0.1)
				(type default)
			)
			(layer "F.Fab")
		)
		(fp_line
			(start -0.508 0.3048)
			(end 0.508 0.3048)
			(stroke
				(width 0.1)
				(type default)
			)
			(layer "F.Fab")
		)
		(fp_line
			(start -0.508 -0.3048)
			(end -0.508 0.3048)
			(stroke
				(width 0.1)
				(type default)
			)
			(layer "F.Fab")
		)
		(pad "1" smd rect
			(at -0.5334 0 180)
			(size 0.7112 0.6096)
			(layers "F.Cu" "F.Mask" "F.Paste")
			(net "VIN_XP3R3")
		)
		(pad "2" smd rect
			(at 0.5334 0 180)
			(size 0.7112 0.6096)
			(layers "F.Cu" "F.Mask" "F.Paste")
			(net "SG")
		)
		(zone
			(layer "F.Cu")
			(hatch none 0.5)
			(connect_pads
				(clearance 0)
			)
			(min_thickness 0.25)
			(keepout
				(tracks allowed)
				(vias not_allowed)
				(pads allowed)
				(copperpour not_allowed)
				(footprints allowed)
			)
			(placement
				(enabled no)
				(sheetname "")
			)
			(fill
				(thermal_gap 0.5)
				(thermal_bridge_width 0.5)
				(island_removal_mode 0)
			)
			(polygon
				(pts
					(xy 83.947 -104.775) (xy 84.0994 -104.775) (xy 84.0994 -105.3846) (xy 83.947 -105.3846)
				)
			)
		)
	)
	(footprint ""
		(layer "F.Cu")
		(at 79.883 -41.783 180)
		(property "Reference" "R287"
			(at -0.381 -13.88237 0)
			(unlocked yes)
			(layer "F.SilkS")
			(effects
				(font
					(size 0.7874 0.5842)
					(thickness 0.1524)
				)
			)
		)
		(property "Value" "VAL*"
			(at 0.02032 2.13233 180)
			(unlocked yes)
			(layer "F.Fab")
			(hide yes)
			(effects
				(font
					(size 0.7874 0.5842)
					(thickness 0.1524)
				)
			)
		)
		(property "Device Type" "RESISTOR-G155-14701-01,4.7KOHMA"
			(at 0.008382 1.210564 180)
			(unlocked yes)
			(layer "F.Fab")
			(hide yes)
			(effects
				(font
					(size 0.7874 0.5842)
					(thickness 0.1524)
				)
			)
		)
		(property "User Part Number" "PARTNUM*"
			(at 0.02032 4.024884 180)
			(unlocked yes)
			(layer "Cmts.User")
			(hide yes)
			(effects
				(font
					(size 0.7874 0.5842)
					(thickness 0.1524)
				)
			)
		)
		(property "Tolerance" "TOL*"
			(at 0.044704 3.05435 180)
			(unlocked yes)
			(layer "Cmts.User")
			(hide yes)
			(effects
				(font
					(size 0.7874 0.5842)
					(thickness 0.1524)
				)
			)
		)
		(duplicate_pad_numbers_are_jumpers no)
		(fp_line
			(start 1.143 0.5588)
			(end 1.143 -0.5588)
			(stroke
				(width 0.1)
				(type default)
			)
			(layer "F.SilkS")
		)
		(fp_line
			(start 1.143 -0.5588)
			(end -1.143 -0.5588)
			(stroke
				(width 0.1)
				(type default)
			)
			(layer "F.SilkS")
		)
		(fp_line
			(start -1.143 0.5588)
			(end 1.143 0.5588)
			(stroke
				(width 0.1)
				(type default)
			)
			(layer "F.SilkS")
		)
		(fp_line
			(start -1.143 -0.5588)
			(end -1.143 0.5588)
			(stroke
				(width 0.1)
				(type default)
			)
			(layer "F.SilkS")
		)
		(fp_rect
			(start 1.143 -0.5588)
			(end -1.143 0.5588)
			(stroke
				(width 0)
				(type default)
			)
			(fill no)
			(layer "F.CrtYd")
		)
		(fp_line
			(start 0.508 0.3048)
			(end 0.508 -0.3048)
			(stroke
				(width 0.1)
				(type default)
			)
			(layer "F.Fab")
		)
		(fp_line
			(start 0.508 -0.3048)
			(end -0.508 -0.3048)
			(stroke
				(width 0.1)
				(type default)
			)
			(layer "F.Fab")
		)
		(fp_line
			(start -0.508 0.3048)
			(end 0.508 0.3048)
			(stroke
				(width 0.1)
				(type default)
			)
			(layer "F.Fab")
		)
		(fp_line
			(start -0.508 -0.3048)
			(end -0.508 0.3048)
			(stroke
				(width 0.1)
				(type default)
			)
			(layer "F.Fab")
		)
		(pad "1" smd rect
			(at -0.5334 0 180)
			(size 0.7112 0.6096)
			(layers "F.Cu" "F.Mask" "F.Paste")
			(net "FPGA_IN_MAC_ALARM_OUT_N")
		)
		(pad "2" smd rect
			(at 0.5334 0 180)
			(size 0.7112 0.6096)
			(layers "F.Cu" "F.Mask" "F.Paste")
			(net "XP3R3V_FPGA")
		)
		(zone
			(layer "F.Cu")
			(hatch none 0.5)
			(connect_pads
				(clearance 0)
			)
			(min_thickness 0.25)
			(keepout
				(tracks allowed)
				(vias not_allowed)
				(pads allowed)
				(copperpour not_allowed)
				(footprints allowed)
			)
			(placement
				(enabled no)
				(sheetname "")
			)
			(fill
				(thermal_gap 0.5)
				(thermal_bridge_width 0.5)
				(island_removal_mode 0)
			)
			(polygon
				(pts
					(xy 79.8068 -41.4782) (xy 79.9592 -41.4782) (xy 79.9592 -42.0878) (xy 79.8068 -42.0878)
				)
			)
		)
	)
	(footprint ""
		(layer "F.Cu")
		(at 70.485 -132.207)
		(property "Reference" "SP40"
			(at 0 0 0)
			(layer "F.SilkS")
			(hide yes)
			(effects
				(font
					(size 1.27 1.27)
				)
			)
		)
		(property "Value" ""
			(at 0 0 0)
			(layer "F.Fab")
			(effects
				(font
					(size 1.27 1.27)
				)
			)
		)
		(duplicate_pad_numbers_are_jumpers no)
	)
	(footprint ""
		(layer "F.Cu")
		(at 97.4598 -68.072)
		(property "Reference" "R186"
			(at -28.067 -19.014694 0)
			(unlocked yes)
			(layer "F.SilkS")
			(effects
				(font
					(size 0.7874 0.5842)
					(thickness 0.1524)
				)
			)
		)
		(property "Value" "VAL*"
			(at 0.02032 2.13233 0)
			(unlocked yes)
			(layer "F.Fab")
			(hide yes)
			(effects
				(font
					(size 0.7874 0.5842)
					(thickness 0.1524)
				)
			)
		)
		(property "Tolerance" "TOL*"
			(at 0.044704 3.05435 0)
			(unlocked yes)
			(layer "Cmts.User")
			(hide yes)
			(effects
				(font
					(size 0.7874 0.5842)
					(thickness 0.1524)
				)
			)
		)
		(property "User Part Number" "PARTNUM*"
			(at 0.02032 4.024884 0)
			(unlocked yes)
			(layer "Cmts.User")
			(hide yes)
			(effects
				(font
					(size 0.7874 0.5842)
					(thickness 0.1524)
				)
			)
		)
		(property "Device Type" "RESISTOR-G155-03001-01,3KOHM,1%"
			(at 0.008382 1.210564 0)
			(unlocked yes)
			(layer "F.Fab")
			(hide yes)
			(effects
				(font
					(size 0.7874 0.5842)
					(thickness 0.1524)
				)
			)
		)
		(duplicate_pad_numbers_are_jumpers no)
		(fp_line
			(start -1.143 -0.5588)
			(end -1.143 0.5588)
			(stroke
				(width 0.1)
				(type default)
			)
			(layer "F.SilkS")
		)
		(fp_line
			(start -1.143 0.5588)
			(end 1.143 0.5588)
			(stroke
				(width 0.1)
				(type default)
			)
			(layer "F.SilkS")
		)
		(fp_line
			(start 1.143 -0.5588)
			(end -1.143 -0.5588)
			(stroke
				(width 0.1)
				(type default)
			)
			(layer "F.SilkS")
		)
		(fp_line
			(start 1.143 0.5588)
			(end 1.143 -0.5588)
			(stroke
				(width 0.1)
				(type default)
			)
			(layer "F.SilkS")
		)
		(fp_poly
			(pts
				(xy -1.143 0.5588) (xy 1.143 0.5588) (xy 1.143 -0.5588) (xy -1.143 -0.5588)
			)
			(stroke
				(width 0)
				(type default)
			)
			(fill no)
			(layer "F.CrtYd")
		)
		(fp_line
			(start -0.508 -0.3048)
			(end -0.508 0.3048)
			(stroke
				(width 0.1)
				(type default)
			)
			(layer "F.Fab")
		)
		(fp_line
			(start -0.508 0.3048)
			(end 0.508 0.3048)
			(stroke
				(width 0.1)
				(type default)
			)
			(layer "F.Fab")
		)
		(fp_line
			(start 0.508 -0.3048)
			(end -0.508 -0.3048)
			(stroke
				(width 0.1)
				(type default)
			)
			(layer "F.Fab")
		)
		(fp_line
			(start 0.508 0.3048)
			(end 0.508 -0.3048)
			(stroke
				(width 0.1)
				(type default)
			)
			(layer "F.Fab")
		)
		(pad "1" smd rect
			(at -0.5334 0)
			(size 0.7112 0.6096)
			(layers "F.Cu" "F.Mask" "F.Paste")
			(net "SG")
		)
		(pad "2" smd rect
			(at 0.5334 0)
			(size 0.7112 0.6096)
			(layers "F.Cu" "F.Mask" "F.Paste")
			(net "XP1R2V_FB")
		)
		(zone
			(layer "F.Cu")
			(hatch none 0.5)
			(connect_pads
				(clearance 0)
			)
			(min_thickness 0.25)
			(keepout
				(tracks not_allowed)
				(vias allowed)
				(pads allowed)
				(copperpour not_allowed)
				(footprints allowed)
			)
			(placement
				(enabled no)
				(sheetname "")
			)
			(fill
				(thermal_gap 0.5)
				(thermal_bridge_width 0.5)
				(island_removal_mode 0)
			)
			(polygon
				(pts
					(xy 97.3836 -67.7672) (xy 97.536 -67.7672) (xy 97.536 -68.3768) (xy 97.3836 -68.3768)
				)
			)
		)
		(zone
			(layer "F.Cu")
			(hatch none 0.5)
			(connect_pads
				(clearance 0)
			)
			(min_thickness 0.25)
			(keepout
				(tracks allowed)
				(vias not_allowed)
				(pads allowed)
				(copperpour not_allowed)
				(footprints allowed)
			)
			(placement
				(enabled no)
				(sheetname "")
			)
			(fill
				(thermal_gap 0.5)
				(thermal_bridge_width 0.5)
				(island_removal_mode 0)
			)
			(polygon
				(pts
					(xy 97.3836 -67.7672) (xy 97.536 -67.7672) (xy 97.536 -68.3768) (xy 97.3836 -68.3768)
				)
			)
		)
	)
	(footprint ""
		(layer "F.Cu")
		(at 19.468338 -46.736 180)
		(property "Reference" "R424"
			(at -3.518662 -0.03937 0)
			(unlocked yes)
			(layer "F.SilkS")
			(effects
				(font
					(size 0.7874 0.5842)
					(thickness 0.1524)
				)
			)
		)
		(property "Value" "VAL*"
			(at 0.02032 2.13233 180)
			(unlocked yes)
			(layer "F.Fab")
			(hide yes)
			(effects
				(font
					(size 0.7874 0.5842)
					(thickness 0.1524)
				)
			)
		)
		(property "Device Type" "RESISTOR-G155-11000-01,100OHM,A"
			(at 0.008382 1.210564 180)
			(unlocked yes)
			(layer "F.Fab")
			(hide yes)
			(effects
				(font
					(size 0.7874 0.5842)
					(thickness 0.1524)
				)
			)
		)
		(property "User Part Number" "PARTNUM*"
			(at 0.02032 4.024884 180)
			(unlocked yes)
			(layer "Cmts.User")
			(hide yes)
			(effects
				(font
					(size 0.7874 0.5842)
					(thickness 0.1524)
				)
			)
		)
		(property "Tolerance" "TOL*"
			(at 0.044704 3.05435 180)
			(unlocked yes)
			(layer "Cmts.User")
			(hide yes)
			(effects
				(font
					(size 0.7874 0.5842)
					(thickness 0.1524)
				)
			)
		)
		(duplicate_pad_numbers_are_jumpers no)
		(fp_line
			(start 1.143 0.5588)
			(end 1.143 -0.5588)
			(stroke
				(width 0.1)
				(type default)
			)
			(layer "F.SilkS")
		)
		(fp_line
			(start 1.143 -0.5588)
			(end -1.143 -0.5588)
			(stroke
				(width 0.1)
				(type default)
			)
			(layer "F.SilkS")
		)
		(fp_line
			(start -1.143 0.5588)
			(end 1.143 0.5588)
			(stroke
				(width 0.1)
				(type default)
			)
			(layer "F.SilkS")
		)
		(fp_line
			(start -1.143 -0.5588)
			(end -1.143 0.5588)
			(stroke
				(width 0.1)
				(type default)
			)
			(layer "F.SilkS")
		)
		(fp_poly
			(pts
				(xy -1.143 0.5588) (xy 1.143 0.5588) (xy 1.143 -0.5588) (xy -1.143 -0.5588)
			)
			(stroke
				(width 0)
				(type default)
			)
			(fill no)
			(layer "F.CrtYd")
		)
		(fp_line
			(start 0.508 0.3048)
			(end 0.508 -0.3048)
			(stroke
				(width 0.1)
				(type default)
			)
			(layer "F.Fab")
		)
		(fp_line
			(start 0.508 -0.3048)
			(end -0.508 -0.3048)
			(stroke
				(width 0.1)
				(type default)
			)
			(layer "F.Fab")
		)
		(fp_line
			(start -0.508 0.3048)
			(end 0.508 0.3048)
			(stroke
				(width 0.1)
				(type default)
			)
			(layer "F.Fab")
		)
		(fp_line
			(start -0.508 -0.3048)
			(end -0.508 0.3048)
			(stroke
				(width 0.1)
				(type default)
			)
			(layer "F.Fab")
		)
		(pad "1" smd rect
			(at -0.5334 0 180)
			(size 0.7112 0.6096)
			(layers "F.Cu" "F.Mask" "F.Paste")
			(net "FPGA_OUT_SMA4_LED_RED_N")
		)
		(pad "2" smd rect
			(at 0.5334 0 180)
			(size 0.7112 0.6096)
			(layers "F.Cu" "F.Mask" "F.Paste")
			(net "UNNAMED_14_LED4PV14_I268_3")
		)
		(zone
			(layer "F.Cu")
			(hatch none 0.5)
			(connect_pads
				(clearance 0)
			)
			(min_thickness 0.25)
			(keepout
				(tracks allowed)
				(vias not_allowed)
				(pads allowed)
				(copperpour not_allowed)
				(footprints allowed)
			)
			(placement
				(enabled no)
				(sheetname "")
			)
			(fill
				(thermal_gap 0.5)
				(thermal_bridge_width 0.5)
				(island_removal_mode 0)
			)
			(polygon
				(pts
					(xy 19.544538 -47.0408) (xy 19.392138 -47.0408) (xy 19.392138 -46.4312) (xy 19.544538 -46.4312)
				)
			)
		)
		(zone
			(layer "F.Cu")
			(hatch none 0.5)
			(connect_pads
				(clearance 0)
			)
			(min_thickness 0.25)
			(keepout
				(tracks not_allowed)
				(vias allowed)
				(pads allowed)
				(copperpour not_allowed)
				(footprints allowed)
			)
			(placement
				(enabled no)
				(sheetname "")
			)
			(fill
				(thermal_gap 0.5)
				(thermal_bridge_width 0.5)
				(island_removal_mode 0)
			)
			(polygon
				(pts
					(xy 19.544538 -47.0408) (xy 19.392138 -47.0408) (xy 19.392138 -46.4312) (xy 19.544538 -46.4312)
				)
			)
		)
	)
	(footprint ""
		(layer "F.Cu")
		(at 115.443 -74.803)
		(property "Reference" "C236"
			(at 3.302 0.42037 0)
			(unlocked yes)
			(layer "F.SilkS")
			(effects
				(font
					(size 0.7874 0.5842)
					(thickness 0.1524)
				)
			)
		)
		(property "Value" "VAL*"
			(at 0.0762 2.067306 0)
			(unlocked yes)
			(layer "F.Fab")
			(hide yes)
			(effects
				(font
					(size 0.7874 0.5842)
					(thickness 0.1524)
				)
			)
		)
		(property "Device Type" "CAPACITOR-G105-0B104-EK,0.1UF,A"
			(at 0.0508 1.127506 0)
			(unlocked yes)
			(layer "F.Fab")
			(hide yes)
			(effects
				(font
					(size 0.7874 0.5842)
					(thickness 0.1524)
				)
			)
		)
		(property "User Part Number" "PARTNUM*"
			(at 0.1016 4.023106 0)
			(unlocked yes)
			(layer "Cmts.User")
			(hide yes)
			(effects
				(font
					(size 0.7874 0.5842)
					(thickness 0.1524)
				)
			)
		)
		(property "Tolerance" "TOL*"
			(at 0.0762 3.032506 0)
			(unlocked yes)
			(layer "Cmts.User")
			(hide yes)
			(effects
				(font
					(size 0.7874 0.5842)
					(thickness 0.1524)
				)
			)
		)
		(duplicate_pad_numbers_are_jumpers no)
		(fp_line
			(start -1.143 -0.5588)
			(end -1.143 0.5588)
			(stroke
				(width 0.1)
				(type default)
			)
			(layer "F.SilkS")
		)
		(fp_line
			(start -1.143 0.5588)
			(end 1.143 0.5588)
			(stroke
				(width 0.1)
				(type default)
			)
			(layer "F.SilkS")
		)
		(fp_line
			(start 1.143 -0.5588)
			(end -1.143 -0.5588)
			(stroke
				(width 0.1)
				(type default)
			)
			(layer "F.SilkS")
		)
		(fp_line
			(start 1.143 0.5588)
			(end 1.143 -0.5588)
			(stroke
				(width 0.1)
				(type default)
			)
			(layer "F.SilkS")
		)
		(fp_rect
			(start -1.143 0.5588)
			(end 1.143 -0.5588)
			(stroke
				(width 0)
				(type default)
			)
			(fill no)
			(layer "F.CrtYd")
		)
		(fp_line
			(start -0.508 -0.3048)
			(end -0.508 0.3048)
			(stroke
				(width 0.1)
				(type default)
			)
			(layer "F.Fab")
		)
		(fp_line
			(start -0.508 0.3048)
			(end 0.508 0.3048)
			(stroke
				(width 0.1)
				(type default)
			)
			(layer "F.Fab")
		)
		(fp_line
			(start 0.508 -0.3048)
			(end -0.508 -0.3048)
			(stroke
				(width 0.1)
				(type default)
			)
			(layer "F.Fab")
		)
		(fp_line
			(start 0.508 0.3048)
			(end 0.508 -0.3048)
			(stroke
				(width 0.1)
				(type default)
			)
			(layer "F.Fab")
		)
		(pad "1" smd rect
			(at -0.5334 0)
			(size 0.7112 0.6096)
			(layers "F.Cu" "F.Mask" "F.Paste")
			(net "XP3R3V_FPGA_SR")
		)
		(pad "2" smd rect
			(at 0.5334 0)
			(size 0.7112 0.6096)
			(layers "F.Cu" "F.Mask" "F.Paste")
			(net "SG")
		)
		(zone
			(layer "F.Cu")
			(hatch none 0.5)
			(connect_pads
				(clearance 0)
			)
			(min_thickness 0.25)
			(keepout
				(tracks allowed)
				(vias not_allowed)
				(pads allowed)
				(copperpour not_allowed)
				(footprints allowed)
			)
			(placement
				(enabled no)
				(sheetname "")
			)
			(fill
				(thermal_gap 0.5)
				(thermal_bridge_width 0.5)
				(island_removal_mode 0)
			)
			(polygon
				(pts
					(xy 115.3668 -74.4982) (xy 115.5192 -74.4982) (xy 115.5192 -75.1078) (xy 115.3668 -75.1078)
				)
			)
		)
	)
	(footprint ""
		(layer "F.Cu")
		(at 38.862 -76.835 -90)
		(property "Reference" "R490"
			(at 0.889 3.77063 90)
			(unlocked yes)
			(layer "F.SilkS")
			(effects
				(font
					(size 0.7874 0.5842)
					(thickness 0.1524)
				)
			)
		)
		(property "Value" "VAL*"
			(at 0.02032 2.13233 270)
			(unlocked yes)
			(layer "F.Fab")
			(hide yes)
			(effects
				(font
					(size 0.7874 0.5842)
					(thickness 0.1524)
				)
			)
		)
		(property "Tolerance" "TOL*"
			(at 0.044704 3.05435 270)
			(unlocked yes)
			(layer "Cmts.User")
			(hide yes)
			(effects
				(font
					(size 0.7874 0.5842)
					(thickness 0.1524)
				)
			)
		)
		(property "User Part Number" "PARTNUM*"
			(at 0.02032 4.024884 270)
			(unlocked yes)
			(layer "Cmts.User")
			(hide yes)
			(effects
				(font
					(size 0.7874 0.5842)
					(thickness 0.1524)
				)
			)
		)
		(property "Device Type" "RESISTOR-G155-11002-01,10KOHM,A"
			(at 0.008382 1.210564 270)
			(unlocked yes)
			(layer "F.Fab")
			(hide yes)
			(effects
				(font
					(size 0.7874 0.5842)
					(thickness 0.1524)
				)
			)
		)
		(duplicate_pad_numbers_are_jumpers no)
		(fp_line
			(start -1.143 0.5588)
			(end 1.143 0.5588)
			(stroke
				(width 0.1)
				(type default)
			)
			(layer "F.SilkS")
		)
		(fp_line
			(start 1.143 0.5588)
			(end 1.143 -0.5588)
			(stroke
				(width 0.1)
				(type default)
			)
			(layer "F.SilkS")
		)
		(fp_line
			(start -1.143 -0.5588)
			(end -1.143 0.5588)
			(stroke
				(width 0.1)
				(type default)
			)
			(layer "F.SilkS")
		)
		(fp_line
			(start 1.143 -0.5588)
			(end -1.143 -0.5588)
			(stroke
				(width 0.1)
				(type default)
			)
			(layer "F.SilkS")
		)
		(fp_poly
			(pts
				(xy -1.143 0.5588) (xy 1.143 0.5588) (xy 1.143 -0.5588) (xy -1.143 -0.5588)
			)
			(stroke
				(width 0)
				(type default)
			)
			(fill no)
			(layer "F.CrtYd")
		)
		(fp_line
			(start -0.508 0.3048)
			(end 0.508 0.3048)
			(stroke
				(width 0.1)
				(type default)
			)
			(layer "F.Fab")
		)
		(fp_line
			(start 0.508 0.3048)
			(end 0.508 -0.3048)
			(stroke
				(width 0.1)
				(type default)
			)
			(layer "F.Fab")
		)
		(fp_line
			(start -0.508 -0.3048)
			(end -0.508 0.3048)
			(stroke
				(width 0.1)
				(type default)
			)
			(layer "F.Fab")
		)
		(fp_line
			(start 0.508 -0.3048)
			(end -0.508 -0.3048)
			(stroke
				(width 0.1)
				(type default)
			)
			(layer "F.Fab")
		)
		(pad "1" smd rect
			(at -0.5334 0 270)
			(size 0.7112 0.6096)
			(layers "F.Cu" "F.Mask" "F.Paste")
			(net "XP3R3V_FT4232")
		)
		(pad "2" smd rect
			(at 0.5334 0 270)
			(size 0.7112 0.6096)
			(layers "F.Cu" "F.Mask" "F.Paste")
			(net "UNNAMED_525_ISL80101IRAJZDFN10_")
		)
		(zone
			(layer "F.Cu")
			(hatch none 0.5)
			(connect_pads
				(clearance 0)
			)
			(min_thickness 0.25)
			(keepout
				(tracks allowed)
				(vias not_allowed)
				(pads allowed)
				(copperpour not_allowed)
				(footprints allowed)
			)
			(placement
				(enabled no)
				(sheetname "")
			)
			(fill
				(thermal_gap 0.5)
				(thermal_bridge_width 0.5)
				(island_removal_mode 0)
			)
			(polygon
				(pts
					(xy 38.5572 -76.9112) (xy 38.5572 -76.7588) (xy 39.1668 -76.7588) (xy 39.1668 -76.9112)
				)
			)
		)
		(zone
			(layer "F.Cu")
			(hatch none 0.5)
			(connect_pads
				(clearance 0)
			)
			(min_thickness 0.25)
			(keepout
				(tracks not_allowed)
				(vias allowed)
				(pads allowed)
				(copperpour not_allowed)
				(footprints allowed)
			)
			(placement
				(enabled no)
				(sheetname "")
			)
			(fill
				(thermal_gap 0.5)
				(thermal_bridge_width 0.5)
				(island_removal_mode 0)
			)
			(polygon
				(pts
					(xy 38.5572 -76.9112) (xy 38.5572 -76.7588) (xy 39.1668 -76.7588) (xy 39.1668 -76.9112)
				)
			)
		)
	)
	(footprint ""
		(layer "F.Cu")
		(at 152.883108 -49.01311 -90)
		(property "Reference" "R299"
			(at 0.11811 -2.858262 90)
			(unlocked yes)
			(layer "F.SilkS")
			(effects
				(font
					(size 0.7874 0.5842)
					(thickness 0.1524)
				)
			)
		)
		(property "Value" "VAL*"
			(at 0.02032 2.13233 270)
			(unlocked yes)
			(layer "F.Fab")
			(hide yes)
			(effects
				(font
					(size 0.7874 0.5842)
					(thickness 0.1524)
				)
			)
		)
		(property "Device Type" "RESISTOR-G155-133R0-01,33OHM,1%"
			(at 0.008382 1.210564 270)
			(unlocked yes)
			(layer "F.Fab")
			(hide yes)
			(effects
				(font
					(size 0.7874 0.5842)
					(thickness 0.1524)
				)
			)
		)
		(property "User Part Number" "PARTNUM*"
			(at 0.02032 4.024884 270)
			(unlocked yes)
			(layer "Cmts.User")
			(hide yes)
			(effects
				(font
					(size 0.7874 0.5842)
					(thickness 0.1524)
				)
			)
		)
		(property "Tolerance" "TOL*"
			(at 0.044704 3.05435 270)
			(unlocked yes)
			(layer "Cmts.User")
			(hide yes)
			(effects
				(font
					(size 0.7874 0.5842)
					(thickness 0.1524)
				)
			)
		)
		(duplicate_pad_numbers_are_jumpers no)
		(fp_line
			(start -1.143 0.5588)
			(end 1.143 0.5588)
			(stroke
				(width 0.1)
				(type default)
			)
			(layer "F.SilkS")
		)
		(fp_line
			(start 1.143 0.5588)
			(end 1.143 -0.5588)
			(stroke
				(width 0.1)
				(type default)
			)
			(layer "F.SilkS")
		)
		(fp_line
			(start -1.143 -0.5588)
			(end -1.143 0.5588)
			(stroke
				(width 0.1)
				(type default)
			)
			(layer "F.SilkS")
		)
		(fp_line
			(start 1.143 -0.5588)
			(end -1.143 -0.5588)
			(stroke
				(width 0.1)
				(type default)
			)
			(layer "F.SilkS")
		)
		(fp_rect
			(start -1.143 -0.5588)
			(end 1.143 0.5588)
			(stroke
				(width 0)
				(type default)
			)
			(fill no)
			(layer "F.CrtYd")
		)
		(fp_line
			(start -0.508 0.3048)
			(end 0.508 0.3048)
			(stroke
				(width 0.1)
				(type default)
			)
			(layer "F.Fab")
		)
		(fp_line
			(start 0.508 0.3048)
			(end 0.508 -0.3048)
			(stroke
				(width 0.1)
				(type default)
			)
			(layer "F.Fab")
		)
		(fp_line
			(start -0.508 -0.3048)
			(end -0.508 0.3048)
			(stroke
				(width 0.1)
				(type default)
			)
			(layer "F.Fab")
		)
		(fp_line
			(start 0.508 -0.3048)
			(end -0.508 -0.3048)
			(stroke
				(width 0.1)
				(type default)
			)
			(layer "F.Fab")
		)
		(pad "1" smd rect
			(at -0.5334 0 270)
			(size 0.7112 0.6096)
			(layers "F.Cu" "F.Mask" "F.Paste")
			(net "R_SHT3X_ALERT_N")
		)
		(pad "2" smd rect
			(at 0.5334 0 270)
			(size 0.7112 0.6096)
			(layers "F.Cu" "F.Mask" "F.Paste")
			(net "FPGA_IN_SHT3X_ALERT_N")
		)
		(zone
			(layer "F.Cu")
			(hatch none 0.5)
			(connect_pads
				(clearance 0)
			)
			(min_thickness 0.25)
			(keepout
				(tracks allowed)
				(vias not_allowed)
				(pads allowed)
				(copperpour not_allowed)
				(footprints allowed)
			)
			(placement
				(enabled no)
				(sheetname "")
			)
			(fill
				(thermal_gap 0.5)
				(thermal_bridge_width 0.5)
				(island_removal_mode 0)
			)
			(polygon
				(pts
					(xy 153.187908 -49.08931) (xy 152.578308 -49.08931) (xy 152.578308 -48.93691) (xy 153.187908 -48.93691)
				)
			)
		)
	)
	(footprint ""
		(layer "F.Cu")
		(at 118.11 -58.928 90)
		(property "Reference" "R362"
			(at -0.127 1.30937 90)
			(unlocked yes)
			(layer "F.SilkS")
			(effects
				(font
					(size 0.7874 0.5842)
					(thickness 0.1524)
				)
			)
		)
		(property "Value" "VAL*"
			(at 0.02032 2.13233 90)
			(unlocked yes)
			(layer "F.Fab")
			(hide yes)
			(effects
				(font
					(size 0.7874 0.5842)
					(thickness 0.1524)
				)
			)
		)
		(property "Tolerance" "TOL*"
			(at 0.044704 3.05435 90)
			(unlocked yes)
			(layer "Cmts.User")
			(hide yes)
			(effects
				(font
					(size 0.7874 0.5842)
					(thickness 0.1524)
				)
			)
		)
		(property "User Part Number" "PARTNUM*"
			(at 0.02032 4.024884 90)
			(unlocked yes)
			(layer "Cmts.User")
			(hide yes)
			(effects
				(font
					(size 0.7874 0.5842)
					(thickness 0.1524)
				)
			)
		)
		(property "Device Type" "RESISTOR-G155-133R0-01,33OHM,1%"
			(at 0.008382 1.210564 90)
			(unlocked yes)
			(layer "F.Fab")
			(hide yes)
			(effects
				(font
					(size 0.7874 0.5842)
					(thickness 0.1524)
				)
			)
		)
		(duplicate_pad_numbers_are_jumpers no)
		(fp_line
			(start 1.143 -0.5588)
			(end -1.143 -0.5588)
			(stroke
				(width 0.1)
				(type default)
			)
			(layer "F.SilkS")
		)
		(fp_line
			(start -1.143 -0.5588)
			(end -1.143 0.5588)
			(stroke
				(width 0.1)
				(type default)
			)
			(layer "F.SilkS")
		)
		(fp_line
			(start 1.143 0.5588)
			(end 1.143 -0.5588)
			(stroke
				(width 0.1)
				(type default)
			)
			(layer "F.SilkS")
		)
		(fp_line
			(start -1.143 0.5588)
			(end 1.143 0.5588)
			(stroke
				(width 0.1)
				(type default)
			)
			(layer "F.SilkS")
		)
		(fp_poly
			(pts
				(xy -1.143 0.5588) (xy 1.143 0.5588) (xy 1.143 -0.5588) (xy -1.143 -0.5588)
			)
			(stroke
				(width 0)
				(type default)
			)
			(fill no)
			(layer "F.CrtYd")
		)
		(fp_line
			(start 0.508 -0.3048)
			(end -0.508 -0.3048)
			(stroke
				(width 0.1)
				(type default)
			)
			(layer "F.Fab")
		)
		(fp_line
			(start -0.508 -0.3048)
			(end -0.508 0.3048)
			(stroke
				(width 0.1)
				(type default)
			)
			(layer "F.Fab")
		)
		(fp_line
			(start 0.508 0.3048)
			(end 0.508 -0.3048)
			(stroke
				(width 0.1)
				(type default)
			)
			(layer "F.Fab")
		)
		(fp_line
			(start -0.508 0.3048)
			(end 0.508 0.3048)
			(stroke
				(width 0.1)
				(type default)
			)
			(layer "F.Fab")
		)
		(pad "1" smd rect
			(at -0.5334 0 90)
			(size 0.7112 0.6096)
			(layers "F.Cu" "F.Mask" "F.Paste")
			(net "FPGA_FCS_B")
		)
		(pad "2" smd rect
			(at 0.5334 0 90)
			(size 0.7112 0.6096)
			(layers "F.Cu" "F.Mask" "F.Paste")
			(net "FPGA_FLASH_CS_N")
		)
		(zone
			(layer "F.Cu")
			(hatch none 0.5)
			(connect_pads
				(clearance 0)
			)
			(min_thickness 0.25)
			(keepout
				(tracks not_allowed)
				(vias allowed)
				(pads allowed)
				(copperpour not_allowed)
				(footprints allowed)
			)
			(placement
				(enabled no)
				(sheetname "")
			)
			(fill
				(thermal_gap 0.5)
				(thermal_bridge_width 0.5)
				(island_removal_mode 0)
			)
			(polygon
				(pts
					(xy 118.4148 -58.8518) (xy 118.4148 -59.0042) (xy 117.8052 -59.0042) (xy 117.8052 -58.8518)
				)
			)
		)
		(zone
			(layer "F.Cu")
			(hatch none 0.5)
			(connect_pads
				(clearance 0)
			)
			(min_thickness 0.25)
			(keepout
				(tracks allowed)
				(vias not_allowed)
				(pads allowed)
				(copperpour not_allowed)
				(footprints allowed)
			)
			(placement
				(enabled no)
				(sheetname "")
			)
			(fill
				(thermal_gap 0.5)
				(thermal_bridge_width 0.5)
				(island_removal_mode 0)
			)
			(polygon
				(pts
					(xy 118.4148 -58.8518) (xy 118.4148 -59.0042) (xy 117.8052 -59.0042) (xy 117.8052 -58.8518)
				)
			)
		)
	)
	(footprint ""
		(layer "F.Cu")
		(at 11.557 -28.06446 -90)
		(property "Reference" "R122"
			(at 0.50546 2.11963 90)
			(unlocked yes)
			(layer "F.SilkS")
			(effects
				(font
					(size 0.7874 0.5842)
					(thickness 0.1524)
				)
			)
		)
		(property "Value" "VAL*"
			(at 0.02032 2.13233 270)
			(unlocked yes)
			(layer "F.Fab")
			(hide yes)
			(effects
				(font
					(size 0.7874 0.5842)
					(thickness 0.1524)
				)
			)
		)
		(property "Tolerance" "TOL*"
			(at 0.044704 3.05435 270)
			(unlocked yes)
			(layer "Cmts.User")
			(hide yes)
			(effects
				(font
					(size 0.7874 0.5842)
					(thickness 0.1524)
				)
			)
		)
		(property "User Part Number" "PARTNUM*"
			(at 0.02032 4.024884 270)
			(unlocked yes)
			(layer "Cmts.User")
			(hide yes)
			(effects
				(font
					(size 0.7874 0.5842)
					(thickness 0.1524)
				)
			)
		)
		(property "Device Type" "RESISTOR-G155-149R9-01,49.9OHMA"
			(at 0.008382 1.210564 270)
			(unlocked yes)
			(layer "F.Fab")
			(hide yes)
			(effects
				(font
					(size 0.7874 0.5842)
					(thickness 0.1524)
				)
			)
		)
		(duplicate_pad_numbers_are_jumpers no)
		(fp_line
			(start -1.143 0.5588)
			(end 1.143 0.5588)
			(stroke
				(width 0.1)
				(type default)
			)
			(layer "F.SilkS")
		)
		(fp_line
			(start 1.143 0.5588)
			(end 1.143 -0.5588)
			(stroke
				(width 0.1)
				(type default)
			)
			(layer "F.SilkS")
		)
		(fp_line
			(start -1.143 -0.5588)
			(end -1.143 0.5588)
			(stroke
				(width 0.1)
				(type default)
			)
			(layer "F.SilkS")
		)
		(fp_line
			(start 1.143 -0.5588)
			(end -1.143 -0.5588)
			(stroke
				(width 0.1)
				(type default)
			)
			(layer "F.SilkS")
		)
		(fp_poly
			(pts
				(xy -1.143 0.5588) (xy 1.143 0.5588) (xy 1.143 -0.5588) (xy -1.143 -0.5588)
			)
			(stroke
				(width 0)
				(type default)
			)
			(fill no)
			(layer "F.CrtYd")
		)
		(fp_line
			(start -0.508 0.3048)
			(end 0.508 0.3048)
			(stroke
				(width 0.1)
				(type default)
			)
			(layer "F.Fab")
		)
		(fp_line
			(start 0.508 0.3048)
			(end 0.508 -0.3048)
			(stroke
				(width 0.1)
				(type default)
			)
			(layer "F.Fab")
		)
		(fp_line
			(start -0.508 -0.3048)
			(end -0.508 0.3048)
			(stroke
				(width 0.1)
				(type default)
			)
			(layer "F.Fab")
		)
		(fp_line
			(start 0.508 -0.3048)
			(end -0.508 -0.3048)
			(stroke
				(width 0.1)
				(type default)
			)
			(layer "F.Fab")
		)
		(pad "1" smd rect
			(at -0.5334 0 270)
			(size 0.7112 0.6096)
			(layers "F.Cu" "F.Mask" "F.Paste")
			(net "BF_SMA3_SIG_IO_CONN")
		)
		(pad "2" smd rect
			(at 0.5334 0 270)
			(size 0.7112 0.6096)
			(layers "F.Cu" "F.Mask" "F.Paste")
			(net "SMA3_SIG_IO_CONN")
		)
		(zone
			(layer "F.Cu")
			(hatch none 0.5)
			(connect_pads
				(clearance 0)
			)
			(min_thickness 0.25)
			(keepout
				(tracks allowed)
				(vias not_allowed)
				(pads allowed)
				(copperpour not_allowed)
				(footprints allowed)
			)
			(placement
				(enabled no)
				(sheetname "")
			)
			(fill
				(thermal_gap 0.5)
				(thermal_bridge_width 0.5)
				(island_removal_mode 0)
			)
			(polygon
				(pts
					(xy 11.2522 -28.14066) (xy 11.2522 -27.98826) (xy 11.8618 -27.98826) (xy 11.8618 -28.14066)
				)
			)
		)
		(zone
			(layer "F.Cu")
			(hatch none 0.5)
			(connect_pads
				(clearance 0)
			)
			(min_thickness 0.25)
			(keepout
				(tracks not_allowed)
				(vias allowed)
				(pads allowed)
				(copperpour not_allowed)
				(footprints allowed)
			)
			(placement
				(enabled no)
				(sheetname "")
			)
			(fill
				(thermal_gap 0.5)
				(thermal_bridge_width 0.5)
				(island_removal_mode 0)
			)
			(polygon
				(pts
					(xy 11.2522 -28.14066) (xy 11.2522 -27.98826) (xy 11.8618 -27.98826) (xy 11.8618 -28.14066)
				)
			)
		)
	)
	(footprint ""
		(layer "F.Cu")
		(at 56.388 -129.032)
		(property "Reference" "SP81"
			(at 0 0 0)
			(layer "F.SilkS")
			(hide yes)
			(effects
				(font
					(size 1.27 1.27)
				)
			)
		)
		(property "Value" ""
			(at 0 0 0)
			(layer "F.Fab")
			(effects
				(font
					(size 1.27 1.27)
				)
			)
		)
		(duplicate_pad_numbers_are_jumpers no)
	)
	(footprint ""
		(layer "F.Cu")
		(at 71.1454 -15.367)
		(property "Reference" "U3"
			(at -0.127 -2.11963 0)
			(unlocked yes)
			(layer "F.SilkS")
			(effects
				(font
					(size 0.7874 0.5842)
					(thickness 0.1524)
				)
			)
		)
		(property "Value" ""
			(at 0 0 0)
			(layer "F.Fab")
			(effects
				(font
					(size 1.27 1.27)
				)
			)
		)
		(property "Device Type" "74LVC1G07_SC70_5-G220-10017-01"
			(at 0.4064 2.05867 0)
			(unlocked yes)
			(layer "F.Fab")
			(hide yes)
			(effects
				(font
					(size 0.7874 0.5842)
					(thickness 0.1524)
				)
			)
		)
		(property "User Part Number" "PARTNUM*"
			(at 0.381 2.97307 0)
			(unlocked yes)
			(layer "Cmts.User")
			(hide yes)
			(effects
				(font
					(size 0.7874 0.5842)
					(thickness 0.1524)
				)
			)
		)
		(duplicate_pad_numbers_are_jumpers no)
		(fp_line
			(start -1.9304 -1.069086)
			(end -1.9304 1.069086)
			(stroke
				(width 0.1)
				(type default)
			)
			(layer "F.SilkS")
		)
		(fp_line
			(start -1.9304 1.069086)
			(end -0.952754 1.069086)
			(stroke
				(width 0.1)
				(type default)
			)
			(layer "F.SilkS")
		)
		(fp_line
			(start -0.952754 -1.32842)
			(end -0.952754 -1.069086)
			(stroke
				(width 0.1)
				(type default)
			)
			(layer "F.SilkS")
		)
		(fp_line
			(start -0.952754 -1.069086)
			(end -1.9304 -1.069086)
			(stroke
				(width 0.1)
				(type default)
			)
			(layer "F.SilkS")
		)
		(fp_line
			(start -0.952754 1.069086)
			(end -0.952754 1.32842)
			(stroke
				(width 0.1)
				(type default)
			)
			(layer "F.SilkS")
		)
		(fp_line
			(start -0.952754 1.32842)
			(end 0.952754 1.32842)
			(stroke
				(width 0.1)
				(type default)
			)
			(layer "F.SilkS")
		)
		(fp_line
			(start 0.952754 -1.32842)
			(end -0.952754 -1.32842)
			(stroke
				(width 0.1)
				(type default)
			)
			(layer "F.SilkS")
		)
		(fp_line
			(start 0.952754 -1.069086)
			(end 0.952754 -1.32842)
			(stroke
				(width 0.1)
				(type default)
			)
			(layer "F.SilkS")
		)
		(fp_line
			(start 0.952754 1.069086)
			(end 1.9304 1.069086)
			(stroke
				(width 0.1)
				(type default)
			)
			(layer "F.SilkS")
		)
		(fp_line
			(start 0.952754 1.32842)
			(end 0.952754 1.069086)
			(stroke
				(width 0.1)
				(type default)
			)
			(layer "F.SilkS")
		)
		(fp_line
			(start 1.9304 -1.069086)
			(end 0.952754 -1.069086)
			(stroke
				(width 0.1)
				(type default)
			)
			(layer "F.SilkS")
		)
		(fp_line
			(start 1.9304 1.069086)
			(end 1.9304 -1.069086)
			(stroke
				(width 0.1)
				(type default)
			)
			(layer "F.SilkS")
		)
		(fp_poly
			(pts
				(arc
					(start -2.196592 -0.75438)
					(mid -2.958592 -0.75438)
					(end -2.196592 -0.75438)
				)
			)
			(stroke
				(width 0)
				(type default)
			)
			(fill yes)
			(layer "F.SilkS")
		)
		(fp_rect
			(start -2.1844 1.58242)
			(end 2.1844 -1.58242)
			(stroke
				(width 0)
				(type default)
			)
			(fill no)
			(layer "F.CrtYd")
		)
		(fp_line
			(start -0.698754 -1.07442)
			(end 0.698754 -1.07442)
			(stroke
				(width 0.1)
				(type default)
			)
			(layer "F.Fab")
		)
		(fp_line
			(start -0.698754 -0.774954)
			(end -0.698754 -1.07442)
			(stroke
				(width 0.1)
				(type default)
			)
			(layer "F.Fab")
		)
		(fp_line
			(start -0.698754 -0.525018)
			(end -0.698754 -0.124968)
			(stroke
				(width 0.1)
				(type default)
			)
			(layer "F.Fab")
		)
		(fp_line
			(start -0.698754 0.124968)
			(end -0.698754 0.525018)
			(stroke
				(width 0.1)
				(type default)
			)
			(layer "F.Fab")
		)
		(fp_line
			(start -0.698754 0.774954)
			(end -0.698754 1.07442)
			(stroke
				(width 0.1)
				(type default)
			)
			(layer "F.Fab")
		)
		(fp_line
			(start -0.698754 1.07442)
			(end 0.698754 1.07442)
			(stroke
				(width 0.1)
				(type default)
			)
			(layer "F.Fab")
		)
		(fp_line
			(start -0.450088 1.07442)
			(end -0.450088 -1.07442)
			(stroke
				(width 0.1)
				(type default)
			)
			(layer "F.Fab")
		)
		(fp_line
			(start 0.450088 -1.07442)
			(end 0.450088 1.07442)
			(stroke
				(width 0.1)
				(type default)
			)
			(layer "F.Fab")
		)
		(fp_line
			(start 0.698754 -1.07442)
			(end 0.698754 -0.774954)
			(stroke
				(width 0.1)
				(type default)
			)
			(layer "F.Fab")
		)
		(fp_line
			(start 0.698754 -0.525018)
			(end 0.698754 0.525018)
			(stroke
				(width 0.1)
				(type default)
			)
			(layer "F.Fab")
		)
		(fp_line
			(start 0.698754 1.07442)
			(end 0.698754 0.774954)
			(stroke
				(width 0.1)
				(type default)
			)
			(layer "F.Fab")
		)
		(fp_rect
			(start -1.198626 -0.525018)
			(end -0.6985 -0.774954)
			(stroke
				(width 0)
				(type default)
			)
			(fill no)
			(layer "F.Fab")
		)
		(fp_rect
			(start -1.198626 0.124968)
			(end -0.6985 -0.124968)
			(stroke
				(width 0)
				(type default)
			)
			(fill no)
			(layer "F.Fab")
		)
		(fp_rect
			(start -1.198626 0.774954)
			(end -0.6985 0.525018)
			(stroke
				(width 0)
				(type default)
			)
			(fill no)
			(layer "F.Fab")
		)
		(fp_rect
			(start 0.6985 -0.525018)
			(end 1.198626 -0.774954)
			(stroke
				(width 0)
				(type default)
			)
			(fill no)
			(layer "F.Fab")
		)
		(fp_rect
			(start 0.6985 0.774954)
			(end 1.198626 0.525018)
			(stroke
				(width 0)
				(type default)
			)
			(fill no)
			(layer "F.Fab")
		)
		(fp_poly
			(pts
				(arc
					(start -1.942592 -0.75438)
					(mid -2.704592 -0.75438)
					(end -1.942592 -0.75438)
				)
			)
			(stroke
				(width 0)
				(type default)
			)
			(fill yes)
			(layer "F.Fab")
		)
		(fp_text user "3"
			(at -2.413 0.797306 0)
			(unlocked yes)
			(layer "F.SilkS")
			(effects
				(font
					(size 0.7874 0.5842)
					(thickness 0.1524)
				)
			)
		)
		(fp_text user "5"
			(at 2.413 -0.599948 0)
			(unlocked yes)
			(layer "F.SilkS")
			(effects
				(font
					(size 0.7874 0.5842)
					(thickness 0.1524)
				)
			)
		)
		(fp_text user "4"
			(at 2.442972 0.7747 0)
			(unlocked yes)
			(layer "F.SilkS")
			(effects
				(font
					(size 0.7874 0.5842)
					(thickness 0.1524)
				)
			)
		)
		(fp_text user "3"
			(at -2.159 0.797306 0)
			(unlocked yes)
			(layer "F.Fab")
			(effects
				(font
					(size 0.7874 0.5842)
					(thickness 0.1524)
				)
			)
		)
		(fp_text user "5"
			(at 2.159 -0.599948 0)
			(unlocked yes)
			(layer "F.Fab")
			(effects
				(font
					(size 0.7874 0.5842)
					(thickness 0.1524)
				)
			)
		)
		(fp_text user "4"
			(at 2.188972 0.7747 0)
			(unlocked yes)
			(layer "F.Fab")
			(effects
				(font
					(size 0.7874 0.5842)
					(thickness 0.1524)
				)
			)
		)
		(pad "1" smd rect
			(at -1.1938 -0.649986 90)
			(size 0.3302 0.9652)
			(layers "F.Cu" "F.Mask" "F.Paste")
			(net "Net_761")
		)
		(pad "2" smd rect
			(at -1.1938 0 90)
			(size 0.3302 0.9652)
			(layers "F.Cu" "F.Mask" "F.Paste")
			(net "PCIE_CONN_PERST_N")
		)
		(pad "3" smd rect
			(at -1.1938 0.649986 90)
			(size 0.3302 0.9652)
			(layers "F.Cu" "F.Mask" "F.Paste")
			(net "SG")
		)
		(pad "4" smd rect
			(at 1.1938 0.649986 90)
			(size 0.3302 0.9652)
			(layers "F.Cu" "F.Mask" "F.Paste")
			(net "BF_PCIE_PERST_N")
		)
		(pad "5" smd rect
			(at 1.1938 -0.649986 90)
			(size 0.3302 0.9652)
			(layers "F.Cu" "F.Mask" "F.Paste")
			(net "XP3R3V_FPGA")
		)
		(zone
			(layer "F.Cu")
			(hatch none 0.5)
			(connect_pads
				(clearance 0)
			)
			(min_thickness 0.25)
			(keepout
				(tracks allowed)
				(vias not_allowed)
				(pads allowed)
				(copperpour not_allowed)
				(footprints allowed)
			)
			(placement
				(enabled no)
				(sheetname "")
			)
			(fill
				(thermal_gap 0.5)
				(thermal_bridge_width 0.5)
				(island_removal_mode 0)
			)
			(polygon
				(pts
					(xy 70.5104 -14.3637) (xy 71.7804 -14.3637) (xy 71.7804 -16.3703) (xy 70.5104 -16.3703)
				)
			)
		)
	)
	(footprint ""
		(layer "F.Cu")
		(at 91.5416 -44.868846 -90)
		(property "Reference" "R104"
			(at -0.597154 -1.44907 90)
			(unlocked yes)
			(layer "F.SilkS")
			(effects
				(font
					(size 0.7874 0.5842)
					(thickness 0.1524)
				)
			)
		)
		(property "Value" "VAL*"
			(at 0.02032 2.13233 270)
			(unlocked yes)
			(layer "F.Fab")
			(hide yes)
			(effects
				(font
					(size 0.7874 0.5842)
					(thickness 0.1524)
				)
			)
		)
		(property "Device Type" "RESISTOR-G155-14701-01,4.7KOHMA"
			(at 0.008382 1.210564 270)
			(unlocked yes)
			(layer "F.Fab")
			(hide yes)
			(effects
				(font
					(size 0.7874 0.5842)
					(thickness 0.1524)
				)
			)
		)
		(property "User Part Number" "PARTNUM*"
			(at 0.02032 4.024884 270)
			(unlocked yes)
			(layer "Cmts.User")
			(hide yes)
			(effects
				(font
					(size 0.7874 0.5842)
					(thickness 0.1524)
				)
			)
		)
		(property "Tolerance" "TOL*"
			(at 0.044704 3.05435 270)
			(unlocked yes)
			(layer "Cmts.User")
			(hide yes)
			(effects
				(font
					(size 0.7874 0.5842)
					(thickness 0.1524)
				)
			)
		)
		(duplicate_pad_numbers_are_jumpers no)
		(fp_line
			(start -1.143 0.5588)
			(end 1.143 0.5588)
			(stroke
				(width 0.1)
				(type default)
			)
			(layer "F.SilkS")
		)
		(fp_line
			(start 1.143 0.5588)
			(end 1.143 -0.5588)
			(stroke
				(width 0.1)
				(type default)
			)
			(layer "F.SilkS")
		)
		(fp_line
			(start -1.143 -0.5588)
			(end -1.143 0.5588)
			(stroke
				(width 0.1)
				(type default)
			)
			(layer "F.SilkS")
		)
		(fp_line
			(start 1.143 -0.5588)
			(end -1.143 -0.5588)
			(stroke
				(width 0.1)
				(type default)
			)
			(layer "F.SilkS")
		)
		(fp_rect
			(start -1.143 -0.5588)
			(end 1.143 0.5588)
			(stroke
				(width 0)
				(type default)
			)
			(fill no)
			(layer "F.CrtYd")
		)
		(fp_line
			(start -0.508 0.3048)
			(end 0.508 0.3048)
			(stroke
				(width 0.1)
				(type default)
			)
			(layer "F.Fab")
		)
		(fp_line
			(start 0.508 0.3048)
			(end 0.508 -0.3048)
			(stroke
				(width 0.1)
				(type default)
			)
			(layer "F.Fab")
		)
		(fp_line
			(start -0.508 -0.3048)
			(end -0.508 0.3048)
			(stroke
				(width 0.1)
				(type default)
			)
			(layer "F.Fab")
		)
		(fp_line
			(start 0.508 -0.3048)
			(end -0.508 -0.3048)
			(stroke
				(width 0.1)
				(type default)
			)
			(layer "F.Fab")
		)
		(pad "1" smd rect
			(at -0.5334 0 270)
			(size 0.7112 0.6096)
			(layers "F.Cu" "F.Mask" "F.Paste")
			(net "UNNAMED_527_RESISTOR_I126_1")
		)
		(pad "2" smd rect
			(at 0.5334 0 270)
			(size 0.7112 0.6096)
			(layers "F.Cu" "F.Mask" "F.Paste")
			(net "SG")
		)
		(zone
			(layer "F.Cu")
			(hatch none 0.5)
			(connect_pads
				(clearance 0)
			)
			(min_thickness 0.25)
			(keepout
				(tracks allowed)
				(vias not_allowed)
				(pads allowed)
				(copperpour not_allowed)
				(footprints allowed)
			)
			(placement
				(enabled no)
				(sheetname "")
			)
			(fill
				(thermal_gap 0.5)
				(thermal_bridge_width 0.5)
				(island_removal_mode 0)
			)
			(polygon
				(pts
					(xy 91.8464 -44.945046) (xy 91.2368 -44.945046) (xy 91.2368 -44.792646) (xy 91.8464 -44.792646)
				)
			)
		)
	)
	(footprint ""
		(layer "F.Cu")
		(at 119.761 -24.511)
		(property "Reference" "R485"
			(at -2.794 -0.08763 0)
			(unlocked yes)
			(layer "F.SilkS")
			(effects
				(font
					(size 0.7874 0.5842)
					(thickness 0.1524)
				)
			)
		)
		(property "Value" "VAL*"
			(at 0.02032 2.13233 0)
			(unlocked yes)
			(layer "F.Fab")
			(hide yes)
			(effects
				(font
					(size 0.7874 0.5842)
					(thickness 0.1524)
				)
			)
		)
		(property "Tolerance" "TOL*"
			(at 0.044704 3.05435 0)
			(unlocked yes)
			(layer "Cmts.User")
			(hide yes)
			(effects
				(font
					(size 0.7874 0.5842)
					(thickness 0.1524)
				)
			)
		)
		(property "User Part Number" "PARTNUM*"
			(at 0.02032 4.024884 0)
			(unlocked yes)
			(layer "Cmts.User")
			(hide yes)
			(effects
				(font
					(size 0.7874 0.5842)
					(thickness 0.1524)
				)
			)
		)
		(property "Device Type" "RESISTOR-G155-133R0-01,33OHM,1%"
			(at 0.008382 1.210564 0)
			(unlocked yes)
			(layer "F.Fab")
			(hide yes)
			(effects
				(font
					(size 0.7874 0.5842)
					(thickness 0.1524)
				)
			)
		)
		(duplicate_pad_numbers_are_jumpers no)
		(fp_line
			(start -1.143 -0.5588)
			(end -1.143 0.5588)
			(stroke
				(width 0.1)
				(type default)
			)
			(layer "F.SilkS")
		)
		(fp_line
			(start -1.143 0.5588)
			(end 1.143 0.5588)
			(stroke
				(width 0.1)
				(type default)
			)
			(layer "F.SilkS")
		)
		(fp_line
			(start 1.143 -0.5588)
			(end -1.143 -0.5588)
			(stroke
				(width 0.1)
				(type default)
			)
			(layer "F.SilkS")
		)
		(fp_line
			(start 1.143 0.5588)
			(end 1.143 -0.5588)
			(stroke
				(width 0.1)
				(type default)
			)
			(layer "F.SilkS")
		)
		(fp_poly
			(pts
				(xy -1.143 0.5588) (xy 1.143 0.5588) (xy 1.143 -0.5588) (xy -1.143 -0.5588)
			)
			(stroke
				(width 0)
				(type default)
			)
			(fill no)
			(layer "F.CrtYd")
		)
		(fp_line
			(start -0.508 -0.3048)
			(end -0.508 0.3048)
			(stroke
				(width 0.1)
				(type default)
			)
			(layer "F.Fab")
		)
		(fp_line
			(start -0.508 0.3048)
			(end 0.508 0.3048)
			(stroke
				(width 0.1)
				(type default)
			)
			(layer "F.Fab")
		)
		(fp_line
			(start 0.508 -0.3048)
			(end -0.508 -0.3048)
			(stroke
				(width 0.1)
				(type default)
			)
			(layer "F.Fab")
		)
		(fp_line
			(start 0.508 0.3048)
			(end 0.508 -0.3048)
			(stroke
				(width 0.1)
				(type default)
			)
			(layer "F.Fab")
		)
		(pad "1" smd rect
			(at -0.5334 0)
			(size 0.7112 0.6096)
			(layers "F.Cu" "F.Mask" "F.Paste")
			(net "FPGA_OUT_MUX3_SEL")
		)
		(pad "2" smd rect
			(at 0.5334 0)
			(size 0.7112 0.6096)
			(layers "F.Cu" "F.Mask" "F.Paste")
			(net "MUX3_SEL")
		)
		(zone
			(layer "F.Cu")
			(hatch none 0.5)
			(connect_pads
				(clearance 0)
			)
			(min_thickness 0.25)
			(keepout
				(tracks not_allowed)
				(vias allowed)
				(pads allowed)
				(copperpour not_allowed)
				(footprints allowed)
			)
			(placement
				(enabled no)
				(sheetname "")
			)
			(fill
				(thermal_gap 0.5)
				(thermal_bridge_width 0.5)
				(island_removal_mode 0)
			)
			(polygon
				(pts
					(xy 119.6848 -24.2062) (xy 119.8372 -24.2062) (xy 119.8372 -24.8158) (xy 119.6848 -24.8158)
				)
			)
		)
		(zone
			(layer "F.Cu")
			(hatch none 0.5)
			(connect_pads
				(clearance 0)
			)
			(min_thickness 0.25)
			(keepout
				(tracks allowed)
				(vias not_allowed)
				(pads allowed)
				(copperpour not_allowed)
				(footprints allowed)
			)
			(placement
				(enabled no)
				(sheetname "")
			)
			(fill
				(thermal_gap 0.5)
				(thermal_bridge_width 0.5)
				(island_removal_mode 0)
			)
			(polygon
				(pts
					(xy 119.6848 -24.2062) (xy 119.8372 -24.2062) (xy 119.8372 -24.8158) (xy 119.6848 -24.8158)
				)
			)
		)
	)
	(footprint ""
		(layer "F.Cu")
		(at 12.192 -52.578 90)
		(property "Reference" "R372"
			(at -0.508 -3.13563 90)
			(unlocked yes)
			(layer "F.SilkS")
			(effects
				(font
					(size 0.7874 0.5842)
					(thickness 0.1524)
				)
			)
		)
		(property "Value" "VAL*"
			(at 0.02032 2.13233 90)
			(unlocked yes)
			(layer "F.Fab")
			(hide yes)
			(effects
				(font
					(size 0.7874 0.5842)
					(thickness 0.1524)
				)
			)
		)
		(property "Tolerance" "TOL*"
			(at 0.044704 3.05435 90)
			(unlocked yes)
			(layer "Cmts.User")
			(hide yes)
			(effects
				(font
					(size 0.7874 0.5842)
					(thickness 0.1524)
				)
			)
		)
		(property "User Part Number" "PARTNUM*"
			(at 0.02032 4.024884 90)
			(unlocked yes)
			(layer "Cmts.User")
			(hide yes)
			(effects
				(font
					(size 0.7874 0.5842)
					(thickness 0.1524)
				)
			)
		)
		(property "Device Type" "RESISTOR-G155-149R9-01,49.9OHMA"
			(at 0.008382 1.210564 90)
			(unlocked yes)
			(layer "F.Fab")
			(hide yes)
			(effects
				(font
					(size 0.7874 0.5842)
					(thickness 0.1524)
				)
			)
		)
		(duplicate_pad_numbers_are_jumpers no)
		(fp_line
			(start 1.143 -0.5588)
			(end -1.143 -0.5588)
			(stroke
				(width 0.1)
				(type default)
			)
			(layer "F.SilkS")
		)
		(fp_line
			(start -1.143 -0.5588)
			(end -1.143 0.5588)
			(stroke
				(width 0.1)
				(type default)
			)
			(layer "F.SilkS")
		)
		(fp_line
			(start 1.143 0.5588)
			(end 1.143 -0.5588)
			(stroke
				(width 0.1)
				(type default)
			)
			(layer "F.SilkS")
		)
		(fp_line
			(start -1.143 0.5588)
			(end 1.143 0.5588)
			(stroke
				(width 0.1)
				(type default)
			)
			(layer "F.SilkS")
		)
		(fp_poly
			(pts
				(xy -1.143 0.5588) (xy 1.143 0.5588) (xy 1.143 -0.5588) (xy -1.143 -0.5588)
			)
			(stroke
				(width 0)
				(type default)
			)
			(fill no)
			(layer "F.CrtYd")
		)
		(fp_line
			(start 0.508 -0.3048)
			(end -0.508 -0.3048)
			(stroke
				(width 0.1)
				(type default)
			)
			(layer "F.Fab")
		)
		(fp_line
			(start -0.508 -0.3048)
			(end -0.508 0.3048)
			(stroke
				(width 0.1)
				(type default)
			)
			(layer "F.Fab")
		)
		(fp_line
			(start 0.508 0.3048)
			(end 0.508 -0.3048)
			(stroke
				(width 0.1)
				(type default)
			)
			(layer "F.Fab")
		)
		(fp_line
			(start -0.508 0.3048)
			(end 0.508 0.3048)
			(stroke
				(width 0.1)
				(type default)
			)
			(layer "F.Fab")
		)
		(pad "1" smd rect
			(at -0.5334 0 90)
			(size 0.7112 0.6096)
			(layers "F.Cu" "F.Mask" "F.Paste")
			(net "BF_ANT2_IN")
		)
		(pad "2" smd rect
			(at 0.5334 0 90)
			(size 0.7112 0.6096)
			(layers "F.Cu" "F.Mask" "F.Paste")
			(net "ANT2_IN")
		)
		(zone
			(layer "F.Cu")
			(hatch none 0.5)
			(connect_pads
				(clearance 0)
			)
			(min_thickness 0.25)
			(keepout
				(tracks allowed)
				(vias not_allowed)
				(pads allowed)
				(copperpour not_allowed)
				(footprints allowed)
			)
			(placement
				(enabled no)
				(sheetname "")
			)
			(fill
				(thermal_gap 0.5)
				(thermal_bridge_width 0.5)
				(island_removal_mode 0)
			)
			(polygon
				(pts
					(xy 12.4968 -52.5018) (xy 12.4968 -52.6542) (xy 11.8872 -52.6542) (xy 11.8872 -52.5018)
				)
			)
		)
		(zone
			(layer "F.Cu")
			(hatch none 0.5)
			(connect_pads
				(clearance 0)
			)
			(min_thickness 0.25)
			(keepout
				(tracks not_allowed)
				(vias allowed)
				(pads allowed)
				(copperpour not_allowed)
				(footprints allowed)
			)
			(placement
				(enabled no)
				(sheetname "")
			)
			(fill
				(thermal_gap 0.5)
				(thermal_bridge_width 0.5)
				(island_removal_mode 0)
			)
			(polygon
				(pts
					(xy 12.4968 -52.5018) (xy 12.4968 -52.6542) (xy 11.8872 -52.6542) (xy 11.8872 -52.5018)
				)
			)
		)
	)
	(footprint ""
		(layer "F.Cu")
		(at 141.097 -59.563 90)
		(property "Reference" "C256"
			(at 3.048 -1.73863 90)
			(unlocked yes)
			(layer "F.SilkS")
			(effects
				(font
					(size 0.7874 0.5842)
					(thickness 0.1524)
				)
			)
		)
		(property "Value" "VAL*"
			(at 0.0762 2.067306 90)
			(unlocked yes)
			(layer "F.Fab")
			(hide yes)
			(effects
				(font
					(size 0.7874 0.5842)
					(thickness 0.1524)
				)
			)
		)
		(property "Device Type" "CAPACITOR-G105-0B104-CK,0.1UF,A"
			(at 0.0508 1.127506 90)
			(unlocked yes)
			(layer "F.Fab")
			(hide yes)
			(effects
				(font
					(size 0.7874 0.5842)
					(thickness 0.1524)
				)
			)
		)
		(property "User Part Number" "PARTNUM*"
			(at 0.1016 4.023106 90)
			(unlocked yes)
			(layer "Cmts.User")
			(hide yes)
			(effects
				(font
					(size 0.7874 0.5842)
					(thickness 0.1524)
				)
			)
		)
		(property "Tolerance" "TOL*"
			(at 0.0762 3.032506 90)
			(unlocked yes)
			(layer "Cmts.User")
			(hide yes)
			(effects
				(font
					(size 0.7874 0.5842)
					(thickness 0.1524)
				)
			)
		)
		(duplicate_pad_numbers_are_jumpers no)
		(fp_line
			(start 1.143 -0.5588)
			(end -1.143 -0.5588)
			(stroke
				(width 0.1)
				(type default)
			)
			(layer "F.SilkS")
		)
		(fp_line
			(start -1.143 -0.5588)
			(end -1.143 0.5588)
			(stroke
				(width 0.1)
				(type default)
			)
			(layer "F.SilkS")
		)
		(fp_line
			(start 1.143 0.5588)
			(end 1.143 -0.5588)
			(stroke
				(width 0.1)
				(type default)
			)
			(layer "F.SilkS")
		)
		(fp_line
			(start -1.143 0.5588)
			(end 1.143 0.5588)
			(stroke
				(width 0.1)
				(type default)
			)
			(layer "F.SilkS")
		)
		(fp_rect
			(start -1.143 -0.5588)
			(end 1.143 0.5588)
			(stroke
				(width 0)
				(type default)
			)
			(fill no)
			(layer "F.CrtYd")
		)
		(fp_line
			(start 0.508 -0.3048)
			(end -0.508 -0.3048)
			(stroke
				(width 0.1)
				(type default)
			)
			(layer "F.Fab")
		)
		(fp_line
			(start -0.508 -0.3048)
			(end -0.508 0.3048)
			(stroke
				(width 0.1)
				(type default)
			)
			(layer "F.Fab")
		)
		(fp_line
			(start 0.508 0.3048)
			(end 0.508 -0.3048)
			(stroke
				(width 0.1)
				(type default)
			)
			(layer "F.Fab")
		)
		(fp_line
			(start -0.508 0.3048)
			(end 0.508 0.3048)
			(stroke
				(width 0.1)
				(type default)
			)
			(layer "F.Fab")
		)
		(pad "1" smd rect
			(at -0.5334 0 90)
			(size 0.7112 0.6096)
			(layers "F.Cu" "F.Mask" "F.Paste")
			(net "UNNAMED_523_CAPACITOR_I7_1")
		)
		(pad "2" smd rect
			(at 0.5334 0 90)
			(size 0.7112 0.6096)
			(layers "F.Cu" "F.Mask" "F.Paste")
			(net "SG")
		)
		(zone
			(layer "F.Cu")
			(hatch none 0.5)
			(connect_pads
				(clearance 0)
			)
			(min_thickness 0.25)
			(keepout
				(tracks allowed)
				(vias not_allowed)
				(pads allowed)
				(copperpour not_allowed)
				(footprints allowed)
			)
			(placement
				(enabled no)
				(sheetname "")
			)
			(fill
				(thermal_gap 0.5)
				(thermal_bridge_width 0.5)
				(island_removal_mode 0)
			)
			(polygon
				(pts
					(xy 140.7922 -59.4868) (xy 141.4018 -59.4868) (xy 141.4018 -59.6392) (xy 140.7922 -59.6392)
				)
			)
		)
	)
	(footprint ""
		(layer "F.Cu")
		(at 9.652 -81.534 90)
		(property "Reference" "R426"
			(at -2.667 -0.08763 90)
			(unlocked yes)
			(layer "F.SilkS")
			(effects
				(font
					(size 0.7874 0.5842)
					(thickness 0.1524)
				)
			)
		)
		(property "Value" "VAL*"
			(at 0.02032 2.13233 90)
			(unlocked yes)
			(layer "F.Fab")
			(hide yes)
			(effects
				(font
					(size 0.7874 0.5842)
					(thickness 0.1524)
				)
			)
		)
		(property "Device Type" "RESISTOR-G155-11000-01,100OHM,A"
			(at 0.008382 1.210564 90)
			(unlocked yes)
			(layer "F.Fab")
			(hide yes)
			(effects
				(font
					(size 0.7874 0.5842)
					(thickness 0.1524)
				)
			)
		)
		(property "User Part Number" "PARTNUM*"
			(at 0.02032 4.024884 90)
			(unlocked yes)
			(layer "Cmts.User")
			(hide yes)
			(effects
				(font
					(size 0.7874 0.5842)
					(thickness 0.1524)
				)
			)
		)
		(property "Tolerance" "TOL*"
			(at 0.044704 3.05435 90)
			(unlocked yes)
			(layer "Cmts.User")
			(hide yes)
			(effects
				(font
					(size 0.7874 0.5842)
					(thickness 0.1524)
				)
			)
		)
		(duplicate_pad_numbers_are_jumpers no)
		(fp_line
			(start 1.143 -0.5588)
			(end -1.143 -0.5588)
			(stroke
				(width 0.1)
				(type default)
			)
			(layer "F.SilkS")
		)
		(fp_line
			(start -1.143 -0.5588)
			(end -1.143 0.5588)
			(stroke
				(width 0.1)
				(type default)
			)
			(layer "F.SilkS")
		)
		(fp_line
			(start 1.143 0.5588)
			(end 1.143 -0.5588)
			(stroke
				(width 0.1)
				(type default)
			)
			(layer "F.SilkS")
		)
		(fp_line
			(start -1.143 0.5588)
			(end 1.143 0.5588)
			(stroke
				(width 0.1)
				(type default)
			)
			(layer "F.SilkS")
		)
		(fp_poly
			(pts
				(xy -1.143 0.5588) (xy 1.143 0.5588) (xy 1.143 -0.5588) (xy -1.143 -0.5588)
			)
			(stroke
				(width 0)
				(type default)
			)
			(fill no)
			(layer "F.CrtYd")
		)
		(fp_line
			(start 0.508 -0.3048)
			(end -0.508 -0.3048)
			(stroke
				(width 0.1)
				(type default)
			)
			(layer "F.Fab")
		)
		(fp_line
			(start -0.508 -0.3048)
			(end -0.508 0.3048)
			(stroke
				(width 0.1)
				(type default)
			)
			(layer "F.Fab")
		)
		(fp_line
			(start 0.508 0.3048)
			(end 0.508 -0.3048)
			(stroke
				(width 0.1)
				(type default)
			)
			(layer "F.Fab")
		)
		(fp_line
			(start -0.508 0.3048)
			(end 0.508 0.3048)
			(stroke
				(width 0.1)
				(type default)
			)
			(layer "F.Fab")
		)
		(pad "1" smd rect
			(at -0.5334 0 90)
			(size 0.7112 0.6096)
			(layers "F.Cu" "F.Mask" "F.Paste")
			(net "FPGA_OUT_GPS_LED_GREEN_N")
		)
		(pad "2" smd rect
			(at 0.5334 0 90)
			(size 0.7112 0.6096)
			(layers "F.Cu" "F.Mask" "F.Paste")
			(net "UNNAMED_14_LED4PV14_I269_4")
		)
		(zone
			(layer "F.Cu")
			(hatch none 0.5)
			(connect_pads
				(clearance 0)
			)
			(min_thickness 0.25)
			(keepout
				(tracks allowed)
				(vias not_allowed)
				(pads allowed)
				(copperpour not_allowed)
				(footprints allowed)
			)
			(placement
				(enabled no)
				(sheetname "")
			)
			(fill
				(thermal_gap 0.5)
				(thermal_bridge_width 0.5)
				(island_removal_mode 0)
			)
			(polygon
				(pts
					(xy 9.9568 -81.4578) (xy 9.9568 -81.6102) (xy 9.3472 -81.6102) (xy 9.3472 -81.4578)
				)
			)
		)
		(zone
			(layer "F.Cu")
			(hatch none 0.5)
			(connect_pads
				(clearance 0)
			)
			(min_thickness 0.25)
			(keepout
				(tracks not_allowed)
				(vias allowed)
				(pads allowed)
				(copperpour not_allowed)
				(footprints allowed)
			)
			(placement
				(enabled no)
				(sheetname "")
			)
			(fill
				(thermal_gap 0.5)
				(thermal_bridge_width 0.5)
				(island_removal_mode 0)
			)
			(polygon
				(pts
					(xy 9.9568 -81.4578) (xy 9.9568 -81.6102) (xy 9.3472 -81.6102) (xy 9.3472 -81.4578)
				)
			)
		)
	)
	(footprint ""
		(layer "F.Cu")
		(at 137.795 -17.526)
		(property "Reference" "R231"
			(at -1.397 1.56337 0)
			(unlocked yes)
			(layer "F.SilkS")
			(effects
				(font
					(size 0.7874 0.5842)
					(thickness 0.1524)
				)
			)
		)
		(property "Value" "VAL*"
			(at 0.0508 2.245106 0)
			(unlocked yes)
			(layer "F.Fab")
			(hide yes)
			(effects
				(font
					(size 0.7874 0.5842)
					(thickness 0.1524)
				)
			)
		)
		(property "Tolerance" "TOL*"
			(at 0.0508 3.261106 0)
			(unlocked yes)
			(layer "Cmts.User")
			(hide yes)
			(effects
				(font
					(size 0.7874 0.5842)
					(thickness 0.1524)
				)
			)
		)
		(property "Device Type" "RESISTOR-G155-04221-01,4.22KOHA"
			(at 0.0762 1.254506 0)
			(unlocked yes)
			(layer "F.Fab")
			(hide yes)
			(effects
				(font
					(size 0.7874 0.5842)
					(thickness 0.1524)
				)
			)
		)
		(property "User Part Number" "PARTNUM*"
			(at 0.0762 4.302506 0)
			(unlocked yes)
			(layer "Cmts.User")
			(hide yes)
			(effects
				(font
					(size 0.7874 0.5842)
					(thickness 0.1524)
				)
			)
		)
		(duplicate_pad_numbers_are_jumpers no)
		(fp_line
			(start -1.143 -0.5588)
			(end -1.143 0.5588)
			(stroke
				(width 0.1)
				(type default)
			)
			(layer "F.SilkS")
		)
		(fp_line
			(start -1.143 0.5588)
			(end 1.143 0.5588)
			(stroke
				(width 0.1)
				(type default)
			)
			(layer "F.SilkS")
		)
		(fp_line
			(start 1.143 -0.5588)
			(end -1.143 -0.5588)
			(stroke
				(width 0.1)
				(type default)
			)
			(layer "F.SilkS")
		)
		(fp_line
			(start 1.143 0.5588)
			(end 1.143 -0.5588)
			(stroke
				(width 0.1)
				(type default)
			)
			(layer "F.SilkS")
		)
		(fp_rect
			(start -1.143 -0.5588)
			(end 1.143 0.5588)
			(stroke
				(width 0)
				(type default)
			)
			(fill no)
			(layer "F.CrtYd")
		)
		(fp_line
			(start -0.508 -0.3048)
			(end -0.508 0.3048)
			(stroke
				(width 0.1)
				(type default)
			)
			(layer "F.Fab")
		)
		(fp_line
			(start -0.508 0.3048)
			(end 0.508 0.3048)
			(stroke
				(width 0.1)
				(type default)
			)
			(layer "F.Fab")
		)
		(fp_line
			(start 0.508 -0.3048)
			(end -0.508 -0.3048)
			(stroke
				(width 0.1)
				(type default)
			)
			(layer "F.Fab")
		)
		(fp_line
			(start 0.508 0.3048)
			(end 0.508 -0.3048)
			(stroke
				(width 0.1)
				(type default)
			)
			(layer "F.Fab")
		)
		(pad "1" smd rect
			(at -0.5334 0)
			(size 0.7112 0.6096)
			(layers "F.Cu" "F.Mask" "F.Paste")
			(net "XP2R5V_FPGA")
		)
		(pad "2" smd rect
			(at 0.5334 0)
			(size 0.7112 0.6096)
			(layers "F.Cu" "F.Mask" "F.Paste")
			(net "UNNAMED_515_ISL80101IRAJZDFN10_")
		)
		(zone
			(layer "F.Cu")
			(hatch none 0.5)
			(connect_pads
				(clearance 0)
			)
			(min_thickness 0.25)
			(keepout
				(tracks allowed)
				(vias not_allowed)
				(pads allowed)
				(copperpour not_allowed)
				(footprints allowed)
			)
			(placement
				(enabled no)
				(sheetname "")
			)
			(fill
				(thermal_gap 0.5)
				(thermal_bridge_width 0.5)
				(island_removal_mode 0)
			)
			(polygon
				(pts
					(xy 137.7188 -17.8308) (xy 137.7188 -17.2212) (xy 137.8712 -17.2212) (xy 137.8712 -17.8308)
				)
			)
		)
	)
	(footprint ""
		(layer "F.Cu")
		(at 119.761 -23.241)
		(property "Reference" "R486"
			(at -2.794 0.54737 0)
			(unlocked yes)
			(layer "F.SilkS")
			(effects
				(font
					(size 0.7874 0.5842)
					(thickness 0.1524)
				)
			)
		)
		(property "Value" "VAL*"
			(at 0.02032 2.13233 0)
			(unlocked yes)
			(layer "F.Fab")
			(hide yes)
			(effects
				(font
					(size 0.7874 0.5842)
					(thickness 0.1524)
				)
			)
		)
		(property "Tolerance" "TOL*"
			(at 0.044704 3.05435 0)
			(unlocked yes)
			(layer "Cmts.User")
			(hide yes)
			(effects
				(font
					(size 0.7874 0.5842)
					(thickness 0.1524)
				)
			)
		)
		(property "User Part Number" "PARTNUM*"
			(at 0.02032 4.024884 0)
			(unlocked yes)
			(layer "Cmts.User")
			(hide yes)
			(effects
				(font
					(size 0.7874 0.5842)
					(thickness 0.1524)
				)
			)
		)
		(property "Device Type" "RESISTOR-G155-133R0-01,33OHM,1%"
			(at 0.008382 1.210564 0)
			(unlocked yes)
			(layer "F.Fab")
			(hide yes)
			(effects
				(font
					(size 0.7874 0.5842)
					(thickness 0.1524)
				)
			)
		)
		(duplicate_pad_numbers_are_jumpers no)
		(fp_line
			(start -1.143 -0.5588)
			(end -1.143 0.5588)
			(stroke
				(width 0.1)
				(type default)
			)
			(layer "F.SilkS")
		)
		(fp_line
			(start -1.143 0.5588)
			(end 1.143 0.5588)
			(stroke
				(width 0.1)
				(type default)
			)
			(layer "F.SilkS")
		)
		(fp_line
			(start 1.143 -0.5588)
			(end -1.143 -0.5588)
			(stroke
				(width 0.1)
				(type default)
			)
			(layer "F.SilkS")
		)
		(fp_line
			(start 1.143 0.5588)
			(end 1.143 -0.5588)
			(stroke
				(width 0.1)
				(type default)
			)
			(layer "F.SilkS")
		)
		(fp_poly
			(pts
				(xy -1.143 0.5588) (xy 1.143 0.5588) (xy 1.143 -0.5588) (xy -1.143 -0.5588)
			)
			(stroke
				(width 0)
				(type default)
			)
			(fill no)
			(layer "F.CrtYd")
		)
		(fp_line
			(start -0.508 -0.3048)
			(end -0.508 0.3048)
			(stroke
				(width 0.1)
				(type default)
			)
			(layer "F.Fab")
		)
		(fp_line
			(start -0.508 0.3048)
			(end 0.508 0.3048)
			(stroke
				(width 0.1)
				(type default)
			)
			(layer "F.Fab")
		)
		(fp_line
			(start 0.508 -0.3048)
			(end -0.508 -0.3048)
			(stroke
				(width 0.1)
				(type default)
			)
			(layer "F.Fab")
		)
		(fp_line
			(start 0.508 0.3048)
			(end 0.508 -0.3048)
			(stroke
				(width 0.1)
				(type default)
			)
			(layer "F.Fab")
		)
		(pad "1" smd rect
			(at -0.5334 0)
			(size 0.7112 0.6096)
			(layers "F.Cu" "F.Mask" "F.Paste")
			(net "FT4232_MUX3_SEL")
		)
		(pad "2" smd rect
			(at 0.5334 0)
			(size 0.7112 0.6096)
			(layers "F.Cu" "F.Mask" "F.Paste")
			(net "MUX3_SEL")
		)
		(zone
			(layer "F.Cu")
			(hatch none 0.5)
			(connect_pads
				(clearance 0)
			)
			(min_thickness 0.25)
			(keepout
				(tracks allowed)
				(vias not_allowed)
				(pads allowed)
				(copperpour not_allowed)
				(footprints allowed)
			)
			(placement
				(enabled no)
				(sheetname "")
			)
			(fill
				(thermal_gap 0.5)
				(thermal_bridge_width 0.5)
				(island_removal_mode 0)
			)
			(polygon
				(pts
					(xy 119.6848 -22.9362) (xy 119.8372 -22.9362) (xy 119.8372 -23.5458) (xy 119.6848 -23.5458)
				)
			)
		)
		(zone
			(layer "F.Cu")
			(hatch none 0.5)
			(connect_pads
				(clearance 0)
			)
			(min_thickness 0.25)
			(keepout
				(tracks not_allowed)
				(vias allowed)
				(pads allowed)
				(copperpour not_allowed)
				(footprints allowed)
			)
			(placement
				(enabled no)
				(sheetname "")
			)
			(fill
				(thermal_gap 0.5)
				(thermal_bridge_width 0.5)
				(island_removal_mode 0)
			)
			(polygon
				(pts
					(xy 119.6848 -22.9362) (xy 119.8372 -22.9362) (xy 119.8372 -23.5458) (xy 119.6848 -23.5458)
				)
			)
		)
	)
	(footprint ""
		(layer "F.Cu")
		(at 89.8652 -100.2538)
		(property "Reference" "C55"
			(at 1.905 0.16637 0)
			(unlocked yes)
			(layer "F.SilkS")
			(effects
				(font
					(size 0.7874 0.5842)
					(thickness 0.1524)
				)
			)
		)
		(property "Value" "VAL*"
			(at 0.193548 2.13614 0)
			(unlocked yes)
			(layer "F.Fab")
			(hide yes)
			(effects
				(font
					(size 0.7874 0.5842)
					(thickness 0.1524)
				)
			)
		)
		(property "User Part Number" "PARTNUM*"
			(at 0.216154 4.185666 0)
			(unlocked yes)
			(layer "Cmts.User")
			(hide yes)
			(effects
				(font
					(size 0.7874 0.5842)
					(thickness 0.1524)
				)
			)
		)
		(property "Device Type" "CAPACITOR-G104-0A180-FJ,18PF,5%"
			(at 0.184404 1.180592 0)
			(unlocked yes)
			(layer "F.Fab")
			(hide yes)
			(effects
				(font
					(size 0.7874 0.5842)
					(thickness 0.1524)
				)
			)
		)
		(property "Tolerance" "TOL*"
			(at 0.216154 3.1496 0)
			(unlocked yes)
			(layer "Cmts.User")
			(hide yes)
			(effects
				(font
					(size 0.7874 0.5842)
					(thickness 0.1524)
				)
			)
		)
		(duplicate_pad_numbers_are_jumpers no)
		(fp_line
			(start -0.671322 -0.4445)
			(end 0.671322 -0.4445)
			(stroke
				(width 0.1)
				(type default)
			)
			(layer "F.SilkS")
		)
		(fp_line
			(start -0.671322 0.4445)
			(end -0.671322 -0.4445)
			(stroke
				(width 0.1)
				(type default)
			)
			(layer "F.SilkS")
		)
		(fp_line
			(start 0.671322 -0.4445)
			(end 0.671322 0.4445)
			(stroke
				(width 0.1)
				(type default)
			)
			(layer "F.SilkS")
		)
		(fp_line
			(start 0.671322 0.4445)
			(end -0.671322 0.4445)
			(stroke
				(width 0.1)
				(type default)
			)
			(layer "F.SilkS")
		)
		(fp_rect
			(start -0.671322 0.4445)
			(end 0.671322 -0.4445)
			(stroke
				(width 0)
				(type default)
			)
			(fill no)
			(layer "F.CrtYd")
		)
		(fp_line
			(start -0.31496 -0.1651)
			(end -0.31496 0.1651)
			(stroke
				(width 0.1)
				(type default)
			)
			(layer "F.Fab")
		)
		(fp_line
			(start -0.31496 0.1651)
			(end 0.31496 0.1651)
			(stroke
				(width 0.1)
				(type default)
			)
			(layer "F.Fab")
		)
		(fp_line
			(start 0.31496 -0.1651)
			(end -0.31496 -0.1651)
			(stroke
				(width 0.1)
				(type default)
			)
			(layer "F.Fab")
		)
		(fp_line
			(start 0.31496 0.1651)
			(end 0.31496 -0.1651)
			(stroke
				(width 0.1)
				(type default)
			)
			(layer "F.Fab")
		)
		(pad "1" smd rect
			(at -0.264922 0)
			(size 0.3048 0.381)
			(layers "F.Cu" "F.Mask" "F.Paste")
			(net "XP3R3V_COMP")
		)
		(pad "2" smd rect
			(at 0.264922 0)
			(size 0.3048 0.381)
			(layers "F.Cu" "F.Mask" "F.Paste")
			(net "XP3R3V_AGND")
		)
		(zone
			(layer "F.Cu")
			(hatch none 0.5)
			(connect_pads
				(clearance 0)
			)
			(min_thickness 0.25)
			(keepout
				(tracks allowed)
				(vias not_allowed)
				(pads allowed)
				(copperpour not_allowed)
				(footprints allowed)
			)
			(placement
				(enabled no)
				(sheetname "")
			)
			(fill
				(thermal_gap 0.5)
				(thermal_bridge_width 0.5)
				(island_removal_mode 0)
			)
			(polygon
				(pts
					(xy 89.752678 -100.0633) (xy 89.977722 -100.0633) (xy 89.977722 -100.4443) (xy 89.752678 -100.4443)
				)
			)
		)
	)
	(footprint ""
		(layer "F.Cu")
		(at 125.349 -89.535 90)
		(property "Reference" "R268"
			(at -3.429 0.03937 90)
			(unlocked yes)
			(layer "F.SilkS")
			(effects
				(font
					(size 0.7874 0.5842)
					(thickness 0.1524)
				)
			)
		)
		(property "Value" "VAL*"
			(at 0.02032 2.13233 90)
			(unlocked yes)
			(layer "F.Fab")
			(hide yes)
			(effects
				(font
					(size 0.7874 0.5842)
					(thickness 0.1524)
				)
			)
		)
		(property "Device Type" "RESISTOR-G155-11003-01,100KOHMA"
			(at 0.008382 1.210564 90)
			(unlocked yes)
			(layer "F.Fab")
			(hide yes)
			(effects
				(font
					(size 0.7874 0.5842)
					(thickness 0.1524)
				)
			)
		)
		(property "User Part Number" "PARTNUM*"
			(at 0.02032 4.024884 90)
			(unlocked yes)
			(layer "Cmts.User")
			(hide yes)
			(effects
				(font
					(size 0.7874 0.5842)
					(thickness 0.1524)
				)
			)
		)
		(property "Tolerance" "TOL*"
			(at 0.044704 3.05435 90)
			(unlocked yes)
			(layer "Cmts.User")
			(hide yes)
			(effects
				(font
					(size 0.7874 0.5842)
					(thickness 0.1524)
				)
			)
		)
		(duplicate_pad_numbers_are_jumpers no)
		(fp_line
			(start 1.143 -0.5588)
			(end -1.143 -0.5588)
			(stroke
				(width 0.1)
				(type default)
			)
			(layer "F.SilkS")
		)
		(fp_line
			(start -1.143 -0.5588)
			(end -1.143 0.5588)
			(stroke
				(width 0.1)
				(type default)
			)
			(layer "F.SilkS")
		)
		(fp_line
			(start 1.143 0.5588)
			(end 1.143 -0.5588)
			(stroke
				(width 0.1)
				(type default)
			)
			(layer "F.SilkS")
		)
		(fp_line
			(start -1.143 0.5588)
			(end 1.143 0.5588)
			(stroke
				(width 0.1)
				(type default)
			)
			(layer "F.SilkS")
		)
		(fp_rect
			(start 1.143 -0.5588)
			(end -1.143 0.5588)
			(stroke
				(width 0)
				(type default)
			)
			(fill no)
			(layer "F.CrtYd")
		)
		(fp_line
			(start 0.508 -0.3048)
			(end -0.508 -0.3048)
			(stroke
				(width 0.1)
				(type default)
			)
			(layer "F.Fab")
		)
		(fp_line
			(start -0.508 -0.3048)
			(end -0.508 0.3048)
			(stroke
				(width 0.1)
				(type default)
			)
			(layer "F.Fab")
		)
		(fp_line
			(start 0.508 0.3048)
			(end 0.508 -0.3048)
			(stroke
				(width 0.1)
				(type default)
			)
			(layer "F.Fab")
		)
		(fp_line
			(start -0.508 0.3048)
			(end 0.508 0.3048)
			(stroke
				(width 0.1)
				(type default)
			)
			(layer "F.Fab")
		)
		(pad "1" smd rect
			(at -0.5334 0 90)
			(size 0.7112 0.6096)
			(layers "F.Cu" "F.Mask" "F.Paste")
			(net "XP3R3V_FPGA")
		)
		(pad "2" smd rect
			(at 0.5334 0 90)
			(size 0.7112 0.6096)
			(layers "F.Cu" "F.Mask" "F.Paste")
			(net "GPS_UART_RXD")
		)
		(zone
			(layer "F.Cu")
			(hatch none 0.5)
			(connect_pads
				(clearance 0)
			)
			(min_thickness 0.25)
			(keepout
				(tracks allowed)
				(vias not_allowed)
				(pads allowed)
				(copperpour not_allowed)
				(footprints allowed)
			)
			(placement
				(enabled no)
				(sheetname "")
			)
			(fill
				(thermal_gap 0.5)
				(thermal_bridge_width 0.5)
				(island_removal_mode 0)
			)
			(polygon
				(pts
					(xy 125.0442 -89.6112) (xy 125.0442 -89.4588) (xy 125.6538 -89.4588) (xy 125.6538 -89.6112)
				)
			)
		)
		(zone
			(layer "F.Cu")
			(hatch none 0.5)
			(connect_pads
				(clearance 0)
			)
			(min_thickness 0.25)
			(keepout
				(tracks not_allowed)
				(vias allowed)
				(pads allowed)
				(copperpour not_allowed)
				(footprints allowed)
			)
			(placement
				(enabled no)
				(sheetname "")
			)
			(fill
				(thermal_gap 0.5)
				(thermal_bridge_width 0.5)
				(island_removal_mode 0)
			)
			(polygon
				(pts
					(xy 125.0442 -89.6112) (xy 125.0442 -89.4588) (xy 125.6538 -89.4588) (xy 125.6538 -89.6112)
				)
			)
		)
	)
	(footprint ""
		(layer "F.Cu")
		(at 19.812 -83.947)
		(property "Reference" "TP5"
			(at 0 0 0)
			(layer "F.SilkS")
			(hide yes)
			(effects
				(font
					(size 1.27 1.27)
				)
			)
		)
		(property "Value" ""
			(at 0 0 0)
			(layer "F.Fab")
			(effects
				(font
					(size 1.27 1.27)
				)
			)
		)
		(property "Device Type" "TP_PIONT-TP010CT020B030_PTH-TPA"
			(at -1.341882 0.996696 0)
			(unlocked yes)
			(layer "F.Fab")
			(hide yes)
			(effects
				(font
					(size 0.7874 0.5842)
					(thickness 0.1524)
				)
				(justify left)
			)
		)
		(duplicate_pad_numbers_are_jumpers no)
		(fp_poly
			(pts
				(arc
					(start 0.889 0)
					(mid -0.889 0)
					(end 0.889 0)
				)
			)
			(stroke
				(width 0)
				(type default)
			)
			(fill no)
			(layer "B.CrtYd")
		)
		(fp_poly
			(pts
				(arc
					(start 0.889 0)
					(mid -0.889 0)
					(end 0.889 0)
				)
			)
			(stroke
				(width 0)
				(type default)
			)
			(fill no)
			(layer "F.CrtYd")
		)
		(pad "1" thru_hole circle
			(at 0 0)
			(size 0.508 0.508)
			(drill 0.254)
			(layers "*.Cu" "*.Mask")
			(remove_unused_layers no)
			(net "UNNAMED_524_FT4232HLREELQFP64_I")
			(clearance 0.1016)
			(padstack
				(mode front_inner_back)
				(layer "Inner"
					(shape circle)
					(size 0.508 0.508)
					(clearance 0.1016)
				)
				(layer "B.Cu"
					(shape circle)
					(size 0.762 0.762)
					(clearance -0.0254)
				)
			)
		)
	)
	(footprint ""
		(layer "F.Cu")
		(at 108.9406 -80.1624)
		(property "Reference" "U38"
			(at -0.7366 3.49377 0)
			(unlocked yes)
			(layer "F.SilkS")
			(effects
				(font
					(size 0.7874 0.5842)
					(thickness 0.1524)
				)
			)
		)
		(property "Value" ""
			(at 0 0 0)
			(layer "F.Fab")
			(effects
				(font
					(size 1.27 1.27)
				)
			)
		)
		(property "Device Type" "TS3A5018PWR_TSSOP16-G220-10324A"
			(at 0 0.924306 0)
			(unlocked yes)
			(layer "F.Fab")
			(hide yes)
			(effects
				(font
					(size 0.7874 0.5842)
					(thickness 0.000001)
				)
			)
		)
		(property "User Part Number" "PARTNUM*"
			(at 0.254 1.940306 0)
			(unlocked yes)
			(layer "Cmts.User")
			(hide yes)
			(effects
				(font
					(size 0.7874 0.5842)
					(thickness 0.000001)
				)
			)
		)
		(duplicate_pad_numbers_are_jumpers no)
		(fp_line
			(start -4.0767 -2.7559)
			(end 4.0767 -2.7559)
			(stroke
				(width 0.1)
				(type default)
			)
			(layer "F.SilkS")
		)
		(fp_line
			(start -4.0767 2.7559)
			(end -4.0767 -2.7559)
			(stroke
				(width 0.1)
				(type default)
			)
			(layer "F.SilkS")
		)
		(fp_line
			(start 4.0767 -2.7559)
			(end 4.0767 2.7559)
			(stroke
				(width 0.1)
				(type default)
			)
			(layer "F.SilkS")
		)
		(fp_line
			(start 4.0767 2.7559)
			(end -4.0767 2.7559)
			(stroke
				(width 0.1)
				(type default)
			)
			(layer "F.SilkS")
		)
		(fp_poly
			(pts
				(arc
					(start -3.6576 -3.2766)
					(mid -4.4196 -3.2766)
					(end -3.6576 -3.2766)
				)
			)
			(stroke
				(width 0)
				(type default)
			)
			(fill yes)
			(layer "F.SilkS")
		)
		(fp_rect
			(start -4.3307 3.0099)
			(end 4.3307 -3.0099)
			(stroke
				(width 0)
				(type default)
			)
			(fill no)
			(layer "F.CrtYd")
		)
		(fp_line
			(start -2.1971 -2.5019)
			(end 2.1971 -2.5019)
			(stroke
				(width 0.1)
				(type default)
			)
			(layer "F.Fab")
		)
		(fp_line
			(start -2.1971 2.5019)
			(end -2.1971 -2.5019)
			(stroke
				(width 0.1)
				(type default)
			)
			(layer "F.Fab")
		)
		(fp_line
			(start 2.1971 -2.5019)
			(end 2.1971 2.5019)
			(stroke
				(width 0.1)
				(type default)
			)
			(layer "F.Fab")
		)
		(fp_line
			(start 2.1971 2.5019)
			(end -2.1971 2.5019)
			(stroke
				(width 0.1)
				(type default)
			)
			(layer "F.Fab")
		)
		(fp_poly
			(pts
				(arc
					(start -1.114298 -1.942084)
					(mid -1.914398 -1.942084)
					(end -1.114298 -1.942084)
				)
			)
			(stroke
				(width 0)
				(type default)
			)
			(fill yes)
			(layer "F.Fab")
		)
		(fp_text user "8"
			(at -4.572 2.25425 0)
			(unlocked yes)
			(layer "F.SilkS")
			(effects
				(font
					(size 0.635 0.4064)
					(thickness 0.1524)
				)
			)
		)
		(fp_text user "16"
			(at 4.50215 -2.6416 90)
			(unlocked yes)
			(layer "F.SilkS")
			(effects
				(font
					(size 0.635 0.4064)
					(thickness 0.1524)
				)
			)
		)
		(fp_text user "9"
			(at 4.5466 2.38125 0)
			(unlocked yes)
			(layer "F.SilkS")
			(effects
				(font
					(size 0.635 0.4064)
					(thickness 0.1524)
				)
			)
		)
		(fp_text user "8"
			(at -4.572 2.18567 0)
			(unlocked yes)
			(layer "F.Fab")
			(effects
				(font
					(size 0.7874 0.5842)
					(thickness 0.1524)
				)
			)
		)
		(fp_text user "16"
			(at 3.9624 -3.23723 0)
			(unlocked yes)
			(layer "F.Fab")
			(effects
				(font
					(size 0.7874 0.5842)
					(thickness 0.1524)
				)
			)
		)
		(fp_text user "9"
			(at 4.5466 2.31267 0)
			(unlocked yes)
			(layer "F.Fab")
			(effects
				(font
					(size 0.7874 0.5842)
					(thickness 0.1524)
				)
			)
		)
		(pad "1" smd rect
			(at -3.0353 -2.275078 90)
			(size 0.3556 1.5748)
			(layers "F.Cu" "F.Mask" "F.Paste")
			(net "MUX2_SEL")
		)
		(pad "2" smd rect
			(at -3.0353 -1.625092 90)
			(size 0.3556 1.5748)
			(layers "F.Cu" "F.Mask" "F.Paste")
			(net "FPGA_FLASH_CLK")
		)
		(pad "3" smd rect
			(at -3.0353 -0.975106 90)
			(size 0.3556 1.5748)
			(layers "F.Cu" "F.Mask" "F.Paste")
			(net "FT4232_SPI_CLK")
		)
		(pad "4" smd rect
			(at -3.0353 -0.32512 90)
			(size 0.3556 1.5748)
			(layers "F.Cu" "F.Mask" "F.Paste")
			(net "FLASH_CLK")
		)
		(pad "5" smd rect
			(at -3.0353 0.32512 90)
			(size 0.3556 1.5748)
			(layers "F.Cu" "F.Mask" "F.Paste")
			(net "FPGA_FLASH_DQ0_MOSI")
		)
		(pad "6" smd rect
			(at -3.0353 0.975106 90)
			(size 0.3556 1.5748)
			(layers "F.Cu" "F.Mask" "F.Paste")
			(net "FT4232_SPI_MOSI")
		)
		(pad "7" smd rect
			(at -3.0353 1.625092 90)
			(size 0.3556 1.5748)
			(layers "F.Cu" "F.Mask" "F.Paste")
			(net "FLASH_DQ0_MOSI")
		)
		(pad "8" smd rect
			(at -3.0353 2.275078 90)
			(size 0.3556 1.5748)
			(layers "F.Cu" "F.Mask" "F.Paste")
			(net "SG")
		)
		(pad "9" smd rect
			(at 3.0353 2.275078 90)
			(size 0.3556 1.5748)
			(layers "F.Cu" "F.Mask" "F.Paste")
			(net "FLASH_DQ1_MISO")
		)
		(pad "10" smd rect
			(at 3.0353 1.625092 90)
			(size 0.3556 1.5748)
			(layers "F.Cu" "F.Mask" "F.Paste")
			(net "FT4232_SPI_MISO")
		)
		(pad "11" smd rect
			(at 3.0353 0.975106 90)
			(size 0.3556 1.5748)
			(layers "F.Cu" "F.Mask" "F.Paste")
			(net "FPGA_FLASH_DQ1_MISO")
		)
		(pad "12" smd rect
			(at 3.0353 0.32512 90)
			(size 0.3556 1.5748)
			(layers "F.Cu" "F.Mask" "F.Paste")
			(net "FLASH_CS_N")
		)
		(pad "13" smd rect
			(at 3.0353 -0.32512 90)
			(size 0.3556 1.5748)
			(layers "F.Cu" "F.Mask" "F.Paste")
			(net "FT4232_SPI_CS_N")
		)
		(pad "14" smd rect
			(at 3.0353 -0.975106 90)
			(size 0.3556 1.5748)
			(layers "F.Cu" "F.Mask" "F.Paste")
			(net "FPGA_FLASH_CS_N")
		)
		(pad "15" smd rect
			(at 3.0353 -1.625092 90)
			(size 0.3556 1.5748)
			(layers "F.Cu" "F.Mask" "F.Paste")
			(net "UNNAMED_524_RESISTOR_I432_2")
		)
		(pad "16" smd rect
			(at 3.0353 -2.275078 90)
			(size 0.3556 1.5748)
			(layers "F.Cu" "F.Mask" "F.Paste")
			(net "XP3R3V_FPGA")
		)
	)
	(footprint ""
		(layer "F.Cu")
		(at 136.779 -53.086 -90)
		(property "Reference" "C260"
			(at 0 2.75463 90)
			(unlocked yes)
			(layer "F.SilkS")
			(effects
				(font
					(size 0.7874 0.5842)
					(thickness 0.1524)
				)
			)
		)
		(property "Value" "VAL*"
			(at 0.0762 3.134106 270)
			(unlocked yes)
			(layer "F.Fab")
			(hide yes)
			(effects
				(font
					(size 0.7874 0.5842)
					(thickness 0.1524)
				)
			)
		)
		(property "Tolerance" "TOL*"
			(at 0.0762 4.048506 270)
			(unlocked yes)
			(layer "Cmts.User")
			(hide yes)
			(effects
				(font
					(size 0.7874 0.5842)
					(thickness 0.1524)
				)
			)
		)
		(property "User Part Number" "PARTNUM*"
			(at 0.1016 5.013706 270)
			(unlocked yes)
			(layer "Cmts.User")
			(hide yes)
			(effects
				(font
					(size 0.7874 0.5842)
					(thickness 0.1524)
				)
			)
		)
		(property "Device Type" "CAPACITOR-G107-0F106-EM,10UF,2A"
			(at 0.0508 2.194306 270)
			(unlocked yes)
			(layer "F.Fab")
			(hide yes)
			(effects
				(font
					(size 0.7874 0.5842)
					(thickness 0.1524)
				)
			)
		)
		(duplicate_pad_numbers_are_jumpers no)
		(fp_line
			(start -1.5748 0.9398)
			(end 1.5748 0.9398)
			(stroke
				(width 0.1)
				(type default)
			)
			(layer "F.SilkS")
		)
		(fp_line
			(start 1.5748 0.9398)
			(end 1.5748 -0.9398)
			(stroke
				(width 0.1)
				(type default)
			)
			(layer "F.SilkS")
		)
		(fp_line
			(start -1.5748 -0.9398)
			(end -1.5748 0.9398)
			(stroke
				(width 0.1)
				(type default)
			)
			(layer "F.SilkS")
		)
		(fp_line
			(start 1.5748 -0.9398)
			(end -1.5748 -0.9398)
			(stroke
				(width 0.1)
				(type default)
			)
			(layer "F.SilkS")
		)
		(fp_rect
			(start 1.5748 0.9398)
			(end -1.5748 -0.9398)
			(stroke
				(width 0)
				(type default)
			)
			(fill no)
			(layer "F.CrtYd")
		)
		(fp_line
			(start -1.016 0.635)
			(end 1.016 0.635)
			(stroke
				(width 0.1)
				(type default)
			)
			(layer "F.Fab")
		)
		(fp_line
			(start 1.016 0.635)
			(end 1.016 -0.635)
			(stroke
				(width 0.1)
				(type default)
			)
			(layer "F.Fab")
		)
		(fp_line
			(start -1.016 -0.635)
			(end -1.016 0.635)
			(stroke
				(width 0.1)
				(type default)
			)
			(layer "F.Fab")
		)
		(fp_line
			(start 1.016 -0.635)
			(end -1.016 -0.635)
			(stroke
				(width 0.1)
				(type default)
			)
			(layer "F.Fab")
		)
		(pad "1" smd rect
			(at -0.8382 0 270)
			(size 0.9652 1.3716)
			(layers "F.Cu" "F.Mask" "F.Paste")
			(net "VIN_XP1R0V")
		)
		(pad "2" smd rect
			(at 0.8382 0 270)
			(size 0.9652 1.3716)
			(layers "F.Cu" "F.Mask" "F.Paste")
			(net "SG")
		)
		(zone
			(layer "F.Cu")
			(hatch none 0.5)
			(connect_pads
				(clearance 0)
			)
			(min_thickness 0.25)
			(keepout
				(tracks allowed)
				(vias not_allowed)
				(pads allowed)
				(copperpour not_allowed)
				(footprints allowed)
			)
			(placement
				(enabled no)
				(sheetname "")
			)
			(fill
				(thermal_gap 0.5)
				(thermal_bridge_width 0.5)
				(island_removal_mode 0)
			)
			(polygon
				(pts
					(xy 136.144 -52.8574) (xy 137.414 -52.8574) (xy 137.414 -53.3146) (xy 136.144 -53.3146)
				)
			)
		)
	)
	(footprint ""
		(layer "F.Cu")
		(at 127.762 -39.37 -90)
		(property "Reference" "TP134"
			(at 0.8128 -1.04775 90)
			(unlocked yes)
			(layer "F.SilkS")
			(effects
				(font
					(size 0.635 0.4064)
					(thickness 0.1524)
				)
				(justify left)
			)
		)
		(property "Value" ""
			(at 0 0 270)
			(layer "F.Fab")
			(effects
				(font
					(size 1.27 1.27)
				)
			)
		)
		(property "Device Type" "TP_PIONT-TP010CT020B030_PTH-TPA"
			(at -1.341882 0.996696 270)
			(unlocked yes)
			(layer "F.Fab")
			(hide yes)
			(effects
				(font
					(size 0.7874 0.5842)
					(thickness 0.1524)
				)
				(justify left)
			)
		)
		(duplicate_pad_numbers_are_jumpers no)
		(fp_poly
			(pts
				(arc
					(start 0 -0.889)
					(mid 0 0.889)
					(end 0 -0.889)
				)
			)
			(stroke
				(width 0)
				(type default)
			)
			(fill no)
			(layer "B.CrtYd")
		)
		(fp_poly
			(pts
				(arc
					(start 0 -0.889)
					(mid 0 0.889)
					(end 0 -0.889)
				)
			)
			(stroke
				(width 0)
				(type default)
			)
			(fill no)
			(layer "F.CrtYd")
		)
		(pad "1" thru_hole circle
			(at 0 0 270)
			(size 0.508 0.508)
			(drill 0.254)
			(layers "*.Cu" "*.Mask")
			(remove_unused_layers no)
			(net "IO_L21P_34")
			(clearance 0.1016)
			(padstack
				(mode front_inner_back)
				(layer "Inner"
					(shape circle)
					(size 0.508 0.508)
					(clearance 0.1016)
				)
				(layer "B.Cu"
					(shape circle)
					(size 0.762 0.762)
					(clearance -0.0254)
				)
			)
		)
	)
	(footprint ""
		(layer "F.Cu")
		(at 150.343108 -49.01311 90)
		(property "Reference" "R66"
			(at 0.00889 -3.237738 90)
			(unlocked yes)
			(layer "F.SilkS")
			(effects
				(font
					(size 0.7874 0.5842)
					(thickness 0.1524)
				)
			)
		)
		(property "Value" "VAL*"
			(at 0.02032 2.13233 90)
			(unlocked yes)
			(layer "F.Fab")
			(hide yes)
			(effects
				(font
					(size 0.7874 0.5842)
					(thickness 0.1524)
				)
			)
		)
		(property "Device Type" "RESISTOR-G155-133R0-01,33OHM,1%"
			(at 0.008382 1.210564 90)
			(unlocked yes)
			(layer "F.Fab")
			(hide yes)
			(effects
				(font
					(size 0.7874 0.5842)
					(thickness 0.1524)
				)
			)
		)
		(property "User Part Number" "PARTNUM*"
			(at 0.02032 4.024884 90)
			(unlocked yes)
			(layer "Cmts.User")
			(hide yes)
			(effects
				(font
					(size 0.7874 0.5842)
					(thickness 0.1524)
				)
			)
		)
		(property "Tolerance" "TOL*"
			(at 0.044704 3.05435 90)
			(unlocked yes)
			(layer "Cmts.User")
			(hide yes)
			(effects
				(font
					(size 0.7874 0.5842)
					(thickness 0.1524)
				)
			)
		)
		(duplicate_pad_numbers_are_jumpers no)
		(fp_line
			(start 1.143 -0.5588)
			(end -1.143 -0.5588)
			(stroke
				(width 0.1)
				(type default)
			)
			(layer "F.SilkS")
		)
		(fp_line
			(start -1.143 -0.5588)
			(end -1.143 0.5588)
			(stroke
				(width 0.1)
				(type default)
			)
			(layer "F.SilkS")
		)
		(fp_line
			(start 1.143 0.5588)
			(end 1.143 -0.5588)
			(stroke
				(width 0.1)
				(type default)
			)
			(layer "F.SilkS")
		)
		(fp_line
			(start -1.143 0.5588)
			(end 1.143 0.5588)
			(stroke
				(width 0.1)
				(type default)
			)
			(layer "F.SilkS")
		)
		(fp_rect
			(start 1.143 0.5588)
			(end -1.143 -0.5588)
			(stroke
				(width 0)
				(type default)
			)
			(fill no)
			(layer "F.CrtYd")
		)
		(fp_line
			(start 0.508 -0.3048)
			(end -0.508 -0.3048)
			(stroke
				(width 0.1)
				(type default)
			)
			(layer "F.Fab")
		)
		(fp_line
			(start -0.508 -0.3048)
			(end -0.508 0.3048)
			(stroke
				(width 0.1)
				(type default)
			)
			(layer "F.Fab")
		)
		(fp_line
			(start 0.508 0.3048)
			(end 0.508 -0.3048)
			(stroke
				(width 0.1)
				(type default)
			)
			(layer "F.Fab")
		)
		(fp_line
			(start -0.508 0.3048)
			(end 0.508 0.3048)
			(stroke
				(width 0.1)
				(type default)
			)
			(layer "F.Fab")
		)
		(pad "1" smd rect
			(at -0.5334 0 90)
			(size 0.7112 0.6096)
			(layers "F.Cu" "F.Mask" "F.Paste")
			(net "SHT3X_I2C_SDA")
		)
		(pad "2" smd rect
			(at 0.5334 0 90)
			(size 0.7112 0.6096)
			(layers "F.Cu" "F.Mask" "F.Paste")
			(net "R_SHT3X_I2C_SDA")
		)
		(zone
			(layer "F.Cu")
			(hatch none 0.5)
			(connect_pads
				(clearance 0)
			)
			(min_thickness 0.25)
			(keepout
				(tracks allowed)
				(vias not_allowed)
				(pads allowed)
				(copperpour not_allowed)
				(footprints allowed)
			)
			(placement
				(enabled no)
				(sheetname "")
			)
			(fill
				(thermal_gap 0.5)
				(thermal_bridge_width 0.5)
				(island_removal_mode 0)
			)
			(polygon
				(pts
					(xy 150.647908 -49.08931) (xy 150.038308 -49.08931) (xy 150.038308 -48.93691) (xy 150.647908 -48.93691)
				)
			)
		)
	)
	(footprint ""
		(layer "F.Cu")
		(at 121.539 -89.535 -90)
		(property "Reference" "R116"
			(at 3.429 0.21463 90)
			(unlocked yes)
			(layer "F.SilkS")
			(effects
				(font
					(size 0.7874 0.5842)
					(thickness 0.1524)
				)
			)
		)
		(property "Value" "VAL*"
			(at 0.02032 2.13233 270)
			(unlocked yes)
			(layer "F.Fab")
			(hide yes)
			(effects
				(font
					(size 0.7874 0.5842)
					(thickness 0.1524)
				)
			)
		)
		(property "Device Type" "RESISTOR-G155-133R0-01,33OHM,1%"
			(at 0.008382 1.210564 270)
			(unlocked yes)
			(layer "F.Fab")
			(hide yes)
			(effects
				(font
					(size 0.7874 0.5842)
					(thickness 0.1524)
				)
			)
		)
		(property "User Part Number" "PARTNUM*"
			(at 0.02032 4.024884 270)
			(unlocked yes)
			(layer "Cmts.User")
			(hide yes)
			(effects
				(font
					(size 0.7874 0.5842)
					(thickness 0.1524)
				)
			)
		)
		(property "Tolerance" "TOL*"
			(at 0.044704 3.05435 270)
			(unlocked yes)
			(layer "Cmts.User")
			(hide yes)
			(effects
				(font
					(size 0.7874 0.5842)
					(thickness 0.1524)
				)
			)
		)
		(duplicate_pad_numbers_are_jumpers no)
		(fp_line
			(start -1.143 0.5588)
			(end 1.143 0.5588)
			(stroke
				(width 0.1)
				(type default)
			)
			(layer "F.SilkS")
		)
		(fp_line
			(start 1.143 0.5588)
			(end 1.143 -0.5588)
			(stroke
				(width 0.1)
				(type default)
			)
			(layer "F.SilkS")
		)
		(fp_line
			(start -1.143 -0.5588)
			(end -1.143 0.5588)
			(stroke
				(width 0.1)
				(type default)
			)
			(layer "F.SilkS")
		)
		(fp_line
			(start 1.143 -0.5588)
			(end -1.143 -0.5588)
			(stroke
				(width 0.1)
				(type default)
			)
			(layer "F.SilkS")
		)
		(fp_rect
			(start 1.143 -0.5588)
			(end -1.143 0.5588)
			(stroke
				(width 0)
				(type default)
			)
			(fill no)
			(layer "F.CrtYd")
		)
		(fp_line
			(start -0.508 0.3048)
			(end 0.508 0.3048)
			(stroke
				(width 0.1)
				(type default)
			)
			(layer "F.Fab")
		)
		(fp_line
			(start 0.508 0.3048)
			(end 0.508 -0.3048)
			(stroke
				(width 0.1)
				(type default)
			)
			(layer "F.Fab")
		)
		(fp_line
			(start -0.508 -0.3048)
			(end -0.508 0.3048)
			(stroke
				(width 0.1)
				(type default)
			)
			(layer "F.Fab")
		)
		(fp_line
			(start 0.508 -0.3048)
			(end -0.508 -0.3048)
			(stroke
				(width 0.1)
				(type default)
			)
			(layer "F.Fab")
		)
		(pad "1" smd rect
			(at -0.5334 0 270)
			(size 0.7112 0.6096)
			(layers "F.Cu" "F.Mask" "F.Paste")
			(net "GPS_RST_N")
		)
		(pad "2" smd rect
			(at 0.5334 0 270)
			(size 0.7112 0.6096)
			(layers "F.Cu" "F.Mask" "F.Paste")
			(net "FPGA_OUT_GPS_RST_N")
		)
		(zone
			(layer "F.Cu")
			(hatch none 0.5)
			(connect_pads
				(clearance 0)
			)
			(min_thickness 0.25)
			(keepout
				(tracks allowed)
				(vias not_allowed)
				(pads allowed)
				(copperpour not_allowed)
				(footprints allowed)
			)
			(placement
				(enabled no)
				(sheetname "")
			)
			(fill
				(thermal_gap 0.5)
				(thermal_bridge_width 0.5)
				(island_removal_mode 0)
			)
			(polygon
				(pts
					(xy 121.8438 -89.4588) (xy 121.8438 -89.6112) (xy 121.2342 -89.6112) (xy 121.2342 -89.4588)
				)
			)
		)
	)
	(footprint ""
		(layer "F.Cu")
		(at 162.569906 -106.13009)
		(property "Reference" "ME11"
			(at 0.625094 4.31546 0)
			(unlocked yes)
			(layer "F.SilkS")
			(effects
				(font
					(size 0.7874 0.5842)
					(thickness 0.1524)
				)
			)
		)
		(property "Value" ""
			(at 0 0 0)
			(layer "F.Fab")
			(effects
				(font
					(size 1.27 1.27)
				)
			)
		)
		(property "Device Type" "MEC_MTH8-MTH125C236N_V8-MTH125A"
			(at 0 5.08127 0)
			(unlocked yes)
			(layer "F.Fab")
			(hide yes)
			(effects
				(font
					(size 0.7874 0.5842)
					(thickness 0.1524)
				)
			)
		)
		(duplicate_pad_numbers_are_jumpers no)
		(fp_poly
			(pts
				(arc
					(start 3.5052 0)
					(mid -3.5052 0)
					(end 3.5052 0)
				)
			)
			(stroke
				(width 0)
				(type default)
			)
			(fill no)
			(layer "B.CrtYd")
		)
		(fp_poly
			(pts
				(arc
					(start 3.5052 0)
					(mid -3.5052 0)
					(end 3.5052 0)
				)
			)
			(stroke
				(width 0)
				(type default)
			)
			(fill no)
			(layer "F.CrtYd")
		)
		(fp_circle
			(center 0 0)
			(end 2.9972 0)
			(stroke
				(width 0.1)
				(type default)
			)
			(fill no)
			(layer "B.Fab")
		)
		(fp_circle
			(center 0 0)
			(end 2.9972 0)
			(stroke
				(width 0.1)
				(type default)
			)
			(fill no)
			(layer "F.Fab")
		)
		(pad "" np_thru_hole circle
			(at 0 0)
			(size 2.921 2.921)
			(drill 3.175)
			(layers "*.Cu" "*.Mask")
			(padstack
				(mode front_inner_back)
				(layer "Inner"
					(shape circle)
					(size 2.921 2.921)
					(clearance 0.4445)
				)
				(layer "B.Cu"
					(shape circle)
					(size 2.921 2.921)
				)
			)
		)
		(pad "1" thru_hole circle
			(at 0 -2.4511)
			(size 0.6096 0.6096)
			(drill 0.3048)
			(layers "*.Cu" "*.Mask")
			(remove_unused_layers no)
			(net "SG")
			(padstack
				(mode front_inner_back)
				(layer "Inner"
					(shape circle)
					(size 0.6096 0.6096)
					(clearance 0.1143)
				)
				(layer "B.Cu"
					(shape circle)
					(size 0.6096 0.6096)
				)
			)
		)
		(pad "2" thru_hole circle
			(at 1.733296 -1.733296)
			(size 0.6096 0.6096)
			(drill 0.3048)
			(layers "*.Cu" "*.Mask")
			(remove_unused_layers no)
			(net "SG")
			(padstack
				(mode front_inner_back)
				(layer "Inner"
					(shape circle)
					(size 0.6096 0.6096)
					(clearance 0.1143)
				)
				(layer "B.Cu"
					(shape circle)
					(size 0.6096 0.6096)
				)
			)
		)
		(pad "3" thru_hole circle
			(at 2.4511 0)
			(size 0.6096 0.6096)
			(drill 0.3048)
			(layers "*.Cu" "*.Mask")
			(remove_unused_layers no)
			(net "SG")
			(padstack
				(mode front_inner_back)
				(layer "Inner"
					(shape circle)
					(size 0.6096 0.6096)
					(clearance 0.1143)
				)
				(layer "B.Cu"
					(shape circle)
					(size 0.6096 0.6096)
				)
			)
		)
		(pad "4" thru_hole circle
			(at 1.733296 1.733296)
			(size 0.6096 0.6096)
			(drill 0.3048)
			(layers "*.Cu" "*.Mask")
			(remove_unused_layers no)
			(net "SG")
			(padstack
				(mode front_inner_back)
				(layer "Inner"
					(shape circle)
					(size 0.6096 0.6096)
					(clearance 0.1143)
				)
				(layer "B.Cu"
					(shape circle)
					(size 0.6096 0.6096)
				)
			)
		)
		(pad "5" thru_hole circle
			(at 0 2.4511)
			(size 0.6096 0.6096)
			(drill 0.3048)
			(layers "*.Cu" "*.Mask")
			(remove_unused_layers no)
			(net "SG")
			(padstack
				(mode front_inner_back)
				(layer "Inner"
					(shape circle)
					(size 0.6096 0.6096)
					(clearance 0.1143)
				)
				(layer "B.Cu"
					(shape circle)
					(size 0.6096 0.6096)
				)
			)
		)
		(pad "6" thru_hole circle
			(at -1.733296 1.733296)
			(size 0.6096 0.6096)
			(drill 0.3048)
			(layers "*.Cu" "*.Mask")
			(remove_unused_layers no)
			(net "SG")
			(padstack
				(mode front_inner_back)
				(layer "Inner"
					(shape circle)
					(size 0.6096 0.6096)
					(clearance 0.1143)
				)
				(layer "B.Cu"
					(shape circle)
					(size 0.6096 0.6096)
				)
			)
		)
		(pad "7" thru_hole circle
			(at -2.4511 0)
			(size 0.6096 0.6096)
			(drill 0.3048)
			(layers "*.Cu" "*.Mask")
			(remove_unused_layers no)
			(net "SG")
			(padstack
				(mode front_inner_back)
				(layer "Inner"
					(shape circle)
					(size 0.6096 0.6096)
					(clearance 0.1143)
				)
				(layer "B.Cu"
					(shape circle)
					(size 0.6096 0.6096)
				)
			)
		)
		(pad "8" thru_hole circle
			(at -1.733296 -1.733296)
			(size 0.6096 0.6096)
			(drill 0.3048)
			(layers "*.Cu" "*.Mask")
			(remove_unused_layers no)
			(net "SG")
			(padstack
				(mode front_inner_back)
				(layer "Inner"
					(shape circle)
					(size 0.6096 0.6096)
					(clearance 0.1143)
				)
				(layer "B.Cu"
					(shape circle)
					(size 0.6096 0.6096)
				)
			)
		)
		(zone
			(layers "F.Cu" "B.Cu" "In1.Cu" "In2.Cu" "In3.Cu" "In4.Cu" "In5.Cu" "In6.Cu"
				"In7.Cu" "In8.Cu"
			)
			(hatch none 0.5)
			(connect_pads
				(clearance 0)
			)
			(min_thickness 0.25)
			(keepout
				(tracks not_allowed)
				(vias allowed)
				(pads allowed)
				(copperpour not_allowed)
				(footprints allowed)
			)
			(placement
				(enabled no)
				(sheetname "")
			)
			(fill
				(thermal_gap 0.5)
				(thermal_bridge_width 0.5)
				(island_removal_mode 0)
			)
			(polygon
				(pts
					(arc
						(start 164.462206 -106.13009)
						(mid 160.677606 -106.13009)
						(end 164.462206 -106.13009)
					)
				)
			)
		)
	)
	(footprint ""
		(layer "F.Cu")
		(at 48.514 -130.683)
		(property "Reference" "SP53"
			(at 0 0 0)
			(layer "F.SilkS")
			(hide yes)
			(effects
				(font
					(size 1.27 1.27)
				)
			)
		)
		(property "Value" ""
			(at 0 0 0)
			(layer "F.Fab")
			(effects
				(font
					(size 1.27 1.27)
				)
			)
		)
		(duplicate_pad_numbers_are_jumpers no)
	)
	(footprint ""
		(layer "F.Cu")
		(at 87.3252 -106.7308 180)
		(property "Reference" "L8"
			(at 0.889 1.30683 0)
			(unlocked yes)
			(layer "F.SilkS")
			(effects
				(font
					(size 0.7874 0.5842)
					(thickness 0.1524)
				)
				(justify left)
			)
		)
		(property "Value" "VAL*"
			(at -0.9398 3.70967 180)
			(unlocked yes)
			(layer "F.Fab")
			(hide yes)
			(effects
				(font
					(size 0.7874 0.5842)
					(thickness 0.1524)
				)
				(justify left)
			)
		)
		(property "Tolerance" "TOL*"
			(at -0.9906 5.00507 180)
			(unlocked yes)
			(layer "Cmts.User")
			(hide yes)
			(effects
				(font
					(size 0.7874 0.5842)
					(thickness 0.1524)
				)
				(justify left)
			)
		)
		(property "User Part Number" "PARTNUM*"
			(at -2.54 2.46507 180)
			(unlocked yes)
			(layer "Cmts.User")
			(hide yes)
			(effects
				(font
					(size 0.7874 0.5842)
					(thickness 0.1524)
				)
				(justify left)
			)
		)
		(property "Device Type" "FERRITEBEAD-G191-10101-01,26OHA"
			(at -0.9906 1.22047 180)
			(unlocked yes)
			(layer "F.Fab")
			(hide yes)
			(effects
				(font
					(size 0.7874 0.5842)
					(thickness 0.1524)
				)
				(justify left)
			)
		)
		(duplicate_pad_numbers_are_jumpers no)
		(fp_line
			(start 1.3208 0.7112)
			(end -1.3208 0.7112)
			(stroke
				(width 0.1)
				(type default)
			)
			(layer "F.SilkS")
		)
		(fp_line
			(start 1.3208 -0.7112)
			(end 1.3208 0.7112)
			(stroke
				(width 0.1)
				(type default)
			)
			(layer "F.SilkS")
		)
		(fp_line
			(start -1.3208 0.7112)
			(end -1.3208 -0.7112)
			(stroke
				(width 0.1)
				(type default)
			)
			(layer "F.SilkS")
		)
		(fp_line
			(start -1.3208 -0.7112)
			(end 1.3208 -0.7112)
			(stroke
				(width 0.1)
				(type default)
			)
			(layer "F.SilkS")
		)
		(fp_rect
			(start -1.3208 0.7112)
			(end 1.3208 -0.7112)
			(stroke
				(width 0)
				(type default)
			)
			(fill no)
			(layer "F.CrtYd")
		)
		(fp_line
			(start 0.8128 0.4572)
			(end -0.8128 0.4572)
			(stroke
				(width 0.1)
				(type default)
			)
			(layer "F.Fab")
		)
		(fp_line
			(start 0.8128 -0.4572)
			(end 0.8128 0.4572)
			(stroke
				(width 0.1)
				(type default)
			)
			(layer "F.Fab")
		)
		(fp_line
			(start -0.8128 0.4572)
			(end -0.8128 -0.4572)
			(stroke
				(width 0.1)
				(type default)
			)
			(layer "F.Fab")
		)
		(fp_line
			(start -0.8128 -0.4572)
			(end 0.8128 -0.4572)
			(stroke
				(width 0.1)
				(type default)
			)
			(layer "F.Fab")
		)
		(pad "1" smd rect
			(at -0.6858 0 180)
			(size 0.762 0.8636)
			(layers "F.Cu" "F.Mask" "F.Paste")
			(net "XP12R0V")
		)
		(pad "2" smd rect
			(at 0.6858 0 180)
			(size 0.762 0.8636)
			(layers "F.Cu" "F.Mask" "F.Paste")
			(net "VIN_XP3R3")
		)
		(zone
			(layer "F.Cu")
			(hatch none 0.5)
			(connect_pads
				(clearance 0)
			)
			(min_thickness 0.25)
			(keepout
				(tracks not_allowed)
				(vias allowed)
				(pads allowed)
				(copperpour not_allowed)
				(footprints allowed)
			)
			(placement
				(enabled no)
				(sheetname "")
			)
			(fill
				(thermal_gap 0.5)
				(thermal_bridge_width 0.5)
				(island_removal_mode 0)
			)
			(polygon
				(pts
					(xy 87.4776 -107.188) (xy 87.1728 -107.188) (xy 87.1728 -106.2736) (xy 87.4776 -106.2736)
				)
			)
		)
		(zone
			(layer "F.Cu")
			(hatch none 0.5)
			(connect_pads
				(clearance 0)
			)
			(min_thickness 0.25)
			(keepout
				(tracks allowed)
				(vias not_allowed)
				(pads allowed)
				(copperpour not_allowed)
				(footprints allowed)
			)
			(placement
				(enabled no)
				(sheetname "")
			)
			(fill
				(thermal_gap 0.5)
				(thermal_bridge_width 0.5)
				(island_removal_mode 0)
			)
			(polygon
				(pts
					(xy 87.4776 -107.188) (xy 87.1728 -107.188) (xy 87.1728 -106.2736) (xy 87.4776 -106.2736)
				)
			)
		)
	)
	(footprint ""
		(layer "F.Cu")
		(at 18.1356 -57.7342 -90)
		(property "Reference" "C313"
			(at -1.54305 1.3716 0)
			(unlocked yes)
			(layer "F.SilkS")
			(effects
				(font
					(size 0.635 0.4064)
					(thickness 0.1524)
				)
			)
		)
		(property "Value" "VAL*"
			(at 0.0762 2.067306 270)
			(unlocked yes)
			(layer "F.Fab")
			(hide yes)
			(effects
				(font
					(size 0.7874 0.5842)
					(thickness 0.1524)
				)
			)
		)
		(property "Tolerance" "TOL*"
			(at 0.0762 3.032506 270)
			(unlocked yes)
			(layer "Cmts.User")
			(hide yes)
			(effects
				(font
					(size 0.7874 0.5842)
					(thickness 0.1524)
				)
			)
		)
		(property "User Part Number" "PARTNUM*"
			(at 0.1016 4.023106 270)
			(unlocked yes)
			(layer "Cmts.User")
			(hide yes)
			(effects
				(font
					(size 0.7874 0.5842)
					(thickness 0.1524)
				)
			)
		)
		(property "Device Type" "CAPACITOR-G105-0B104-CK,0.1UF,A"
			(at 0.0508 1.127506 270)
			(unlocked yes)
			(layer "F.Fab")
			(hide yes)
			(effects
				(font
					(size 0.7874 0.5842)
					(thickness 0.1524)
				)
			)
		)
		(duplicate_pad_numbers_are_jumpers no)
		(fp_line
			(start -1.143 0.5588)
			(end 1.143 0.5588)
			(stroke
				(width 0.1)
				(type default)
			)
			(layer "F.SilkS")
		)
		(fp_line
			(start 1.143 0.5588)
			(end 1.143 -0.5588)
			(stroke
				(width 0.1)
				(type default)
			)
			(layer "F.SilkS")
		)
		(fp_line
			(start -1.143 -0.5588)
			(end -1.143 0.5588)
			(stroke
				(width 0.1)
				(type default)
			)
			(layer "F.SilkS")
		)
		(fp_line
			(start 1.143 -0.5588)
			(end -1.143 -0.5588)
			(stroke
				(width 0.1)
				(type default)
			)
			(layer "F.SilkS")
		)
		(fp_poly
			(pts
				(xy -1.143 0.5588) (xy 1.143 0.5588) (xy 1.143 -0.5588) (xy -1.143 -0.5588)
			)
			(stroke
				(width 0)
				(type default)
			)
			(fill no)
			(layer "F.CrtYd")
		)
		(fp_line
			(start -0.508 0.3048)
			(end 0.508 0.3048)
			(stroke
				(width 0.1)
				(type default)
			)
			(layer "F.Fab")
		)
		(fp_line
			(start 0.508 0.3048)
			(end 0.508 -0.3048)
			(stroke
				(width 0.1)
				(type default)
			)
			(layer "F.Fab")
		)
		(fp_line
			(start -0.508 -0.3048)
			(end -0.508 0.3048)
			(stroke
				(width 0.1)
				(type default)
			)
			(layer "F.Fab")
		)
		(fp_line
			(start 0.508 -0.3048)
			(end -0.508 -0.3048)
			(stroke
				(width 0.1)
				(type default)
			)
			(layer "F.Fab")
		)
		(pad "1" smd rect
			(at -0.5334 0 270)
			(size 0.7112 0.6096)
			(layers "F.Cu" "F.Mask" "F.Paste")
			(net "XP1R8V_ICP10100")
		)
		(pad "2" smd rect
			(at 0.5334 0 270)
			(size 0.7112 0.6096)
			(layers "F.Cu" "F.Mask" "F.Paste")
			(net "SG")
		)
		(zone
			(layer "F.Cu")
			(hatch none 0.5)
			(connect_pads
				(clearance 0)
			)
			(min_thickness 0.25)
			(keepout
				(tracks allowed)
				(vias not_allowed)
				(pads allowed)
				(copperpour not_allowed)
				(footprints allowed)
			)
			(placement
				(enabled no)
				(sheetname "")
			)
			(fill
				(thermal_gap 0.5)
				(thermal_bridge_width 0.5)
				(island_removal_mode 0)
			)
			(polygon
				(pts
					(xy 17.8308 -57.8104) (xy 17.8308 -57.658) (xy 18.4404 -57.658) (xy 18.4404 -57.8104)
				)
			)
		)
		(zone
			(layer "F.Cu")
			(hatch none 0.5)
			(connect_pads
				(clearance 0)
			)
			(min_thickness 0.25)
			(keepout
				(tracks not_allowed)
				(vias allowed)
				(pads allowed)
				(copperpour not_allowed)
				(footprints allowed)
			)
			(placement
				(enabled no)
				(sheetname "")
			)
			(fill
				(thermal_gap 0.5)
				(thermal_bridge_width 0.5)
				(island_removal_mode 0)
			)
			(polygon
				(pts
					(xy 17.8308 -57.8104) (xy 17.8308 -57.658) (xy 18.4404 -57.658) (xy 18.4404 -57.8104)
				)
			)
		)
	)
	(footprint ""
		(layer "F.Cu")
		(at 41.656 -83.058 180)
		(property "Reference" "CR1"
			(at 0.635 3.00863 0)
			(unlocked yes)
			(layer "F.SilkS")
			(effects
				(font
					(size 0.7874 0.5842)
					(thickness 0.1524)
				)
			)
		)
		(property "Value" ""
			(at 0 0 180)
			(layer "F.Fab")
			(effects
				(font
					(size 1.27 1.27)
				)
			)
		)
		(property "Device Type" "DIODE_2F-G122-10186-01"
			(at 0 2.037842 180)
			(unlocked yes)
			(layer "F.Fab")
			(hide yes)
			(effects
				(font
					(size 0.7874 0.5842)
					(thickness 0.000001)
				)
			)
		)
		(property "User Part Number" "PARTNUM*"
			(at 0 3.231642 180)
			(unlocked yes)
			(layer "Cmts.User")
			(hide yes)
			(effects
				(font
					(size 0.7874 0.5842)
					(thickness 0.000001)
				)
			)
		)
		(duplicate_pad_numbers_are_jumpers no)
		(fp_line
			(start 1.608074 0.928878)
			(end -1.608074 0.928878)
			(stroke
				(width 0.1)
				(type default)
			)
			(layer "F.SilkS")
		)
		(fp_line
			(start 1.608074 -0.928878)
			(end 1.608074 0.928878)
			(stroke
				(width 0.1)
				(type default)
			)
			(layer "F.SilkS")
		)
		(fp_line
			(start -1.608074 0.928878)
			(end -1.608074 -0.928878)
			(stroke
				(width 0.1)
				(type default)
			)
			(layer "F.SilkS")
		)
		(fp_line
			(start -1.608074 -0.928878)
			(end 1.608074 -0.928878)
			(stroke
				(width 0.1)
				(type default)
			)
			(layer "F.SilkS")
		)
		(fp_poly
			(pts
				(xy -2.116074 -0.928878) (xy -2.116074 0.928878) (xy -1.608074 0.928878) (xy -1.608074 -0.928878)
			)
			(stroke
				(width 0)
				(type default)
			)
			(fill yes)
			(layer "F.SilkS")
		)
		(fp_poly
			(pts
				(xy -2.116074 1.182878) (xy 1.862074 1.182878) (xy 1.862074 -1.182878) (xy -2.116074 -1.182878)
			)
			(stroke
				(width 0)
				(type default)
			)
			(fill no)
			(layer "F.CrtYd")
		)
		(fp_line
			(start 0.899922 0.674878)
			(end -0.899922 0.674878)
			(stroke
				(width 0.1)
				(type default)
			)
			(layer "F.Fab")
		)
		(fp_line
			(start 0.899922 -0.674878)
			(end 0.899922 0.674878)
			(stroke
				(width 0.1)
				(type default)
			)
			(layer "F.Fab")
		)
		(fp_line
			(start -0.899922 0.674878)
			(end -0.899922 -0.674878)
			(stroke
				(width 0.1)
				(type default)
			)
			(layer "F.Fab")
		)
		(fp_line
			(start -0.899922 -0.674878)
			(end 0.899922 -0.674878)
			(stroke
				(width 0.1)
				(type default)
			)
			(layer "F.Fab")
		)
		(fp_poly
			(pts
				(xy -0.899922 -0.674878) (xy -0.899922 0.674878) (xy -0.391922 0.674878) (xy -0.391922 -0.674878)
			)
			(stroke
				(width 0)
				(type default)
			)
			(fill yes)
			(layer "F.Fab")
		)
		(fp_text user "A"
			(at 2.54 1.10363 0)
			(unlocked yes)
			(layer "F.SilkS")
			(effects
				(font
					(size 0.7874 0.5842)
					(thickness 0.1524)
				)
			)
		)
		(fp_text user "C"
			(at -2.413 0.78105 0)
			(unlocked yes)
			(layer "F.SilkS")
			(effects
				(font
					(size 0.635 0.4064)
					(thickness 0.1524)
				)
			)
		)
		(fp_text user "A"
			(at 2.262124 0.156718 0)
			(unlocked yes)
			(layer "F.Fab")
			(effects
				(font
					(size 0.7874 0.5842)
					(thickness 0.1524)
				)
			)
		)
		(fp_text user "C"
			(at -1.905 1.10363 0)
			(unlocked yes)
			(layer "F.Fab")
			(effects
				(font
					(size 0.7874 0.5842)
					(thickness 0.1524)
				)
			)
		)
		(pad "A" smd rect
			(at 1.100074 0 180)
			(size 0.508 0.508)
			(layers "F.Cu" "F.Mask" "F.Paste")
			(net "XP5R0V")
		)
		(pad "C" smd rect
			(at -1.100074 0 180)
			(size 0.508 0.508)
			(layers "F.Cu" "F.Mask" "F.Paste")
			(net "UNNAMED_525_CAPACITOR_I7_1")
		)
	)
	(footprint ""
		(layer "F.Cu")
		(at 36.9824 -103.7844)
		(property "Reference" "C11"
			(at -4.0894 -1.33223 0)
			(unlocked yes)
			(layer "F.SilkS")
			(effects
				(font
					(size 0.7874 0.5842)
					(thickness 0.1524)
				)
			)
		)
		(property "Value" "VAL*"
			(at 0.193548 2.13614 0)
			(unlocked yes)
			(layer "F.Fab")
			(hide yes)
			(effects
				(font
					(size 0.7874 0.5842)
					(thickness 0.1524)
				)
			)
		)
		(property "Tolerance" "TOL*"
			(at 0.216154 3.1496 0)
			(unlocked yes)
			(layer "Cmts.User")
			(hide yes)
			(effects
				(font
					(size 0.7874 0.5842)
					(thickness 0.1524)
				)
			)
		)
		(property "Device Type" "CAPACITOR-G104-0B101-FK,100PF,A"
			(at 0.184404 1.180592 0)
			(unlocked yes)
			(layer "F.Fab")
			(hide yes)
			(effects
				(font
					(size 0.7874 0.5842)
					(thickness 0.1524)
				)
			)
		)
		(property "User Part Number" "PARTNUM*"
			(at 0.216154 4.185666 0)
			(unlocked yes)
			(layer "Cmts.User")
			(hide yes)
			(effects
				(font
					(size 0.7874 0.5842)
					(thickness 0.1524)
				)
			)
		)
		(duplicate_pad_numbers_are_jumpers no)
		(fp_line
			(start -0.671322 -0.4445)
			(end 0.671322 -0.4445)
			(stroke
				(width 0.1)
				(type default)
			)
			(layer "F.SilkS")
		)
		(fp_line
			(start -0.671322 0.4445)
			(end -0.671322 -0.4445)
			(stroke
				(width 0.1)
				(type default)
			)
			(layer "F.SilkS")
		)
		(fp_line
			(start 0.671322 -0.4445)
			(end 0.671322 0.4445)
			(stroke
				(width 0.1)
				(type default)
			)
			(layer "F.SilkS")
		)
		(fp_line
			(start 0.671322 0.4445)
			(end -0.671322 0.4445)
			(stroke
				(width 0.1)
				(type default)
			)
			(layer "F.SilkS")
		)
		(fp_rect
			(start 0.671322 -0.4445)
			(end -0.671322 0.4445)
			(stroke
				(width 0)
				(type default)
			)
			(fill no)
			(layer "F.CrtYd")
		)
		(fp_line
			(start -0.31496 -0.1651)
			(end -0.31496 0.1651)
			(stroke
				(width 0.1)
				(type default)
			)
			(layer "F.Fab")
		)
		(fp_line
			(start -0.31496 0.1651)
			(end 0.31496 0.1651)
			(stroke
				(width 0.1)
				(type default)
			)
			(layer "F.Fab")
		)
		(fp_line
			(start 0.31496 -0.1651)
			(end -0.31496 -0.1651)
			(stroke
				(width 0.1)
				(type default)
			)
			(layer "F.Fab")
		)
		(fp_line
			(start 0.31496 0.1651)
			(end 0.31496 -0.1651)
			(stroke
				(width 0.1)
				(type default)
			)
			(layer "F.Fab")
		)
		(pad "1" smd rect
			(at -0.264922 0)
			(size 0.3048 0.381)
			(layers "F.Cu" "F.Mask" "F.Paste")
			(net "UNNAMED_516_CAPACITOR_I29_1")
		)
		(pad "2" smd rect
			(at 0.264922 0)
			(size 0.3048 0.381)
			(layers "F.Cu" "F.Mask" "F.Paste")
			(net "XP5R0V_FB_R_TO_AGND")
		)
		(zone
			(layer "F.Cu")
			(hatch none 0.5)
			(connect_pads
				(clearance 0)
			)
			(min_thickness 0.25)
			(keepout
				(tracks allowed)
				(vias not_allowed)
				(pads allowed)
				(copperpour not_allowed)
				(footprints allowed)
			)
			(placement
				(enabled no)
				(sheetname "")
			)
			(fill
				(thermal_gap 0.5)
				(thermal_bridge_width 0.5)
				(island_removal_mode 0)
			)
			(polygon
				(pts
					(xy 37.094922 -103.9749) (xy 36.869878 -103.9749) (xy 36.869878 -103.5939) (xy 37.094922 -103.5939)
				)
			)
		)
	)
	(footprint ""
		(layer "F.Cu")
		(at 66.4464 -15.367)
		(property "Reference" "R56"
			(at -0.0254 2.19837 0)
			(unlocked yes)
			(layer "F.SilkS")
			(effects
				(font
					(size 0.7874 0.5842)
					(thickness 0.1524)
				)
			)
		)
		(property "Value" "VAL*"
			(at 0.02032 2.13233 0)
			(unlocked yes)
			(layer "F.Fab")
			(hide yes)
			(effects
				(font
					(size 0.7874 0.5842)
					(thickness 0.1524)
				)
			)
		)
		(property "Tolerance" "TOL*"
			(at 0.044704 3.05435 0)
			(unlocked yes)
			(layer "Cmts.User")
			(hide yes)
			(effects
				(font
					(size 0.7874 0.5842)
					(thickness 0.1524)
				)
			)
		)
		(property "User Part Number" "PARTNUM*"
			(at 0.02032 4.024884 0)
			(unlocked yes)
			(layer "Cmts.User")
			(hide yes)
			(effects
				(font
					(size 0.7874 0.5842)
					(thickness 0.1524)
				)
			)
		)
		(property "Device Type" "RESISTOR-G155-14701-01,4.7KOHMA"
			(at 0.008382 1.210564 0)
			(unlocked yes)
			(layer "F.Fab")
			(hide yes)
			(effects
				(font
					(size 0.7874 0.5842)
					(thickness 0.1524)
				)
			)
		)
		(duplicate_pad_numbers_are_jumpers no)
		(fp_line
			(start -1.143 -0.5588)
			(end -1.143 0.5588)
			(stroke
				(width 0.1)
				(type default)
			)
			(layer "F.SilkS")
		)
		(fp_line
			(start -1.143 0.5588)
			(end 1.143 0.5588)
			(stroke
				(width 0.1)
				(type default)
			)
			(layer "F.SilkS")
		)
		(fp_line
			(start 1.143 -0.5588)
			(end -1.143 -0.5588)
			(stroke
				(width 0.1)
				(type default)
			)
			(layer "F.SilkS")
		)
		(fp_line
			(start 1.143 0.5588)
			(end 1.143 -0.5588)
			(stroke
				(width 0.1)
				(type default)
			)
			(layer "F.SilkS")
		)
		(fp_rect
			(start -1.143 0.5588)
			(end 1.143 -0.5588)
			(stroke
				(width 0)
				(type default)
			)
			(fill no)
			(layer "F.CrtYd")
		)
		(fp_line
			(start -0.508 -0.3048)
			(end -0.508 0.3048)
			(stroke
				(width 0.1)
				(type default)
			)
			(layer "F.Fab")
		)
		(fp_line
			(start -0.508 0.3048)
			(end 0.508 0.3048)
			(stroke
				(width 0.1)
				(type default)
			)
			(layer "F.Fab")
		)
		(fp_line
			(start 0.508 -0.3048)
			(end -0.508 -0.3048)
			(stroke
				(width 0.1)
				(type default)
			)
			(layer "F.Fab")
		)
		(fp_line
			(start 0.508 0.3048)
			(end 0.508 -0.3048)
			(stroke
				(width 0.1)
				(type default)
			)
			(layer "F.Fab")
		)
		(pad "1" smd rect
			(at -0.5334 0)
			(size 0.7112 0.6096)
			(layers "F.Cu" "F.Mask" "F.Paste")
			(net "XP3R3V")
		)
		(pad "2" smd rect
			(at 0.5334 0)
			(size 0.7112 0.6096)
			(layers "F.Cu" "F.Mask" "F.Paste")
			(net "PCIE_CONN_PERST_N")
		)
		(zone
			(layer "F.Cu")
			(hatch none 0.5)
			(connect_pads
				(clearance 0)
			)
			(min_thickness 0.25)
			(keepout
				(tracks allowed)
				(vias not_allowed)
				(pads allowed)
				(copperpour not_allowed)
				(footprints allowed)
			)
			(placement
				(enabled no)
				(sheetname "")
			)
			(fill
				(thermal_gap 0.5)
				(thermal_bridge_width 0.5)
				(island_removal_mode 0)
			)
			(polygon
				(pts
					(xy 66.3702 -15.0622) (xy 66.5226 -15.0622) (xy 66.5226 -15.6718) (xy 66.3702 -15.6718)
				)
			)
		)
	)
	(footprint ""
		(layer "F.Cu")
		(at 112.649 -90.805)
		(property "Reference" "Q1"
			(at 2.667 -0.08763 0)
			(unlocked yes)
			(layer "F.SilkS")
			(effects
				(font
					(size 0.7874 0.5842)
					(thickness 0.1524)
				)
			)
		)
		(property "Value" ""
			(at 0 0 0)
			(layer "F.Fab")
			(effects
				(font
					(size 1.27 1.27)
				)
			)
		)
		(property "User Part Number" "PARTNUM*"
			(at -0.074676 4.841748 0)
			(unlocked yes)
			(layer "Cmts.User")
			(hide yes)
			(effects
				(font
					(size 0.7874 0.5842)
					(thickness 0.000001)
				)
			)
		)
		(property "Device Type" "POWERMOS_3P_NCH_V1-G121-10200-A"
			(at -0.051562 3.91414 0)
			(unlocked yes)
			(layer "F.Fab")
			(hide yes)
			(effects
				(font
					(size 0.7874 0.5842)
					(thickness 0.000001)
				)
			)
		)
		(duplicate_pad_numbers_are_jumpers no)
		(fp_line
			(start -1.7018 -0.9144)
			(end -0.7493 -0.9144)
			(stroke
				(width 0.1)
				(type default)
			)
			(layer "F.SilkS")
		)
		(fp_line
			(start -1.7018 2.0574)
			(end -1.7018 -0.9144)
			(stroke
				(width 0.1)
				(type default)
			)
			(layer "F.SilkS")
		)
		(fp_line
			(start -0.7493 -2.0574)
			(end 0.7493 -2.0574)
			(stroke
				(width 0.1)
				(type default)
			)
			(layer "F.SilkS")
		)
		(fp_line
			(start -0.7493 -0.9144)
			(end -0.7493 -2.0574)
			(stroke
				(width 0.1)
				(type default)
			)
			(layer "F.SilkS")
		)
		(fp_line
			(start -0.1905 0.9144)
			(end -0.1905 2.0574)
			(stroke
				(width 0.1)
				(type default)
			)
			(layer "F.SilkS")
		)
		(fp_line
			(start -0.1905 2.0574)
			(end -1.7018 2.0574)
			(stroke
				(width 0.1)
				(type default)
			)
			(layer "F.SilkS")
		)
		(fp_line
			(start 0.1905 0.9144)
			(end -0.1905 0.9144)
			(stroke
				(width 0.1)
				(type default)
			)
			(layer "F.SilkS")
		)
		(fp_line
			(start 0.1905 2.0574)
			(end 0.1905 0.9144)
			(stroke
				(width 0.1)
				(type default)
			)
			(layer "F.SilkS")
		)
		(fp_line
			(start 0.7493 -2.0574)
			(end 0.7493 -0.9144)
			(stroke
				(width 0.1)
				(type default)
			)
			(layer "F.SilkS")
		)
		(fp_line
			(start 0.7493 -0.9144)
			(end 1.7018 -0.9144)
			(stroke
				(width 0.1)
				(type default)
			)
			(layer "F.SilkS")
		)
		(fp_line
			(start 1.7018 -0.9144)
			(end 1.7018 2.0574)
			(stroke
				(width 0.1)
				(type default)
			)
			(layer "F.SilkS")
		)
		(fp_line
			(start 1.7018 2.0574)
			(end 0.1905 2.0574)
			(stroke
				(width 0.1)
				(type default)
			)
			(layer "F.SilkS")
		)
		(fp_poly
			(pts
				(arc
					(start -0.752856 2.634234)
					(mid -1.514856 2.634234)
					(end -0.752856 2.634234)
				)
			)
			(stroke
				(width 0)
				(type default)
			)
			(fill yes)
			(layer "F.SilkS")
		)
		(fp_poly
			(pts
				(xy -1.7018 2.0828) (xy -1.7018 -0.9144) (xy -0.762 -0.9144) (xy -0.762 -2.0574) (xy 0.762 -2.0574)
				(xy 0.762 -0.9144) (xy 1.7018 -0.9144) (xy 1.7018 2.0828)
			)
			(stroke
				(width 0)
				(type default)
			)
			(fill no)
			(layer "F.CrtYd")
		)
		(fp_line
			(start -1.4478 -0.6604)
			(end -1.3716 -0.5842)
			(stroke
				(width 0.1)
				(type default)
			)
			(layer "F.Fab")
		)
		(fp_line
			(start -1.4478 -0.6604)
			(end 1.4478 -0.6604)
			(stroke
				(width 0.1)
				(type default)
			)
			(layer "F.Fab")
		)
		(fp_line
			(start -1.4478 0.6604)
			(end -1.4478 -0.6604)
			(stroke
				(width 0.1)
				(type default)
			)
			(layer "F.Fab")
		)
		(fp_line
			(start -1.4478 0.6604)
			(end -1.3716 0.5842)
			(stroke
				(width 0.1)
				(type default)
			)
			(layer "F.Fab")
		)
		(fp_line
			(start -1.3716 -0.5842)
			(end 1.3716 -0.5842)
			(stroke
				(width 0.1)
				(type default)
			)
			(layer "F.Fab")
		)
		(fp_line
			(start -1.3716 0.5842)
			(end -1.3716 -0.5842)
			(stroke
				(width 0.1)
				(type default)
			)
			(layer "F.Fab")
		)
		(fp_line
			(start -1.1684 0.6604)
			(end -0.7112 0.6604)
			(stroke
				(width 0.1)
				(type default)
			)
			(layer "F.Fab")
		)
		(fp_line
			(start -1.1684 0.9144)
			(end -0.7112 0.9144)
			(stroke
				(width 0.1)
				(type default)
			)
			(layer "F.Fab")
		)
		(fp_line
			(start -1.1684 1.143)
			(end -1.1684 0.6604)
			(stroke
				(width 0.1)
				(type default)
			)
			(layer "F.Fab")
		)
		(fp_line
			(start -0.7112 0.6604)
			(end -0.7112 1.143)
			(stroke
				(width 0.1)
				(type default)
			)
			(layer "F.Fab")
		)
		(fp_line
			(start -0.7112 1.143)
			(end -1.1684 1.143)
			(stroke
				(width 0.1)
				(type default)
			)
			(layer "F.Fab")
		)
		(fp_line
			(start -0.2286 -1.143)
			(end 0.2286 -1.143)
			(stroke
				(width 0.1)
				(type default)
			)
			(layer "F.Fab")
		)
		(fp_line
			(start -0.2286 -0.9144)
			(end 0.2286 -0.9144)
			(stroke
				(width 0.1)
				(type default)
			)
			(layer "F.Fab")
		)
		(fp_line
			(start -0.2286 -0.6604)
			(end -0.2286 -1.143)
			(stroke
				(width 0.1)
				(type default)
			)
			(layer "F.Fab")
		)
		(fp_line
			(start 0.2286 -1.143)
			(end 0.2286 -0.6604)
			(stroke
				(width 0.1)
				(type default)
			)
			(layer "F.Fab")
		)
		(fp_line
			(start 0.2286 -0.6604)
			(end -0.2286 -0.6604)
			(stroke
				(width 0.1)
				(type default)
			)
			(layer "F.Fab")
		)
		(fp_line
			(start 0.7112 0.6604)
			(end 1.1684 0.6604)
			(stroke
				(width 0.1)
				(type default)
			)
			(layer "F.Fab")
		)
		(fp_line
			(start 0.7112 0.9144)
			(end 1.1684 0.9144)
			(stroke
				(width 0.1)
				(type default)
			)
			(layer "F.Fab")
		)
		(fp_line
			(start 0.7112 1.143)
			(end 0.7112 0.6604)
			(stroke
				(width 0.1)
				(type default)
			)
			(layer "F.Fab")
		)
		(fp_line
			(start 1.1684 0.6604)
			(end 1.1684 1.143)
			(stroke
				(width 0.1)
				(type default)
			)
			(layer "F.Fab")
		)
		(fp_line
			(start 1.1684 1.143)
			(end 0.7112 1.143)
			(stroke
				(width 0.1)
				(type default)
			)
			(layer "F.Fab")
		)
		(fp_line
			(start 1.3716 -0.5842)
			(end 1.3716 0.5842)
			(stroke
				(width 0.1)
				(type default)
			)
			(layer "F.Fab")
		)
		(fp_line
			(start 1.3716 -0.5842)
			(end 1.4478 -0.6604)
			(stroke
				(width 0.1)
				(type default)
			)
			(layer "F.Fab")
		)
		(fp_line
			(start 1.3716 0.5842)
			(end -1.3716 0.5842)
			(stroke
				(width 0.1)
				(type default)
			)
			(layer "F.Fab")
		)
		(fp_line
			(start 1.3716 0.5842)
			(end 1.4478 0.6604)
			(stroke
				(width 0.1)
				(type default)
			)
			(layer "F.Fab")
		)
		(fp_line
			(start 1.4478 -0.6604)
			(end 1.4478 0.6604)
			(stroke
				(width 0.1)
				(type default)
			)
			(layer "F.Fab")
		)
		(fp_line
			(start 1.4478 0.6604)
			(end -1.4478 0.6604)
			(stroke
				(width 0.1)
				(type default)
			)
			(layer "F.Fab")
		)
		(fp_poly
			(pts
				(arc
					(start -0.752856 2.634234)
					(mid -1.514856 2.634234)
					(end -0.752856 2.634234)
				)
			)
			(stroke
				(width 0)
				(type default)
			)
			(fill yes)
			(layer "F.Fab")
		)
		(fp_text user "2"
			(at 1.651 2.70637 0)
			(unlocked yes)
			(layer "F.SilkS")
			(effects
				(font
					(size 0.7874 0.5842)
					(thickness 0.1524)
				)
			)
		)
		(fp_text user "2"
			(at 0.931418 2.683764 0)
			(unlocked yes)
			(layer "F.Fab")
			(effects
				(font
					(size 0.7874 0.5842)
					(thickness 0.1524)
				)
			)
		)
		(pad "1" smd rect
			(at -0.9398 1.1049)
			(size 0.9906 1.397)
			(layers "F.Cu" "F.Mask" "F.Paste")
			(net "FT_USB_DETECT")
		)
		(pad "2" smd rect
			(at 0.9398 1.1049)
			(size 0.9906 1.397)
			(layers "F.Cu" "F.Mask" "F.Paste")
			(net "SG")
		)
		(pad "3" smd rect
			(at 0 -1.1049)
			(size 0.9906 1.397)
			(layers "F.Cu" "F.Mask" "F.Paste")
			(net "UNNAMED_524_POWERMOS3PNCHV1_I44")
		)
	)
	(footprint ""
		(layer "F.Cu")
		(at 93.4974 -78.7146)
		(property "Reference" "L11"
			(at -4.0259 -0.24003 0)
			(unlocked yes)
			(layer "F.SilkS")
			(effects
				(font
					(size 0.7874 0.5842)
					(thickness 0.1524)
				)
				(justify left)
			)
		)
		(property "Value" "VAL*"
			(at -0.9398 3.70967 0)
			(unlocked yes)
			(layer "F.Fab")
			(hide yes)
			(effects
				(font
					(size 0.7874 0.5842)
					(thickness 0.1524)
				)
				(justify left)
			)
		)
		(property "Tolerance" "TOL*"
			(at -0.9906 5.00507 0)
			(unlocked yes)
			(layer "Cmts.User")
			(hide yes)
			(effects
				(font
					(size 0.7874 0.5842)
					(thickness 0.1524)
				)
				(justify left)
			)
		)
		(property "User Part Number" "PARTNUM*"
			(at -2.54 2.46507 0)
			(unlocked yes)
			(layer "Cmts.User")
			(hide yes)
			(effects
				(font
					(size 0.7874 0.5842)
					(thickness 0.1524)
				)
				(justify left)
			)
		)
		(property "Device Type" "FERRITEBEAD-G191-10101-01,26OHA"
			(at -0.9906 1.22047 0)
			(unlocked yes)
			(layer "F.Fab")
			(hide yes)
			(effects
				(font
					(size 0.7874 0.5842)
					(thickness 0.1524)
				)
				(justify left)
			)
		)
		(duplicate_pad_numbers_are_jumpers no)
		(fp_line
			(start -1.3208 -0.7112)
			(end 1.3208 -0.7112)
			(stroke
				(width 0.1)
				(type default)
			)
			(layer "F.SilkS")
		)
		(fp_line
			(start -1.3208 0.7112)
			(end -1.3208 -0.7112)
			(stroke
				(width 0.1)
				(type default)
			)
			(layer "F.SilkS")
		)
		(fp_line
			(start 1.3208 -0.7112)
			(end 1.3208 0.7112)
			(stroke
				(width 0.1)
				(type default)
			)
			(layer "F.SilkS")
		)
		(fp_line
			(start 1.3208 0.7112)
			(end -1.3208 0.7112)
			(stroke
				(width 0.1)
				(type default)
			)
			(layer "F.SilkS")
		)
		(fp_rect
			(start -1.3208 -0.7112)
			(end 1.3208 0.7112)
			(stroke
				(width 0)
				(type default)
			)
			(fill no)
			(layer "F.CrtYd")
		)
		(fp_line
			(start -0.8128 -0.4572)
			(end 0.8128 -0.4572)
			(stroke
				(width 0.1)
				(type default)
			)
			(layer "F.Fab")
		)
		(fp_line
			(start -0.8128 0.4572)
			(end -0.8128 -0.4572)
			(stroke
				(width 0.1)
				(type default)
			)
			(layer "F.Fab")
		)
		(fp_line
			(start 0.8128 -0.4572)
			(end 0.8128 0.4572)
			(stroke
				(width 0.1)
				(type default)
			)
			(layer "F.Fab")
		)
		(fp_line
			(start 0.8128 0.4572)
			(end -0.8128 0.4572)
			(stroke
				(width 0.1)
				(type default)
			)
			(layer "F.Fab")
		)
		(pad "1" smd rect
			(at -0.6858 0)
			(size 0.762 0.8636)
			(layers "F.Cu" "F.Mask" "F.Paste")
			(net "XP3R3V")
		)
		(pad "2" smd rect
			(at 0.6858 0)
			(size 0.762 0.8636)
			(layers "F.Cu" "F.Mask" "F.Paste")
			(net "XP1R2V_VIN")
		)
		(zone
			(layer "F.Cu")
			(hatch none 0.5)
			(connect_pads
				(clearance 0)
			)
			(min_thickness 0.25)
			(keepout
				(tracks allowed)
				(vias not_allowed)
				(pads allowed)
				(copperpour not_allowed)
				(footprints allowed)
			)
			(placement
				(enabled no)
				(sheetname "")
			)
			(fill
				(thermal_gap 0.5)
				(thermal_bridge_width 0.5)
				(island_removal_mode 0)
			)
			(polygon
				(pts
					(xy 93.345 -79.1718) (xy 93.345 -78.2574) (xy 93.6498 -78.2574) (xy 93.6498 -79.1718)
				)
			)
		)
	)
	(footprint ""
		(layer "F.Cu")
		(at 51.2318 -83.2866 -90)
		(property "Reference" "TP23"
			(at -0.8382 0.01143 90)
			(unlocked yes)
			(layer "F.SilkS")
			(effects
				(font
					(size 0.7874 0.5842)
					(thickness 0.1524)
				)
				(justify left)
			)
		)
		(property "Value" ""
			(at 0 0 270)
			(layer "F.Fab")
			(effects
				(font
					(size 1.27 1.27)
				)
			)
		)
		(property "Device Type" "TP_PIONT-TP010CT020B030_PTH-TPA"
			(at -1.341882 0.996696 270)
			(unlocked yes)
			(layer "F.Fab")
			(hide yes)
			(effects
				(font
					(size 0.7874 0.5842)
					(thickness 0.000001)
				)
				(justify left)
			)
		)
		(duplicate_pad_numbers_are_jumpers no)
		(fp_poly
			(pts
				(arc
					(start 0 -0.889)
					(mid 0 0.889)
					(end 0 -0.889)
				)
			)
			(stroke
				(width 0)
				(type default)
			)
			(fill no)
			(layer "B.CrtYd")
		)
		(fp_poly
			(pts
				(arc
					(start 0 -0.889)
					(mid 0 0.889)
					(end 0 -0.889)
				)
			)
			(stroke
				(width 0)
				(type default)
			)
			(fill no)
			(layer "F.CrtYd")
		)
		(pad "1" thru_hole circle
			(at 0 0 270)
			(size 0.508 0.508)
			(drill 0.254)
			(layers "*.Cu" "*.Mask")
			(remove_unused_layers no)
			(net "FPGA_IN_LM75B_INT2_N")
			(clearance 0.1016)
			(padstack
				(mode front_inner_back)
				(layer "Inner"
					(shape circle)
					(size 0.508 0.508)
					(clearance 0.1016)
				)
				(layer "B.Cu"
					(shape circle)
					(size 0.762 0.762)
					(clearance -0.0254)
				)
			)
		)
	)
	(footprint ""
		(layer "F.Cu")
		(at 14.605 -57.531)
		(property "Reference" "TP28"
			(at 0.66675 2.8194 90)
			(unlocked yes)
			(layer "F.SilkS")
			(effects
				(font
					(size 0.635 0.4064)
					(thickness 0.1524)
				)
				(justify left)
			)
		)
		(property "Value" ""
			(at 0 0 0)
			(layer "F.Fab")
			(effects
				(font
					(size 1.27 1.27)
				)
			)
		)
		(property "Device Type" "TP_PIONT-TP010CT020B030_PTH-TPA"
			(at -1.341882 0.996696 0)
			(unlocked yes)
			(layer "F.Fab")
			(hide yes)
			(effects
				(font
					(size 0.7874 0.5842)
					(thickness 0.000001)
				)
				(justify left)
			)
		)
		(duplicate_pad_numbers_are_jumpers no)
		(fp_poly
			(pts
				(arc
					(start 0.889 0)
					(mid -0.889 0)
					(end 0.889 0)
				)
			)
			(stroke
				(width 0)
				(type default)
			)
			(fill no)
			(layer "B.CrtYd")
		)
		(fp_poly
			(pts
				(arc
					(start 0.889 0)
					(mid -0.889 0)
					(end 0.889 0)
				)
			)
			(stroke
				(width 0)
				(type default)
			)
			(fill no)
			(layer "F.CrtYd")
		)
		(pad "1" thru_hole circle
			(at 0 0)
			(size 0.508 0.508)
			(drill 0.254)
			(layers "*.Cu" "*.Mask")
			(remove_unused_layers no)
			(net "SMA1_SIG_IN_BF_EN_N")
			(clearance 0.1016)
			(padstack
				(mode front_inner_back)
				(layer "Inner"
					(shape circle)
					(size 0.508 0.508)
					(clearance 0.1016)
				)
				(layer "B.Cu"
					(shape circle)
					(size 0.762 0.762)
					(clearance -0.0254)
				)
			)
		)
	)
	(footprint ""
		(layer "F.Cu")
		(at 150.749 -26.035)
		(property "Reference" "R21"
			(at -0.381 2.83337 0)
			(unlocked yes)
			(layer "F.SilkS")
			(effects
				(font
					(size 0.7874 0.5842)
					(thickness 0.1524)
				)
			)
		)
		(property "Value" "VAL*"
			(at 0.02032 2.13233 0)
			(unlocked yes)
			(layer "F.Fab")
			(hide yes)
			(effects
				(font
					(size 0.7874 0.5842)
					(thickness 0.1524)
				)
			)
		)
		(property "Tolerance" "TOL*"
			(at 0.044704 3.05435 0)
			(unlocked yes)
			(layer "Cmts.User")
			(hide yes)
			(effects
				(font
					(size 0.7874 0.5842)
					(thickness 0.1524)
				)
			)
		)
		(property "User Part Number" "PARTNUM*"
			(at 0.02032 4.024884 0)
			(unlocked yes)
			(layer "Cmts.User")
			(hide yes)
			(effects
				(font
					(size 0.7874 0.5842)
					(thickness 0.1524)
				)
			)
		)
		(property "Device Type" "RESISTOR-G155-14701-01,4.7KOHMA"
			(at 0.008382 1.210564 0)
			(unlocked yes)
			(layer "F.Fab")
			(hide yes)
			(effects
				(font
					(size 0.7874 0.5842)
					(thickness 0.1524)
				)
			)
		)
		(duplicate_pad_numbers_are_jumpers no)
		(fp_line
			(start -1.143 -0.5588)
			(end -1.143 0.5588)
			(stroke
				(width 0.1)
				(type default)
			)
			(layer "F.SilkS")
		)
		(fp_line
			(start -1.143 0.5588)
			(end 1.143 0.5588)
			(stroke
				(width 0.1)
				(type default)
			)
			(layer "F.SilkS")
		)
		(fp_line
			(start 1.143 -0.5588)
			(end -1.143 -0.5588)
			(stroke
				(width 0.1)
				(type default)
			)
			(layer "F.SilkS")
		)
		(fp_line
			(start 1.143 0.5588)
			(end 1.143 -0.5588)
			(stroke
				(width 0.1)
				(type default)
			)
			(layer "F.SilkS")
		)
		(fp_rect
			(start -1.143 -0.5588)
			(end 1.143 0.5588)
			(stroke
				(width 0)
				(type default)
			)
			(fill no)
			(layer "F.CrtYd")
		)
		(fp_line
			(start -0.508 -0.3048)
			(end -0.508 0.3048)
			(stroke
				(width 0.1)
				(type default)
			)
			(layer "F.Fab")
		)
		(fp_line
			(start -0.508 0.3048)
			(end 0.508 0.3048)
			(stroke
				(width 0.1)
				(type default)
			)
			(layer "F.Fab")
		)
		(fp_line
			(start 0.508 -0.3048)
			(end -0.508 -0.3048)
			(stroke
				(width 0.1)
				(type default)
			)
			(layer "F.Fab")
		)
		(fp_line
			(start 0.508 0.3048)
			(end 0.508 -0.3048)
			(stroke
				(width 0.1)
				(type default)
			)
			(layer "F.Fab")
		)
		(pad "1" smd rect
			(at -0.5334 0)
			(size 0.7112 0.6096)
			(layers "F.Cu" "F.Mask" "F.Paste")
			(net "XP3R3V_FPGA")
		)
		(pad "2" smd rect
			(at 0.5334 0)
			(size 0.7112 0.6096)
			(layers "F.Cu" "F.Mask" "F.Paste")
			(net "LM75B_I2C_SCL")
		)
		(zone
			(layer "F.Cu")
			(hatch none 0.5)
			(connect_pads
				(clearance 0)
			)
			(min_thickness 0.25)
			(keepout
				(tracks allowed)
				(vias not_allowed)
				(pads allowed)
				(copperpour not_allowed)
				(footprints allowed)
			)
			(placement
				(enabled no)
				(sheetname "")
			)
			(fill
				(thermal_gap 0.5)
				(thermal_bridge_width 0.5)
				(island_removal_mode 0)
			)
			(polygon
				(pts
					(xy 150.6728 -26.3398) (xy 150.6728 -25.7302) (xy 150.8252 -25.7302) (xy 150.8252 -26.3398)
				)
			)
		)
	)
	(footprint ""
		(layer "F.Cu")
		(at 80.772 -64.1096 180)
		(property "Reference" "C285"
			(at 10.287 19.29003 0)
			(unlocked yes)
			(layer "F.SilkS")
			(effects
				(font
					(size 0.7874 0.5842)
					(thickness 0.1524)
				)
			)
		)
		(property "Value" "VAL*"
			(at 0.0762 2.067306 180)
			(unlocked yes)
			(layer "F.Fab")
			(hide yes)
			(effects
				(font
					(size 0.7874 0.5842)
					(thickness 0.1524)
				)
			)
		)
		(property "Tolerance" "TOL*"
			(at 0.0762 3.032506 180)
			(unlocked yes)
			(layer "Cmts.User")
			(hide yes)
			(effects
				(font
					(size 0.7874 0.5842)
					(thickness 0.1524)
				)
			)
		)
		(property "User Part Number" "PARTNUM*"
			(at 0.1016 4.023106 180)
			(unlocked yes)
			(layer "Cmts.User")
			(hide yes)
			(effects
				(font
					(size 0.7874 0.5842)
					(thickness 0.1524)
				)
			)
		)
		(property "Device Type" "CAPACITOR-G105-0B104-CK,0.1UF,A"
			(at 0.0508 1.127506 180)
			(unlocked yes)
			(layer "F.Fab")
			(hide yes)
			(effects
				(font
					(size 0.7874 0.5842)
					(thickness 0.1524)
				)
			)
		)
		(duplicate_pad_numbers_are_jumpers no)
		(fp_line
			(start 1.143 0.5588)
			(end 1.143 -0.5588)
			(stroke
				(width 0.1)
				(type default)
			)
			(layer "F.SilkS")
		)
		(fp_line
			(start 1.143 -0.5588)
			(end -1.143 -0.5588)
			(stroke
				(width 0.1)
				(type default)
			)
			(layer "F.SilkS")
		)
		(fp_line
			(start -1.143 0.5588)
			(end 1.143 0.5588)
			(stroke
				(width 0.1)
				(type default)
			)
			(layer "F.SilkS")
		)
		(fp_line
			(start -1.143 -0.5588)
			(end -1.143 0.5588)
			(stroke
				(width 0.1)
				(type default)
			)
			(layer "F.SilkS")
		)
		(fp_rect
			(start 1.143 -0.5588)
			(end -1.143 0.5588)
			(stroke
				(width 0)
				(type default)
			)
			(fill no)
			(layer "F.CrtYd")
		)
		(fp_line
			(start 0.508 0.3048)
			(end 0.508 -0.3048)
			(stroke
				(width 0.1)
				(type default)
			)
			(layer "F.Fab")
		)
		(fp_line
			(start 0.508 -0.3048)
			(end -0.508 -0.3048)
			(stroke
				(width 0.1)
				(type default)
			)
			(layer "F.Fab")
		)
		(fp_line
			(start -0.508 0.3048)
			(end 0.508 0.3048)
			(stroke
				(width 0.1)
				(type default)
			)
			(layer "F.Fab")
		)
		(fp_line
			(start -0.508 -0.3048)
			(end -0.508 0.3048)
			(stroke
				(width 0.1)
				(type default)
			)
			(layer "F.Fab")
		)
		(pad "1" smd rect
			(at -0.5334 0 180)
			(size 0.7112 0.6096)
			(layers "F.Cu" "F.Mask" "F.Paste")
			(net "UNNAMED_9_BNO080LGA28_I29_CAP")
		)
		(pad "2" smd rect
			(at 0.5334 0 180)
			(size 0.7112 0.6096)
			(layers "F.Cu" "F.Mask" "F.Paste")
			(net "SG")
		)
		(zone
			(layer "F.Cu")
			(hatch none 0.5)
			(connect_pads
				(clearance 0)
			)
			(min_thickness 0.25)
			(keepout
				(tracks allowed)
				(vias not_allowed)
				(pads allowed)
				(copperpour not_allowed)
				(footprints allowed)
			)
			(placement
				(enabled no)
				(sheetname "")
			)
			(fill
				(thermal_gap 0.5)
				(thermal_bridge_width 0.5)
				(island_removal_mode 0)
			)
			(polygon
				(pts
					(xy 80.6958 -63.8048) (xy 80.8482 -63.8048) (xy 80.8482 -64.4144) (xy 80.6958 -64.4144)
				)
			)
		)
	)
	(footprint ""
		(layer "F.Cu")
		(at 124.587 -53.721 180)
		(property "Reference" "R193"
			(at -3.175 -0.29337 0)
			(unlocked yes)
			(layer "F.SilkS")
			(effects
				(font
					(size 0.7874 0.5842)
					(thickness 0.1524)
				)
			)
		)
		(property "Value" "VAL*"
			(at 0.02032 2.13233 180)
			(unlocked yes)
			(layer "F.Fab")
			(hide yes)
			(effects
				(font
					(size 0.7874 0.5842)
					(thickness 0.1524)
				)
			)
		)
		(property "Device Type" "RESISTOR-G155-14701-01,4.7KOHMA"
			(at 0.008382 1.210564 180)
			(unlocked yes)
			(layer "F.Fab")
			(hide yes)
			(effects
				(font
					(size 0.7874 0.5842)
					(thickness 0.1524)
				)
			)
		)
		(property "User Part Number" "PARTNUM*"
			(at 0.02032 4.024884 180)
			(unlocked yes)
			(layer "Cmts.User")
			(hide yes)
			(effects
				(font
					(size 0.7874 0.5842)
					(thickness 0.1524)
				)
			)
		)
		(property "Tolerance" "TOL*"
			(at 0.044704 3.05435 180)
			(unlocked yes)
			(layer "Cmts.User")
			(hide yes)
			(effects
				(font
					(size 0.7874 0.5842)
					(thickness 0.1524)
				)
			)
		)
		(duplicate_pad_numbers_are_jumpers no)
		(fp_line
			(start 1.143 0.5588)
			(end 1.143 -0.5588)
			(stroke
				(width 0.1)
				(type default)
			)
			(layer "F.SilkS")
		)
		(fp_line
			(start 1.143 -0.5588)
			(end -1.143 -0.5588)
			(stroke
				(width 0.1)
				(type default)
			)
			(layer "F.SilkS")
		)
		(fp_line
			(start -1.143 0.5588)
			(end 1.143 0.5588)
			(stroke
				(width 0.1)
				(type default)
			)
			(layer "F.SilkS")
		)
		(fp_line
			(start -1.143 -0.5588)
			(end -1.143 0.5588)
			(stroke
				(width 0.1)
				(type default)
			)
			(layer "F.SilkS")
		)
		(fp_rect
			(start -1.143 0.5588)
			(end 1.143 -0.5588)
			(stroke
				(width 0)
				(type default)
			)
			(fill no)
			(layer "F.CrtYd")
		)
		(fp_line
			(start 0.508 0.3048)
			(end 0.508 -0.3048)
			(stroke
				(width 0.1)
				(type default)
			)
			(layer "F.Fab")
		)
		(fp_line
			(start 0.508 -0.3048)
			(end -0.508 -0.3048)
			(stroke
				(width 0.1)
				(type default)
			)
			(layer "F.Fab")
		)
		(fp_line
			(start -0.508 0.3048)
			(end 0.508 0.3048)
			(stroke
				(width 0.1)
				(type default)
			)
			(layer "F.Fab")
		)
		(fp_line
			(start -0.508 -0.3048)
			(end -0.508 0.3048)
			(stroke
				(width 0.1)
				(type default)
			)
			(layer "F.Fab")
		)
		(pad "1" smd rect
			(at -0.5334 0 180)
			(size 0.7112 0.6096)
			(layers "F.Cu" "F.Mask" "F.Paste")
			(net "XP3R3V_FPGA")
		)
		(pad "2" smd rect
			(at 0.5334 0 180)
			(size 0.7112 0.6096)
			(layers "F.Cu" "F.Mask" "F.Paste")
			(net "FPGA_PROGRAM_N")
		)
		(zone
			(layer "F.Cu")
			(hatch none 0.5)
			(connect_pads
				(clearance 0)
			)
			(min_thickness 0.25)
			(keepout
				(tracks allowed)
				(vias not_allowed)
				(pads allowed)
				(copperpour not_allowed)
				(footprints allowed)
			)
			(placement
				(enabled no)
				(sheetname "")
			)
			(fill
				(thermal_gap 0.5)
				(thermal_bridge_width 0.5)
				(island_removal_mode 0)
			)
			(polygon
				(pts
					(xy 124.6632 -54.0258) (xy 124.5108 -54.0258) (xy 124.5108 -53.4162) (xy 124.6632 -53.4162)
				)
			)
		)
	)
	(footprint ""
		(layer "F.Cu")
		(at 105.6894 -59.7916)
		(property "Reference" "TP184"
			(at 3.68935 0.7874 90)
			(unlocked yes)
			(layer "F.SilkS")
			(effects
				(font
					(size 0.635 0.4064)
					(thickness 0.1524)
				)
				(justify left)
			)
		)
		(property "Value" ""
			(at 0 0 0)
			(layer "F.Fab")
			(effects
				(font
					(size 1.27 1.27)
				)
			)
		)
		(property "Device Type" "TP_PIONT-TP010CT020B030_PTH-TPA"
			(at -1.341882 0.996696 0)
			(unlocked yes)
			(layer "F.Fab")
			(hide yes)
			(effects
				(font
					(size 0.7874 0.5842)
					(thickness 0.1524)
				)
				(justify left)
			)
		)
		(duplicate_pad_numbers_are_jumpers no)
		(fp_poly
			(pts
				(arc
					(start 0.889 0)
					(mid -0.889 0)
					(end 0.889 0)
				)
			)
			(stroke
				(width 0)
				(type default)
			)
			(fill no)
			(layer "B.CrtYd")
		)
		(fp_poly
			(pts
				(arc
					(start 0.889 0)
					(mid -0.889 0)
					(end 0.889 0)
				)
			)
			(stroke
				(width 0)
				(type default)
			)
			(fill no)
			(layer "F.CrtYd")
		)
		(pad "1" thru_hole circle
			(at 0 0)
			(size 0.508 0.508)
			(drill 0.254)
			(layers "*.Cu" "*.Mask")
			(remove_unused_layers no)
			(net "IO_L22N_16")
			(clearance 0.1016)
			(padstack
				(mode front_inner_back)
				(layer "Inner"
					(shape circle)
					(size 0.508 0.508)
					(clearance 0.1016)
				)
				(layer "B.Cu"
					(shape circle)
					(size 0.762 0.762)
					(clearance -0.0254)
				)
			)
		)
	)
	(footprint ""
		(layer "F.Cu")
		(at 36.9824 -105.2068)
		(property "Reference" "R34"
			(at -4.0894 -0.92583 0)
			(unlocked yes)
			(layer "F.SilkS")
			(effects
				(font
					(size 0.7874 0.5842)
					(thickness 0.1524)
				)
			)
		)
		(property "Value" "VAL*"
			(at 0.02032 2.13233 0)
			(unlocked yes)
			(layer "F.Fab")
			(hide yes)
			(effects
				(font
					(size 0.7874 0.5842)
					(thickness 0.1524)
				)
			)
		)
		(property "Tolerance" "TOL*"
			(at 0.044704 3.05435 0)
			(unlocked yes)
			(layer "Cmts.User")
			(hide yes)
			(effects
				(font
					(size 0.7874 0.5842)
					(thickness 0.1524)
				)
			)
		)
		(property "User Part Number" "PARTNUM*"
			(at 0.02032 4.024884 0)
			(unlocked yes)
			(layer "Cmts.User")
			(hide yes)
			(effects
				(font
					(size 0.7874 0.5842)
					(thickness 0.1524)
				)
			)
		)
		(property "Device Type" "RESISTOR-G155-02402-01,24KOHM,A"
			(at 0.008382 1.210564 0)
			(unlocked yes)
			(layer "F.Fab")
			(hide yes)
			(effects
				(font
					(size 0.7874 0.5842)
					(thickness 0.1524)
				)
			)
		)
		(duplicate_pad_numbers_are_jumpers no)
		(fp_line
			(start -1.143 -0.5588)
			(end -1.143 0.5588)
			(stroke
				(width 0.1)
				(type default)
			)
			(layer "F.SilkS")
		)
		(fp_line
			(start -1.143 0.5588)
			(end 1.143 0.5588)
			(stroke
				(width 0.1)
				(type default)
			)
			(layer "F.SilkS")
		)
		(fp_line
			(start 1.143 -0.5588)
			(end -1.143 -0.5588)
			(stroke
				(width 0.1)
				(type default)
			)
			(layer "F.SilkS")
		)
		(fp_line
			(start 1.143 0.5588)
			(end 1.143 -0.5588)
			(stroke
				(width 0.1)
				(type default)
			)
			(layer "F.SilkS")
		)
		(fp_poly
			(pts
				(xy -1.143 0.5588) (xy 1.143 0.5588) (xy 1.143 -0.5588) (xy -1.143 -0.5588)
			)
			(stroke
				(width 0)
				(type default)
			)
			(fill no)
			(layer "F.CrtYd")
		)
		(fp_line
			(start -0.508 -0.3048)
			(end -0.508 0.3048)
			(stroke
				(width 0.1)
				(type default)
			)
			(layer "F.Fab")
		)
		(fp_line
			(start -0.508 0.3048)
			(end 0.508 0.3048)
			(stroke
				(width 0.1)
				(type default)
			)
			(layer "F.Fab")
		)
		(fp_line
			(start 0.508 -0.3048)
			(end -0.508 -0.3048)
			(stroke
				(width 0.1)
				(type default)
			)
			(layer "F.Fab")
		)
		(fp_line
			(start 0.508 0.3048)
			(end 0.508 -0.3048)
			(stroke
				(width 0.1)
				(type default)
			)
			(layer "F.Fab")
		)
		(pad "1" smd rect
			(at -0.5334 0)
			(size 0.7112 0.6096)
			(layers "F.Cu" "F.Mask" "F.Paste")
			(net "UNNAMED_516_CAPACITOR_I29_1")
		)
		(pad "2" smd rect
			(at 0.5334 0)
			(size 0.7112 0.6096)
			(layers "F.Cu" "F.Mask" "F.Paste")
			(net "XP5R0V_FB_R_TO_AGND")
		)
		(zone
			(layer "F.Cu")
			(hatch none 0.5)
			(connect_pads
				(clearance 0)
			)
			(min_thickness 0.25)
			(keepout
				(tracks allowed)
				(vias not_allowed)
				(pads allowed)
				(copperpour not_allowed)
				(footprints allowed)
			)
			(placement
				(enabled no)
				(sheetname "")
			)
			(fill
				(thermal_gap 0.5)
				(thermal_bridge_width 0.5)
				(island_removal_mode 0)
			)
			(polygon
				(pts
					(xy 36.9062 -104.902) (xy 37.0586 -104.902) (xy 37.0586 -105.5116) (xy 36.9062 -105.5116)
				)
			)
		)
		(zone
			(layer "F.Cu")
			(hatch none 0.5)
			(connect_pads
				(clearance 0)
			)
			(min_thickness 0.25)
			(keepout
				(tracks not_allowed)
				(vias allowed)
				(pads allowed)
				(copperpour not_allowed)
				(footprints allowed)
			)
			(placement
				(enabled no)
				(sheetname "")
			)
			(fill
				(thermal_gap 0.5)
				(thermal_bridge_width 0.5)
				(island_removal_mode 0)
			)
			(polygon
				(pts
					(xy 36.9062 -104.902) (xy 37.0586 -104.902) (xy 37.0586 -105.5116) (xy 36.9062 -105.5116)
				)
			)
		)
	)
	(footprint ""
		(layer "F.Cu")
		(at 94.107 -41.021 90)
		(property "Reference" "C137"
			(at 0 -1.48463 90)
			(unlocked yes)
			(layer "F.SilkS")
			(effects
				(font
					(size 0.7874 0.5842)
					(thickness 0.1524)
				)
			)
		)
		(property "Value" "VAL*"
			(at 0.0762 3.134106 90)
			(unlocked yes)
			(layer "F.Fab")
			(hide yes)
			(effects
				(font
					(size 0.7874 0.5842)
					(thickness 0.1524)
				)
			)
		)
		(property "Tolerance" "TOL*"
			(at 0.0762 4.048506 90)
			(unlocked yes)
			(layer "Cmts.User")
			(hide yes)
			(effects
				(font
					(size 0.7874 0.5842)
					(thickness 0.1524)
				)
			)
		)
		(property "User Part Number" "PARTNUM*"
			(at 0.1016 5.013706 90)
			(unlocked yes)
			(layer "Cmts.User")
			(hide yes)
			(effects
				(font
					(size 0.7874 0.5842)
					(thickness 0.1524)
				)
			)
		)
		(property "Device Type" "CAPACITOR-G107-0F476-AM,47UF,2A"
			(at 0.0508 2.194306 90)
			(unlocked yes)
			(layer "F.Fab")
			(hide yes)
			(effects
				(font
					(size 0.7874 0.5842)
					(thickness 0.1524)
				)
			)
		)
		(duplicate_pad_numbers_are_jumpers no)
		(fp_line
			(start 1.5748 -0.9398)
			(end -1.5748 -0.9398)
			(stroke
				(width 0.1)
				(type default)
			)
			(layer "F.SilkS")
		)
		(fp_line
			(start -1.5748 -0.9398)
			(end -1.5748 0.9398)
			(stroke
				(width 0.1)
				(type default)
			)
			(layer "F.SilkS")
		)
		(fp_line
			(start 1.5748 0.9398)
			(end 1.5748 -0.9398)
			(stroke
				(width 0.1)
				(type default)
			)
			(layer "F.SilkS")
		)
		(fp_line
			(start -1.5748 0.9398)
			(end 1.5748 0.9398)
			(stroke
				(width 0.1)
				(type default)
			)
			(layer "F.SilkS")
		)
		(fp_rect
			(start 1.5748 -0.9398)
			(end -1.5748 0.9398)
			(stroke
				(width 0)
				(type default)
			)
			(fill no)
			(layer "F.CrtYd")
		)
		(fp_line
			(start 1.016 -0.635)
			(end -1.016 -0.635)
			(stroke
				(width 0.1)
				(type default)
			)
			(layer "F.Fab")
		)
		(fp_line
			(start -1.016 -0.635)
			(end -1.016 0.635)
			(stroke
				(width 0.1)
				(type default)
			)
			(layer "F.Fab")
		)
		(fp_line
			(start 1.016 0.635)
			(end 1.016 -0.635)
			(stroke
				(width 0.1)
				(type default)
			)
			(layer "F.Fab")
		)
		(fp_line
			(start -1.016 0.635)
			(end 1.016 0.635)
			(stroke
				(width 0.1)
				(type default)
			)
			(layer "F.Fab")
		)
		(pad "1" smd rect
			(at -0.8382 0 90)
			(size 0.9652 1.3716)
			(layers "F.Cu" "F.Mask" "F.Paste")
			(net "XP1R0V_FPGA_MGTAVCC")
		)
		(pad "2" smd rect
			(at 0.8382 0 90)
			(size 0.9652 1.3716)
			(layers "F.Cu" "F.Mask" "F.Paste")
			(net "SG")
		)
		(zone
			(layer "F.Cu")
			(hatch none 0.5)
			(connect_pads
				(clearance 0)
			)
			(min_thickness 0.25)
			(keepout
				(tracks allowed)
				(vias not_allowed)
				(pads allowed)
				(copperpour not_allowed)
				(footprints allowed)
			)
			(placement
				(enabled no)
				(sheetname "")
			)
			(fill
				(thermal_gap 0.5)
				(thermal_bridge_width 0.5)
				(island_removal_mode 0)
			)
			(polygon
				(pts
					(xy 93.472 -41.2496) (xy 93.472 -40.7924) (xy 94.742 -40.7924) (xy 94.742 -41.2496)
				)
			)
		)
	)
	(footprint ""
		(layer "F.Cu")
		(at 135.4074 -97.2058 180)
		(property "Reference" "C6"
			(at 2.286 -0.42037 0)
			(unlocked yes)
			(layer "F.SilkS")
			(effects
				(font
					(size 0.7874 0.5842)
					(thickness 0.1524)
				)
			)
		)
		(property "Value" "VAL*"
			(at 0.0762 3.134106 180)
			(unlocked yes)
			(layer "F.Fab")
			(hide yes)
			(effects
				(font
					(size 0.7874 0.5842)
					(thickness 0.1524)
				)
			)
		)
		(property "Device Type" "CAPACITOR-G107-0F106-EM,10UF,2A"
			(at 0.0508 2.194306 180)
			(unlocked yes)
			(layer "F.Fab")
			(hide yes)
			(effects
				(font
					(size 0.7874 0.5842)
					(thickness 0.1524)
				)
			)
		)
		(property "User Part Number" "PARTNUM*"
			(at 0.1016 5.013706 180)
			(unlocked yes)
			(layer "Cmts.User")
			(hide yes)
			(effects
				(font
					(size 0.7874 0.5842)
					(thickness 0.1524)
				)
			)
		)
		(property "Tolerance" "TOL*"
			(at 0.0762 4.048506 180)
			(unlocked yes)
			(layer "Cmts.User")
			(hide yes)
			(effects
				(font
					(size 0.7874 0.5842)
					(thickness 0.1524)
				)
			)
		)
		(duplicate_pad_numbers_are_jumpers no)
		(fp_line
			(start 1.5748 0.9398)
			(end 1.5748 -0.9398)
			(stroke
				(width 0.1)
				(type default)
			)
			(layer "F.SilkS")
		)
		(fp_line
			(start 1.5748 -0.9398)
			(end -1.5748 -0.9398)
			(stroke
				(width 0.1)
				(type default)
			)
			(layer "F.SilkS")
		)
		(fp_line
			(start -1.5748 0.9398)
			(end 1.5748 0.9398)
			(stroke
				(width 0.1)
				(type default)
			)
			(layer "F.SilkS")
		)
		(fp_line
			(start -1.5748 -0.9398)
			(end -1.5748 0.9398)
			(stroke
				(width 0.1)
				(type default)
			)
			(layer "F.SilkS")
		)
		(fp_rect
			(start 1.5748 -0.9398)
			(end -1.5748 0.9398)
			(stroke
				(width 0)
				(type default)
			)
			(fill no)
			(layer "F.CrtYd")
		)
		(fp_line
			(start 1.016 0.635)
			(end 1.016 -0.635)
			(stroke
				(width 0.1)
				(type default)
			)
			(layer "F.Fab")
		)
		(fp_line
			(start 1.016 -0.635)
			(end -1.016 -0.635)
			(stroke
				(width 0.1)
				(type default)
			)
			(layer "F.Fab")
		)
		(fp_line
			(start -1.016 0.635)
			(end 1.016 0.635)
			(stroke
				(width 0.1)
				(type default)
			)
			(layer "F.Fab")
		)
		(fp_line
			(start -1.016 -0.635)
			(end -1.016 0.635)
			(stroke
				(width 0.1)
				(type default)
			)
			(layer "F.Fab")
		)
		(pad "1" smd rect
			(at -0.8382 0 180)
			(size 0.9652 1.3716)
			(layers "F.Cu" "F.Mask" "F.Paste")
			(net "XP12R0V_A_AVIN")
		)
		(pad "2" smd rect
			(at 0.8382 0 180)
			(size 0.9652 1.3716)
			(layers "F.Cu" "F.Mask" "F.Paste")
			(net "SG")
		)
		(zone
			(layer "F.Cu")
			(hatch none 0.5)
			(connect_pads
				(clearance 0)
			)
			(min_thickness 0.25)
			(keepout
				(tracks allowed)
				(vias not_allowed)
				(pads allowed)
				(copperpour not_allowed)
				(footprints allowed)
			)
			(placement
				(enabled no)
				(sheetname "")
			)
			(fill
				(thermal_gap 0.5)
				(thermal_bridge_width 0.5)
				(island_removal_mode 0)
			)
			(polygon
				(pts
					(xy 135.1788 -96.5708) (xy 135.636 -96.5708) (xy 135.636 -97.8408) (xy 135.1788 -97.8408)
				)
			)
		)
	)
	(footprint ""
		(layer "F.Cu")
		(at 137.3124 -59.5884 180)
		(property "Reference" "TP52"
			(at 3.5306 0.06223 0)
			(unlocked yes)
			(layer "F.SilkS")
			(effects
				(font
					(size 0.7874 0.5842)
					(thickness 0.1524)
				)
				(justify left)
			)
		)
		(property "Value" ""
			(at 0 0 180)
			(layer "F.Fab")
			(effects
				(font
					(size 1.27 1.27)
				)
			)
		)
		(property "Device Type" "TP_PIONT-TP010CT020B030_PTH-TPA"
			(at -1.341882 0.996696 180)
			(unlocked yes)
			(layer "F.Fab")
			(hide yes)
			(effects
				(font
					(size 0.7874 0.5842)
					(thickness 0.1524)
				)
				(justify left)
			)
		)
		(duplicate_pad_numbers_are_jumpers no)
		(fp_poly
			(pts
				(arc
					(start -0.889 0)
					(mid 0.889 0)
					(end -0.889 0)
				)
			)
			(stroke
				(width 0)
				(type default)
			)
			(fill no)
			(layer "B.CrtYd")
		)
		(fp_poly
			(pts
				(arc
					(start -0.889 0)
					(mid 0.889 0)
					(end -0.889 0)
				)
			)
			(stroke
				(width 0)
				(type default)
			)
			(fill no)
			(layer "F.CrtYd")
		)
		(pad "1" thru_hole circle
			(at 0 0 180)
			(size 0.508 0.508)
			(drill 0.254)
			(layers "*.Cu" "*.Mask")
			(remove_unused_layers no)
			(net "XP12R0V")
			(clearance 0.1016)
			(padstack
				(mode front_inner_back)
				(layer "Inner"
					(shape circle)
					(size 0.508 0.508)
					(clearance 0.1016)
				)
				(layer "B.Cu"
					(shape circle)
					(size 0.762 0.762)
					(clearance -0.0254)
				)
			)
		)
	)
	(footprint ""
		(layer "F.Cu")
		(at 38.1 -127.254)
		(property "Reference" "SP74"
			(at 0 0 0)
			(layer "F.SilkS")
			(hide yes)
			(effects
				(font
					(size 1.27 1.27)
				)
			)
		)
		(property "Value" ""
			(at 0 0 0)
			(layer "F.Fab")
			(effects
				(font
					(size 1.27 1.27)
				)
			)
		)
		(duplicate_pad_numbers_are_jumpers no)
	)
	(footprint ""
		(layer "F.Cu")
		(at 89.9922 -103.5558)
		(property "Reference" "R52"
			(at 3.048 0.29337 0)
			(unlocked yes)
			(layer "F.SilkS")
			(effects
				(font
					(size 0.7874 0.5842)
					(thickness 0.1524)
				)
			)
		)
		(property "Value" "VAL*"
			(at 0.02032 2.13233 0)
			(unlocked yes)
			(layer "F.Fab")
			(hide yes)
			(effects
				(font
					(size 0.7874 0.5842)
					(thickness 0.1524)
				)
			)
		)
		(property "Tolerance" "TOL*"
			(at 0.044704 3.05435 0)
			(unlocked yes)
			(layer "Cmts.User")
			(hide yes)
			(effects
				(font
					(size 0.7874 0.5842)
					(thickness 0.1524)
				)
			)
		)
		(property "User Part Number" "PARTNUM*"
			(at 0.02032 4.024884 0)
			(unlocked yes)
			(layer "Cmts.User")
			(hide yes)
			(effects
				(font
					(size 0.7874 0.5842)
					(thickness 0.1524)
				)
			)
		)
		(property "Device Type" "RESISTOR-G155-05101-01,5.1KOHMA"
			(at 0.008382 1.210564 0)
			(unlocked yes)
			(layer "F.Fab")
			(hide yes)
			(effects
				(font
					(size 0.7874 0.5842)
					(thickness 0.1524)
				)
			)
		)
		(duplicate_pad_numbers_are_jumpers no)
		(fp_line
			(start -1.143 -0.5588)
			(end -1.143 0.5588)
			(stroke
				(width 0.1)
				(type default)
			)
			(layer "F.SilkS")
		)
		(fp_line
			(start -1.143 0.5588)
			(end 1.143 0.5588)
			(stroke
				(width 0.1)
				(type default)
			)
			(layer "F.SilkS")
		)
		(fp_line
			(start 1.143 -0.5588)
			(end -1.143 -0.5588)
			(stroke
				(width 0.1)
				(type default)
			)
			(layer "F.SilkS")
		)
		(fp_line
			(start 1.143 0.5588)
			(end 1.143 -0.5588)
			(stroke
				(width 0.1)
				(type default)
			)
			(layer "F.SilkS")
		)
		(fp_rect
			(start -1.143 0.5588)
			(end 1.143 -0.5588)
			(stroke
				(width 0)
				(type default)
			)
			(fill no)
			(layer "F.CrtYd")
		)
		(fp_line
			(start -0.508 -0.3048)
			(end -0.508 0.3048)
			(stroke
				(width 0.1)
				(type default)
			)
			(layer "F.Fab")
		)
		(fp_line
			(start -0.508 0.3048)
			(end 0.508 0.3048)
			(stroke
				(width 0.1)
				(type default)
			)
			(layer "F.Fab")
		)
		(fp_line
			(start 0.508 -0.3048)
			(end -0.508 -0.3048)
			(stroke
				(width 0.1)
				(type default)
			)
			(layer "F.Fab")
		)
		(fp_line
			(start 0.508 0.3048)
			(end 0.508 -0.3048)
			(stroke
				(width 0.1)
				(type default)
			)
			(layer "F.Fab")
		)
		(pad "1" smd rect
			(at -0.5334 0)
			(size 0.7112 0.6096)
			(layers "F.Cu" "F.Mask" "F.Paste")
			(net "XP3R3V_EN")
		)
		(pad "2" smd rect
			(at 0.5334 0)
			(size 0.7112 0.6096)
			(layers "F.Cu" "F.Mask" "F.Paste")
			(net "SG")
		)
		(zone
			(layer "F.Cu")
			(hatch none 0.5)
			(connect_pads
				(clearance 0)
			)
			(min_thickness 0.25)
			(keepout
				(tracks allowed)
				(vias not_allowed)
				(pads allowed)
				(copperpour not_allowed)
				(footprints allowed)
			)
			(placement
				(enabled no)
				(sheetname "")
			)
			(fill
				(thermal_gap 0.5)
				(thermal_bridge_width 0.5)
				(island_removal_mode 0)
			)
			(polygon
				(pts
					(xy 89.916 -103.251) (xy 90.0684 -103.251) (xy 90.0684 -103.8606) (xy 89.916 -103.8606)
				)
			)
		)
	)
	(footprint ""
		(layer "F.Cu")
		(at 108.966 -69.596)
		(property "Reference" "TP53"
			(at -0.9652 1.43637 0)
			(unlocked yes)
			(layer "F.SilkS")
			(effects
				(font
					(size 0.7874 0.5842)
					(thickness 0.1524)
				)
				(justify left)
			)
		)
		(property "Value" ""
			(at 0 0 0)
			(layer "F.Fab")
			(effects
				(font
					(size 1.27 1.27)
				)
			)
		)
		(property "Device Type" "TP_PIONT-TP010CT020B030_PTH-TPA"
			(at -1.341882 0.996696 0)
			(unlocked yes)
			(layer "F.Fab")
			(hide yes)
			(effects
				(font
					(size 0.7874 0.5842)
					(thickness 0.1524)
				)
				(justify left)
			)
		)
		(duplicate_pad_numbers_are_jumpers no)
		(fp_poly
			(pts
				(arc
					(start 0.889 0)
					(mid -0.889 0)
					(end 0.889 0)
				)
			)
			(stroke
				(width 0)
				(type default)
			)
			(fill no)
			(layer "B.CrtYd")
		)
		(fp_poly
			(pts
				(arc
					(start 0.889 0)
					(mid -0.889 0)
					(end 0.889 0)
				)
			)
			(stroke
				(width 0)
				(type default)
			)
			(fill no)
			(layer "F.CrtYd")
		)
		(pad "1" thru_hole circle
			(at 0 0)
			(size 0.508 0.508)
			(drill 0.254)
			(layers "*.Cu" "*.Mask")
			(remove_unused_layers no)
			(net "XP3R3V")
			(clearance 0.1016)
			(padstack
				(mode front_inner_back)
				(layer "Inner"
					(shape circle)
					(size 0.508 0.508)
					(clearance 0.1016)
				)
				(layer "B.Cu"
					(shape circle)
					(size 0.762 0.762)
					(clearance -0.0254)
				)
			)
		)
	)
	(footprint ""
		(layer "F.Cu")
		(at 65.532 -136.017)
		(property "Reference" "SP32"
			(at 0 0 0)
			(layer "F.SilkS")
			(hide yes)
			(effects
				(font
					(size 1.27 1.27)
				)
			)
		)
		(property "Value" ""
			(at 0 0 0)
			(layer "F.Fab")
			(effects
				(font
					(size 1.27 1.27)
				)
			)
		)
		(duplicate_pad_numbers_are_jumpers no)
	)
	(footprint ""
		(layer "F.Cu")
		(at 20.32 -27.94 180)
		(property "Reference" "R273"
			(at -2.794 -0.54737 0)
			(unlocked yes)
			(layer "F.SilkS")
			(effects
				(font
					(size 0.7874 0.5842)
					(thickness 0.1524)
				)
			)
		)
		(property "Value" "VAL*"
			(at 0.02032 2.13233 180)
			(unlocked yes)
			(layer "F.Fab")
			(hide yes)
			(effects
				(font
					(size 0.7874 0.5842)
					(thickness 0.1524)
				)
			)
		)
		(property "Device Type" "RESISTOR-G155-11000-01,100OHM,A"
			(at 0.008382 1.210564 180)
			(unlocked yes)
			(layer "F.Fab")
			(hide yes)
			(effects
				(font
					(size 0.7874 0.5842)
					(thickness 0.1524)
				)
			)
		)
		(property "User Part Number" "PARTNUM*"
			(at 0.02032 4.024884 180)
			(unlocked yes)
			(layer "Cmts.User")
			(hide yes)
			(effects
				(font
					(size 0.7874 0.5842)
					(thickness 0.1524)
				)
			)
		)
		(property "Tolerance" "TOL*"
			(at 0.044704 3.05435 180)
			(unlocked yes)
			(layer "Cmts.User")
			(hide yes)
			(effects
				(font
					(size 0.7874 0.5842)
					(thickness 0.1524)
				)
			)
		)
		(duplicate_pad_numbers_are_jumpers no)
		(fp_line
			(start 1.143 0.5588)
			(end 1.143 -0.5588)
			(stroke
				(width 0.1)
				(type default)
			)
			(layer "F.SilkS")
		)
		(fp_line
			(start 1.143 -0.5588)
			(end -1.143 -0.5588)
			(stroke
				(width 0.1)
				(type default)
			)
			(layer "F.SilkS")
		)
		(fp_line
			(start -1.143 0.5588)
			(end 1.143 0.5588)
			(stroke
				(width 0.1)
				(type default)
			)
			(layer "F.SilkS")
		)
		(fp_line
			(start -1.143 -0.5588)
			(end -1.143 0.5588)
			(stroke
				(width 0.1)
				(type default)
			)
			(layer "F.SilkS")
		)
		(fp_poly
			(pts
				(xy -1.143 0.5588) (xy 1.143 0.5588) (xy 1.143 -0.5588) (xy -1.143 -0.5588)
			)
			(stroke
				(width 0)
				(type default)
			)
			(fill no)
			(layer "F.CrtYd")
		)
		(fp_line
			(start 0.508 0.3048)
			(end 0.508 -0.3048)
			(stroke
				(width 0.1)
				(type default)
			)
			(layer "F.Fab")
		)
		(fp_line
			(start 0.508 -0.3048)
			(end -0.508 -0.3048)
			(stroke
				(width 0.1)
				(type default)
			)
			(layer "F.Fab")
		)
		(fp_line
			(start -0.508 0.3048)
			(end 0.508 0.3048)
			(stroke
				(width 0.1)
				(type default)
			)
			(layer "F.Fab")
		)
		(fp_line
			(start -0.508 -0.3048)
			(end -0.508 0.3048)
			(stroke
				(width 0.1)
				(type default)
			)
			(layer "F.Fab")
		)
		(pad "1" smd rect
			(at -0.5334 0 180)
			(size 0.7112 0.6096)
			(layers "F.Cu" "F.Mask" "F.Paste")
			(net "FPGA_OUT_SMA2_LED_BLUE_N")
		)
		(pad "2" smd rect
			(at 0.5334 0 180)
			(size 0.7112 0.6096)
			(layers "F.Cu" "F.Mask" "F.Paste")
			(net "UNNAMED_14_LED4PV14_I266_1")
		)
		(zone
			(layer "F.Cu")
			(hatch none 0.5)
			(connect_pads
				(clearance 0)
			)
			(min_thickness 0.25)
			(keepout
				(tracks not_allowed)
				(vias allowed)
				(pads allowed)
				(copperpour not_allowed)
				(footprints allowed)
			)
			(placement
				(enabled no)
				(sheetname "")
			)
			(fill
				(thermal_gap 0.5)
				(thermal_bridge_width 0.5)
				(island_removal_mode 0)
			)
			(polygon
				(pts
					(xy 20.3962 -28.2448) (xy 20.2438 -28.2448) (xy 20.2438 -27.6352) (xy 20.3962 -27.6352)
				)
			)
		)
		(zone
			(layer "F.Cu")
			(hatch none 0.5)
			(connect_pads
				(clearance 0)
			)
			(min_thickness 0.25)
			(keepout
				(tracks allowed)
				(vias not_allowed)
				(pads allowed)
				(copperpour not_allowed)
				(footprints allowed)
			)
			(placement
				(enabled no)
				(sheetname "")
			)
			(fill
				(thermal_gap 0.5)
				(thermal_bridge_width 0.5)
				(island_removal_mode 0)
			)
			(polygon
				(pts
					(xy 20.3962 -28.2448) (xy 20.2438 -28.2448) (xy 20.2438 -27.6352) (xy 20.3962 -27.6352)
				)
			)
		)
	)
	(footprint ""
		(layer "F.Cu")
		(at 134.112 -69.215)
		(property "Reference" "C193"
			(at 0.889 -3.38963 0)
			(unlocked yes)
			(layer "F.SilkS")
			(effects
				(font
					(size 0.7874 0.5842)
					(thickness 0.1524)
				)
			)
		)
		(property "Value" "VAL*"
			(at 0.193548 2.13614 0)
			(unlocked yes)
			(layer "F.Fab")
			(hide yes)
			(effects
				(font
					(size 0.7874 0.5842)
					(thickness 0.1524)
				)
			)
		)
		(property "Tolerance" "TOL*"
			(at 0.216154 3.1496 0)
			(unlocked yes)
			(layer "Cmts.User")
			(hide yes)
			(effects
				(font
					(size 0.7874 0.5842)
					(thickness 0.1524)
				)
			)
		)
		(property "Device Type" "CAPACITOR-G104-0B103-EK,0.01UFA"
			(at 0.184404 1.180592 0)
			(unlocked yes)
			(layer "F.Fab")
			(hide yes)
			(effects
				(font
					(size 0.7874 0.5842)
					(thickness 0.1524)
				)
			)
		)
		(property "User Part Number" "PARTNUM*"
			(at 0.216154 4.185666 0)
			(unlocked yes)
			(layer "Cmts.User")
			(hide yes)
			(effects
				(font
					(size 0.7874 0.5842)
					(thickness 0.1524)
				)
			)
		)
		(duplicate_pad_numbers_are_jumpers no)
		(fp_line
			(start -0.671322 -0.4445)
			(end 0.671322 -0.4445)
			(stroke
				(width 0.1)
				(type default)
			)
			(layer "F.SilkS")
		)
		(fp_line
			(start -0.671322 0.4445)
			(end -0.671322 -0.4445)
			(stroke
				(width 0.1)
				(type default)
			)
			(layer "F.SilkS")
		)
		(fp_line
			(start 0.671322 -0.4445)
			(end 0.671322 0.4445)
			(stroke
				(width 0.1)
				(type default)
			)
			(layer "F.SilkS")
		)
		(fp_line
			(start 0.671322 0.4445)
			(end -0.671322 0.4445)
			(stroke
				(width 0.1)
				(type default)
			)
			(layer "F.SilkS")
		)
		(fp_rect
			(start 0.671322 0.4445)
			(end -0.671322 -0.4445)
			(stroke
				(width 0)
				(type default)
			)
			(fill no)
			(layer "F.CrtYd")
		)
		(fp_line
			(start -0.31496 -0.1651)
			(end -0.31496 0.1651)
			(stroke
				(width 0.1)
				(type default)
			)
			(layer "F.Fab")
		)
		(fp_line
			(start -0.31496 0.1651)
			(end 0.31496 0.1651)
			(stroke
				(width 0.1)
				(type default)
			)
			(layer "F.Fab")
		)
		(fp_line
			(start 0.31496 -0.1651)
			(end -0.31496 -0.1651)
			(stroke
				(width 0.1)
				(type default)
			)
			(layer "F.Fab")
		)
		(fp_line
			(start 0.31496 0.1651)
			(end 0.31496 -0.1651)
			(stroke
				(width 0.1)
				(type default)
			)
			(layer "F.Fab")
		)
		(pad "1" smd rect
			(at -0.264922 0)
			(size 0.3048 0.381)
			(layers "F.Cu" "F.Mask" "F.Paste")
			(net "XP1R8V_PG_R")
		)
		(pad "2" smd rect
			(at 0.264922 0)
			(size 0.3048 0.381)
			(layers "F.Cu" "F.Mask" "F.Paste")
			(net "SG")
		)
		(zone
			(layer "F.Cu")
			(hatch none 0.5)
			(connect_pads
				(clearance 0)
			)
			(min_thickness 0.25)
			(keepout
				(tracks allowed)
				(vias not_allowed)
				(pads allowed)
				(copperpour not_allowed)
				(footprints allowed)
			)
			(placement
				(enabled no)
				(sheetname "")
			)
			(fill
				(thermal_gap 0.5)
				(thermal_bridge_width 0.5)
				(island_removal_mode 0)
			)
			(polygon
				(pts
					(xy 134.224522 -69.0245) (xy 134.224522 -69.4055) (xy 133.999478 -69.4055) (xy 133.999478 -69.0245)
				)
			)
		)
	)
	(footprint ""
		(layer "F.Cu")
		(at 38.354 -80.899 90)
		(property "Reference" "C309"
			(at 3.556 -0.08763 90)
			(unlocked yes)
			(layer "F.SilkS")
			(effects
				(font
					(size 0.7874 0.5842)
					(thickness 0.1524)
				)
			)
		)
		(property "Value" "VAL*"
			(at 0.0762 2.067306 90)
			(unlocked yes)
			(layer "F.Fab")
			(hide yes)
			(effects
				(font
					(size 0.7874 0.5842)
					(thickness 0.1524)
				)
			)
		)
		(property "Tolerance" "TOL*"
			(at 0.0762 3.032506 90)
			(unlocked yes)
			(layer "Cmts.User")
			(hide yes)
			(effects
				(font
					(size 0.7874 0.5842)
					(thickness 0.1524)
				)
			)
		)
		(property "User Part Number" "PARTNUM*"
			(at 0.1016 4.023106 90)
			(unlocked yes)
			(layer "Cmts.User")
			(hide yes)
			(effects
				(font
					(size 0.7874 0.5842)
					(thickness 0.1524)
				)
			)
		)
		(property "Device Type" "CAPACITOR-G105-0B104-EK,0.1UF,A"
			(at 0.0508 1.127506 90)
			(unlocked yes)
			(layer "F.Fab")
			(hide yes)
			(effects
				(font
					(size 0.7874 0.5842)
					(thickness 0.1524)
				)
			)
		)
		(duplicate_pad_numbers_are_jumpers no)
		(fp_line
			(start 1.143 -0.5588)
			(end -1.143 -0.5588)
			(stroke
				(width 0.1)
				(type default)
			)
			(layer "F.SilkS")
		)
		(fp_line
			(start -1.143 -0.5588)
			(end -1.143 0.5588)
			(stroke
				(width 0.1)
				(type default)
			)
			(layer "F.SilkS")
		)
		(fp_line
			(start 1.143 0.5588)
			(end 1.143 -0.5588)
			(stroke
				(width 0.1)
				(type default)
			)
			(layer "F.SilkS")
		)
		(fp_line
			(start -1.143 0.5588)
			(end 1.143 0.5588)
			(stroke
				(width 0.1)
				(type default)
			)
			(layer "F.SilkS")
		)
		(fp_poly
			(pts
				(xy -1.143 0.5588) (xy 1.143 0.5588) (xy 1.143 -0.5588) (xy -1.143 -0.5588)
			)
			(stroke
				(width 0)
				(type default)
			)
			(fill no)
			(layer "F.CrtYd")
		)
		(fp_line
			(start 0.508 -0.3048)
			(end -0.508 -0.3048)
			(stroke
				(width 0.1)
				(type default)
			)
			(layer "F.Fab")
		)
		(fp_line
			(start -0.508 -0.3048)
			(end -0.508 0.3048)
			(stroke
				(width 0.1)
				(type default)
			)
			(layer "F.Fab")
		)
		(fp_line
			(start 0.508 0.3048)
			(end 0.508 -0.3048)
			(stroke
				(width 0.1)
				(type default)
			)
			(layer "F.Fab")
		)
		(fp_line
			(start -0.508 0.3048)
			(end 0.508 0.3048)
			(stroke
				(width 0.1)
				(type default)
			)
			(layer "F.Fab")
		)
		(pad "1" smd rect
			(at -0.5334 0 90)
			(size 0.7112 0.6096)
			(layers "F.Cu" "F.Mask" "F.Paste")
			(net "XP3R3V_FT4232")
		)
		(pad "2" smd rect
			(at 0.5334 0 90)
			(size 0.7112 0.6096)
			(layers "F.Cu" "F.Mask" "F.Paste")
			(net "SG")
		)
		(zone
			(layer "F.Cu")
			(hatch none 0.5)
			(connect_pads
				(clearance 0)
			)
			(min_thickness 0.25)
			(keepout
				(tracks not_allowed)
				(vias allowed)
				(pads allowed)
				(copperpour not_allowed)
				(footprints allowed)
			)
			(placement
				(enabled no)
				(sheetname "")
			)
			(fill
				(thermal_gap 0.5)
				(thermal_bridge_width 0.5)
				(island_removal_mode 0)
			)
			(polygon
				(pts
					(xy 38.6588 -80.8228) (xy 38.6588 -80.9752) (xy 38.0492 -80.9752) (xy 38.0492 -80.8228)
				)
			)
		)
		(zone
			(layer "F.Cu")
			(hatch none 0.5)
			(connect_pads
				(clearance 0)
			)
			(min_thickness 0.25)
			(keepout
				(tracks allowed)
				(vias not_allowed)
				(pads allowed)
				(copperpour not_allowed)
				(footprints allowed)
			)
			(placement
				(enabled no)
				(sheetname "")
			)
			(fill
				(thermal_gap 0.5)
				(thermal_bridge_width 0.5)
				(island_removal_mode 0)
			)
			(polygon
				(pts
					(xy 38.6588 -80.8228) (xy 38.6588 -80.9752) (xy 38.0492 -80.9752) (xy 38.0492 -80.8228)
				)
			)
		)
	)
	(footprint ""
		(layer "F.Cu")
		(at 57.15 -134.747)
		(property "Reference" "SP46"
			(at 0 0 0)
			(layer "F.SilkS")
			(hide yes)
			(effects
				(font
					(size 1.27 1.27)
				)
			)
		)
		(property "Value" ""
			(at 0 0 0)
			(layer "F.Fab")
			(effects
				(font
					(size 1.27 1.27)
				)
			)
		)
		(duplicate_pad_numbers_are_jumpers no)
	)
	(footprint ""
		(layer "F.Cu")
		(at 84.836 -71.501 90)
		(property "Reference" "J17"
			(at 3.38963 -0.762 0)
			(unlocked yes)
			(layer "F.SilkS")
			(effects
				(font
					(size 0.7874 0.5842)
					(thickness 0.1524)
				)
			)
		)
		(property "Value" ""
			(at 0 0 90)
			(layer "F.Fab")
			(effects
				(font
					(size 1.27 1.27)
				)
			)
		)
		(property "Device Type" "CONN_HDR_2X2_M_S_SMT-G200-1068A"
			(at 0.069088 6.518656 90)
			(unlocked yes)
			(layer "F.Fab")
			(hide yes)
			(effects
				(font
					(size 0.7874 0.5842)
					(thickness 0.000001)
				)
			)
		)
		(property "User Part Number" "PARTNUM*"
			(at 0.069088 7.712456 90)
			(unlocked yes)
			(layer "Cmts.User")
			(hide yes)
			(effects
				(font
					(size 0.7874 0.5842)
					(thickness 0.000001)
				)
			)
		)
		(duplicate_pad_numbers_are_jumpers no)
		(fp_line
			(start 2.589022 -4.637024)
			(end 2.589022 4.637024)
			(stroke
				(width 0.1)
				(type default)
			)
			(layer "F.SilkS")
		)
		(fp_line
			(start -2.589022 -4.637024)
			(end 2.589022 -4.637024)
			(stroke
				(width 0.1)
				(type default)
			)
			(layer "F.SilkS")
		)
		(fp_line
			(start 2.589022 4.637024)
			(end -2.589022 4.637024)
			(stroke
				(width 0.1)
				(type default)
			)
			(layer "F.SilkS")
		)
		(fp_line
			(start -2.589022 4.637024)
			(end -2.589022 -4.637024)
			(stroke
				(width 0.1)
				(type default)
			)
			(layer "F.SilkS")
		)
		(fp_rect
			(start -2.843022 4.891024)
			(end 2.843022 -4.891024)
			(stroke
				(width 0)
				(type default)
			)
			(fill no)
			(layer "F.CrtYd")
		)
		(fp_line
			(start 2.335022 -2.439924)
			(end -2.335022 -2.439924)
			(stroke
				(width 0.1)
				(type default)
			)
			(layer "F.Fab")
		)
		(fp_line
			(start -2.335022 -2.439924)
			(end -2.335022 2.439924)
			(stroke
				(width 0.1)
				(type default)
			)
			(layer "F.Fab")
		)
		(fp_line
			(start 2.335022 2.439924)
			(end 2.335022 -2.439924)
			(stroke
				(width 0.1)
				(type default)
			)
			(layer "F.Fab")
		)
		(fp_line
			(start -2.335022 2.439924)
			(end 2.335022 2.439924)
			(stroke
				(width 0.1)
				(type default)
			)
			(layer "F.Fab")
		)
		(fp_text user "4"
			(at 2.11963 -5.4991 0)
			(unlocked yes)
			(layer "F.SilkS")
			(effects
				(font
					(size 0.7874 0.5842)
					(thickness 0.1524)
				)
				(justify left)
			)
		)
		(fp_text user "2"
			(at -0.29337 -5.4991 0)
			(unlocked yes)
			(layer "F.SilkS")
			(effects
				(font
					(size 0.7874 0.5842)
					(thickness 0.1524)
				)
				(justify left)
			)
		)
		(fp_text user "3"
			(at 3.13563 3.0099 0)
			(unlocked yes)
			(layer "F.SilkS")
			(effects
				(font
					(size 0.7874 0.5842)
					(thickness 0.1524)
				)
				(justify left)
			)
		)
		(fp_text user "1"
			(at -0.42037 4.7879 0)
			(unlocked yes)
			(layer "F.SilkS")
			(effects
				(font
					(size 0.7874 0.5842)
					(thickness 0.1524)
				)
				(justify left)
			)
		)
		(fp_text user "4"
			(at 1.109218 -3.767074 0)
			(unlocked yes)
			(layer "F.Fab")
			(effects
				(font
					(size 0.7874 0.5842)
					(thickness 0.1524)
				)
				(justify left)
			)
		)
		(fp_text user "2"
			(at -1.667002 -3.7338 0)
			(unlocked yes)
			(layer "F.Fab")
			(effects
				(font
					(size 0.7874 0.5842)
					(thickness 0.1524)
				)
				(justify left)
			)
		)
		(fp_text user "3"
			(at 1.26111 2.939542 0)
			(unlocked yes)
			(layer "F.Fab")
			(effects
				(font
					(size 0.7874 0.5842)
					(thickness 0.1524)
				)
				(justify left)
			)
		)
		(fp_text user "1"
			(at -1.38049 2.939542 0)
			(unlocked yes)
			(layer "F.Fab")
			(effects
				(font
					(size 0.7874 0.5842)
					(thickness 0.1524)
				)
				(justify left)
			)
		)
		(pad "1" smd rect
			(at -1.27 2.605024 90)
			(size 1.27 3.556)
			(layers "F.Cu" "F.Mask" "F.Paste")
			(net "SN_EEPROM_WP")
		)
		(pad "2" smd rect
			(at -1.27 -2.605024 90)
			(size 1.27 3.556)
			(layers "F.Cu" "F.Mask" "F.Paste")
			(net "SG")
		)
		(pad "3" smd rect
			(at 1.27 2.605024 90)
			(size 1.27 3.556)
			(layers "F.Cu" "F.Mask" "F.Paste")
			(net "SEC_EEPROM_WP")
		)
		(pad "4" smd rect
			(at 1.27 -2.605024 90)
			(size 1.27 3.556)
			(layers "F.Cu" "F.Mask" "F.Paste")
			(net "SG")
		)
	)
	(footprint ""
		(layer "F.Cu")
		(at 44.069 -130.429)
		(property "Reference" "SP65"
			(at 0 0 0)
			(layer "F.SilkS")
			(hide yes)
			(effects
				(font
					(size 1.27 1.27)
				)
			)
		)
		(property "Value" ""
			(at 0 0 0)
			(layer "F.Fab")
			(effects
				(font
					(size 1.27 1.27)
				)
			)
		)
		(duplicate_pad_numbers_are_jumpers no)
	)
	(footprint ""
		(layer "F.Cu")
		(at 135.6614 -99.1108)
		(property "Reference" "R9"
			(at -2.5654 -0.29083 0)
			(unlocked yes)
			(layer "F.SilkS")
			(effects
				(font
					(size 0.7874 0.5842)
					(thickness 0.1524)
				)
			)
		)
		(property "Value" "VAL*"
			(at 0.0508 2.549906 0)
			(unlocked yes)
			(layer "F.Fab")
			(hide yes)
			(effects
				(font
					(size 0.7874 0.5842)
					(thickness 0.1524)
				)
			)
		)
		(property "Device Type" "RESISTOR-G156-049R9-01,49.9OHMA"
			(at 0.0254 1.584706 0)
			(unlocked yes)
			(layer "F.Fab")
			(hide yes)
			(effects
				(font
					(size 0.7874 0.5842)
					(thickness 0.1524)
				)
			)
		)
		(property "User Part Number" "PARTNUM*"
			(at 0.0762 4.480306 0)
			(unlocked yes)
			(layer "Cmts.User")
			(hide yes)
			(effects
				(font
					(size 0.7874 0.5842)
					(thickness 0.1524)
				)
			)
		)
		(property "Tolerance" "TOL*"
			(at 0.0508 3.515106 0)
			(unlocked yes)
			(layer "Cmts.User")
			(hide yes)
			(effects
				(font
					(size 0.7874 0.5842)
					(thickness 0.1524)
				)
			)
		)
		(duplicate_pad_numbers_are_jumpers no)
		(fp_line
			(start -1.3208 -0.7112)
			(end 1.3208 -0.7112)
			(stroke
				(width 0.1)
				(type default)
			)
			(layer "F.SilkS")
		)
		(fp_line
			(start -1.3208 0.7112)
			(end -1.3208 -0.7112)
			(stroke
				(width 0.1)
				(type default)
			)
			(layer "F.SilkS")
		)
		(fp_line
			(start 1.3208 -0.7112)
			(end 1.3208 0.7112)
			(stroke
				(width 0.1)
				(type default)
			)
			(layer "F.SilkS")
		)
		(fp_line
			(start 1.3208 0.7112)
			(end -1.3208 0.7112)
			(stroke
				(width 0.1)
				(type default)
			)
			(layer "F.SilkS")
		)
		(fp_rect
			(start -1.3208 0.7112)
			(end 1.3208 -0.7112)
			(stroke
				(width 0)
				(type default)
			)
			(fill no)
			(layer "F.CrtYd")
		)
		(fp_line
			(start -0.8128 -0.4572)
			(end 0.8128 -0.4572)
			(stroke
				(width 0.1)
				(type default)
			)
			(layer "F.Fab")
		)
		(fp_line
			(start -0.8128 0.4572)
			(end -0.8128 -0.4572)
			(stroke
				(width 0.1)
				(type default)
			)
			(layer "F.Fab")
		)
		(fp_line
			(start 0.8128 -0.4572)
			(end 0.8128 0.4572)
			(stroke
				(width 0.1)
				(type default)
			)
			(layer "F.Fab")
		)
		(fp_line
			(start 0.8128 0.4572)
			(end -0.8128 0.4572)
			(stroke
				(width 0.1)
				(type default)
			)
			(layer "F.Fab")
		)
		(pad "1" smd rect
			(at -0.6858 0)
			(size 0.762 0.8636)
			(layers "F.Cu" "F.Mask" "F.Paste")
			(net "XP12R0V_IN")
		)
		(pad "2" smd rect
			(at 0.6858 0)
			(size 0.762 0.8636)
			(layers "F.Cu" "F.Mask" "F.Paste")
			(net "XP12R0V_A_AVIN")
		)
		(zone
			(layer "F.Cu")
			(hatch none 0.5)
			(connect_pads
				(clearance 0)
			)
			(min_thickness 0.25)
			(keepout
				(tracks allowed)
				(vias not_allowed)
				(pads allowed)
				(copperpour not_allowed)
				(footprints allowed)
			)
			(placement
				(enabled no)
				(sheetname "")
			)
			(fill
				(thermal_gap 0.5)
				(thermal_bridge_width 0.5)
				(island_removal_mode 0)
			)
			(polygon
				(pts
					(xy 135.509 -98.6536) (xy 135.8138 -98.6536) (xy 135.8138 -99.568) (xy 135.509 -99.568)
				)
			)
		)
	)
	(footprint ""
		(layer "F.Cu")
		(at 126.0602 -70.5358 180)
		(property "Reference" "C191"
			(at 0.0762 3.33883 0)
			(unlocked yes)
			(layer "F.SilkS")
			(effects
				(font
					(size 0.7874 0.5842)
					(thickness 0.1524)
				)
			)
		)
		(property "Value" "VAL*"
			(at 0.193548 2.13614 180)
			(unlocked yes)
			(layer "F.Fab")
			(hide yes)
			(effects
				(font
					(size 0.7874 0.5842)
					(thickness 0.1524)
				)
			)
		)
		(property "Tolerance" "TOL*"
			(at 0.216154 3.1496 180)
			(unlocked yes)
			(layer "Cmts.User")
			(hide yes)
			(effects
				(font
					(size 0.7874 0.5842)
					(thickness 0.1524)
				)
			)
		)
		(property "Device Type" "CAPACITOR-G104-0B103-EK,0.01UFA"
			(at 0.184404 1.180592 180)
			(unlocked yes)
			(layer "F.Fab")
			(hide yes)
			(effects
				(font
					(size 0.7874 0.5842)
					(thickness 0.1524)
				)
			)
		)
		(property "User Part Number" "PARTNUM*"
			(at 0.216154 4.185666 180)
			(unlocked yes)
			(layer "Cmts.User")
			(hide yes)
			(effects
				(font
					(size 0.7874 0.5842)
					(thickness 0.1524)
				)
			)
		)
		(duplicate_pad_numbers_are_jumpers no)
		(fp_line
			(start 0.671322 0.4445)
			(end -0.671322 0.4445)
			(stroke
				(width 0.1)
				(type default)
			)
			(layer "F.SilkS")
		)
		(fp_line
			(start 0.671322 -0.4445)
			(end 0.671322 0.4445)
			(stroke
				(width 0.1)
				(type default)
			)
			(layer "F.SilkS")
		)
		(fp_line
			(start -0.671322 0.4445)
			(end -0.671322 -0.4445)
			(stroke
				(width 0.1)
				(type default)
			)
			(layer "F.SilkS")
		)
		(fp_line
			(start -0.671322 -0.4445)
			(end 0.671322 -0.4445)
			(stroke
				(width 0.1)
				(type default)
			)
			(layer "F.SilkS")
		)
		(fp_rect
			(start -0.671322 0.4445)
			(end 0.671322 -0.4445)
			(stroke
				(width 0)
				(type default)
			)
			(fill no)
			(layer "F.CrtYd")
		)
		(fp_line
			(start 0.31496 0.1651)
			(end 0.31496 -0.1651)
			(stroke
				(width 0.1)
				(type default)
			)
			(layer "F.Fab")
		)
		(fp_line
			(start 0.31496 -0.1651)
			(end -0.31496 -0.1651)
			(stroke
				(width 0.1)
				(type default)
			)
			(layer "F.Fab")
		)
		(fp_line
			(start -0.31496 0.1651)
			(end 0.31496 0.1651)
			(stroke
				(width 0.1)
				(type default)
			)
			(layer "F.Fab")
		)
		(fp_line
			(start -0.31496 -0.1651)
			(end -0.31496 0.1651)
			(stroke
				(width 0.1)
				(type default)
			)
			(layer "F.Fab")
		)
		(pad "1" smd rect
			(at -0.264922 0 180)
			(size 0.3048 0.381)
			(layers "F.Cu" "F.Mask" "F.Paste")
			(net "XP1R8V_SS")
		)
		(pad "2" smd rect
			(at 0.264922 0 180)
			(size 0.3048 0.381)
			(layers "F.Cu" "F.Mask" "F.Paste")
			(net "SG")
		)
		(zone
			(layer "F.Cu")
			(hatch none 0.5)
			(connect_pads
				(clearance 0)
			)
			(min_thickness 0.25)
			(keepout
				(tracks allowed)
				(vias not_allowed)
				(pads allowed)
				(copperpour not_allowed)
				(footprints allowed)
			)
			(placement
				(enabled no)
				(sheetname "")
			)
			(fill
				(thermal_gap 0.5)
				(thermal_bridge_width 0.5)
				(island_removal_mode 0)
			)
			(polygon
				(pts
					(xy 126.172722 -70.7263) (xy 125.947678 -70.7263) (xy 125.947678 -70.3453) (xy 126.172722 -70.3453)
				)
			)
		)
	)
	(footprint ""
		(layer "F.Cu")
		(at 13.589 -22.987 -90)
		(property "Reference" "R157"
			(at 0.635 3.51663 90)
			(unlocked yes)
			(layer "F.SilkS")
			(effects
				(font
					(size 0.7874 0.5842)
					(thickness 0.1524)
				)
			)
		)
		(property "Value" "VAL*"
			(at 0.02032 2.13233 270)
			(unlocked yes)
			(layer "F.Fab")
			(hide yes)
			(effects
				(font
					(size 0.7874 0.5842)
					(thickness 0.1524)
				)
			)
		)
		(property "Tolerance" "TOL*"
			(at 0.044704 3.05435 270)
			(unlocked yes)
			(layer "Cmts.User")
			(hide yes)
			(effects
				(font
					(size 0.7874 0.5842)
					(thickness 0.1524)
				)
			)
		)
		(property "User Part Number" "PARTNUM*"
			(at 0.02032 4.024884 270)
			(unlocked yes)
			(layer "Cmts.User")
			(hide yes)
			(effects
				(font
					(size 0.7874 0.5842)
					(thickness 0.1524)
				)
			)
		)
		(property "Device Type" "RESISTOR-G155-11000-01,100OHM,A"
			(at 0.008382 1.210564 270)
			(unlocked yes)
			(layer "F.Fab")
			(hide yes)
			(effects
				(font
					(size 0.7874 0.5842)
					(thickness 0.1524)
				)
			)
		)
		(duplicate_pad_numbers_are_jumpers no)
		(fp_line
			(start -1.143 0.5588)
			(end 1.143 0.5588)
			(stroke
				(width 0.1)
				(type default)
			)
			(layer "F.SilkS")
		)
		(fp_line
			(start 1.143 0.5588)
			(end 1.143 -0.5588)
			(stroke
				(width 0.1)
				(type default)
			)
			(layer "F.SilkS")
		)
		(fp_line
			(start -1.143 -0.5588)
			(end -1.143 0.5588)
			(stroke
				(width 0.1)
				(type default)
			)
			(layer "F.SilkS")
		)
		(fp_line
			(start 1.143 -0.5588)
			(end -1.143 -0.5588)
			(stroke
				(width 0.1)
				(type default)
			)
			(layer "F.SilkS")
		)
		(fp_poly
			(pts
				(xy -1.143 0.5588) (xy 1.143 0.5588) (xy 1.143 -0.5588) (xy -1.143 -0.5588)
			)
			(stroke
				(width 0)
				(type default)
			)
			(fill no)
			(layer "F.CrtYd")
		)
		(fp_line
			(start -0.508 0.3048)
			(end 0.508 0.3048)
			(stroke
				(width 0.1)
				(type default)
			)
			(layer "F.Fab")
		)
		(fp_line
			(start 0.508 0.3048)
			(end 0.508 -0.3048)
			(stroke
				(width 0.1)
				(type default)
			)
			(layer "F.Fab")
		)
		(fp_line
			(start -0.508 -0.3048)
			(end -0.508 0.3048)
			(stroke
				(width 0.1)
				(type default)
			)
			(layer "F.Fab")
		)
		(fp_line
			(start 0.508 -0.3048)
			(end -0.508 -0.3048)
			(stroke
				(width 0.1)
				(type default)
			)
			(layer "F.Fab")
		)
		(pad "1" smd rect
			(at -0.5334 0 270)
			(size 0.7112 0.6096)
			(layers "F.Cu" "F.Mask" "F.Paste")
			(net "ANT4_OUT")
		)
		(pad "2" smd rect
			(at 0.5334 0 270)
			(size 0.7112 0.6096)
			(layers "F.Cu" "F.Mask" "F.Paste")
			(net "UNNAMED_12_74HCT2G125DPTSSOP8_3")
		)
		(zone
			(layer "F.Cu")
			(hatch none 0.5)
			(connect_pads
				(clearance 0)
			)
			(min_thickness 0.25)
			(keepout
				(tracks not_allowed)
				(vias allowed)
				(pads allowed)
				(copperpour not_allowed)
				(footprints allowed)
			)
			(placement
				(enabled no)
				(sheetname "")
			)
			(fill
				(thermal_gap 0.5)
				(thermal_bridge_width 0.5)
				(island_removal_mode 0)
			)
			(polygon
				(pts
					(xy 13.2842 -23.0632) (xy 13.2842 -22.9108) (xy 13.8938 -22.9108) (xy 13.8938 -23.0632)
				)
			)
		)
		(zone
			(layer "F.Cu")
			(hatch none 0.5)
			(connect_pads
				(clearance 0)
			)
			(min_thickness 0.25)
			(keepout
				(tracks allowed)
				(vias not_allowed)
				(pads allowed)
				(copperpour not_allowed)
				(footprints allowed)
			)
			(placement
				(enabled no)
				(sheetname "")
			)
			(fill
				(thermal_gap 0.5)
				(thermal_bridge_width 0.5)
				(island_removal_mode 0)
			)
			(polygon
				(pts
					(xy 13.2842 -23.0632) (xy 13.2842 -22.9108) (xy 13.8938 -22.9108) (xy 13.8938 -23.0632)
				)
			)
		)
	)
	(footprint ""
		(layer "F.Cu")
		(at 84.328 -76.581 90)
		(property "Reference" "TP1"
			(at 1.5875 -0.08763 90)
			(unlocked yes)
			(layer "F.SilkS")
			(effects
				(font
					(size 0.7874 0.5842)
					(thickness 0.1524)
				)
				(justify left)
			)
		)
		(property "Value" ""
			(at 0 0 90)
			(layer "F.Fab")
			(effects
				(font
					(size 1.27 1.27)
				)
			)
		)
		(property "Device Type" "TP_PIONT-TP010CT020B030_PTH-TPA"
			(at -1.341882 0.996696 90)
			(unlocked yes)
			(layer "F.Fab")
			(hide yes)
			(effects
				(font
					(size 0.7874 0.5842)
					(thickness 0.1524)
				)
				(justify left)
			)
		)
		(duplicate_pad_numbers_are_jumpers no)
		(fp_poly
			(pts
				(arc
					(start 0 0.889)
					(mid 0 -0.889)
					(end 0 0.889)
				)
			)
			(stroke
				(width 0)
				(type default)
			)
			(fill no)
			(layer "B.CrtYd")
		)
		(fp_poly
			(pts
				(arc
					(start 0 0.889)
					(mid 0 -0.889)
					(end 0 0.889)
				)
			)
			(stroke
				(width 0)
				(type default)
			)
			(fill no)
			(layer "F.CrtYd")
		)
		(pad "1" thru_hole circle
			(at 0 0 90)
			(size 0.508 0.508)
			(drill 0.254)
			(layers "*.Cu" "*.Mask")
			(remove_unused_layers no)
			(net "BNO080_EVN_SDA")
			(clearance 0.1016)
			(padstack
				(mode front_inner_back)
				(layer "Inner"
					(shape circle)
					(size 0.508 0.508)
					(clearance 0.1016)
				)
				(layer "B.Cu"
					(shape circle)
					(size 0.762 0.762)
					(clearance -0.0254)
				)
			)
		)
	)
	(footprint ""
		(layer "F.Cu")
		(at 119.761 -21.971)
		(property "Reference" "R474"
			(at -2.794 0.92837 0)
			(unlocked yes)
			(layer "F.SilkS")
			(effects
				(font
					(size 0.7874 0.5842)
					(thickness 0.1524)
				)
			)
		)
		(property "Value" "VAL*"
			(at 0.02032 2.13233 0)
			(unlocked yes)
			(layer "F.Fab")
			(hide yes)
			(effects
				(font
					(size 0.7874 0.5842)
					(thickness 0.1524)
				)
			)
		)
		(property "Tolerance" "TOL*"
			(at 0.044704 3.05435 0)
			(unlocked yes)
			(layer "Cmts.User")
			(hide yes)
			(effects
				(font
					(size 0.7874 0.5842)
					(thickness 0.1524)
				)
			)
		)
		(property "User Part Number" "PARTNUM*"
			(at 0.02032 4.024884 0)
			(unlocked yes)
			(layer "Cmts.User")
			(hide yes)
			(effects
				(font
					(size 0.7874 0.5842)
					(thickness 0.1524)
				)
			)
		)
		(property "Device Type" "RESISTOR-G155-11003-01,100KOHMA"
			(at 0.008382 1.210564 0)
			(unlocked yes)
			(layer "F.Fab")
			(hide yes)
			(effects
				(font
					(size 0.7874 0.5842)
					(thickness 0.1524)
				)
			)
		)
		(duplicate_pad_numbers_are_jumpers no)
		(fp_line
			(start -1.143 -0.5588)
			(end -1.143 0.5588)
			(stroke
				(width 0.1)
				(type default)
			)
			(layer "F.SilkS")
		)
		(fp_line
			(start -1.143 0.5588)
			(end 1.143 0.5588)
			(stroke
				(width 0.1)
				(type default)
			)
			(layer "F.SilkS")
		)
		(fp_line
			(start 1.143 -0.5588)
			(end -1.143 -0.5588)
			(stroke
				(width 0.1)
				(type default)
			)
			(layer "F.SilkS")
		)
		(fp_line
			(start 1.143 0.5588)
			(end 1.143 -0.5588)
			(stroke
				(width 0.1)
				(type default)
			)
			(layer "F.SilkS")
		)
		(fp_poly
			(pts
				(xy -1.143 0.5588) (xy 1.143 0.5588) (xy 1.143 -0.5588) (xy -1.143 -0.5588)
			)
			(stroke
				(width 0)
				(type default)
			)
			(fill no)
			(layer "F.CrtYd")
		)
		(fp_line
			(start -0.508 -0.3048)
			(end -0.508 0.3048)
			(stroke
				(width 0.1)
				(type default)
			)
			(layer "F.Fab")
		)
		(fp_line
			(start -0.508 0.3048)
			(end 0.508 0.3048)
			(stroke
				(width 0.1)
				(type default)
			)
			(layer "F.Fab")
		)
		(fp_line
			(start 0.508 -0.3048)
			(end -0.508 -0.3048)
			(stroke
				(width 0.1)
				(type default)
			)
			(layer "F.Fab")
		)
		(fp_line
			(start 0.508 0.3048)
			(end 0.508 -0.3048)
			(stroke
				(width 0.1)
				(type default)
			)
			(layer "F.Fab")
		)
		(pad "1" smd rect
			(at -0.5334 0)
			(size 0.7112 0.6096)
			(layers "F.Cu" "F.Mask" "F.Paste")
			(net "XP3R3V_FPGA")
		)
		(pad "2" smd rect
			(at 0.5334 0)
			(size 0.7112 0.6096)
			(layers "F.Cu" "F.Mask" "F.Paste")
			(net "FPGA_PCA9546_I2C_SDA")
		)
		(zone
			(layer "F.Cu")
			(hatch none 0.5)
			(connect_pads
				(clearance 0)
			)
			(min_thickness 0.25)
			(keepout
				(tracks allowed)
				(vias not_allowed)
				(pads allowed)
				(copperpour not_allowed)
				(footprints allowed)
			)
			(placement
				(enabled no)
				(sheetname "")
			)
			(fill
				(thermal_gap 0.5)
				(thermal_bridge_width 0.5)
				(island_removal_mode 0)
			)
			(polygon
				(pts
					(xy 119.6848 -21.6662) (xy 119.8372 -21.6662) (xy 119.8372 -22.2758) (xy 119.6848 -22.2758)
				)
			)
		)
		(zone
			(layer "F.Cu")
			(hatch none 0.5)
			(connect_pads
				(clearance 0)
			)
			(min_thickness 0.25)
			(keepout
				(tracks not_allowed)
				(vias allowed)
				(pads allowed)
				(copperpour not_allowed)
				(footprints allowed)
			)
			(placement
				(enabled no)
				(sheetname "")
			)
			(fill
				(thermal_gap 0.5)
				(thermal_bridge_width 0.5)
				(island_removal_mode 0)
			)
			(polygon
				(pts
					(xy 119.6848 -21.6662) (xy 119.8372 -21.6662) (xy 119.8372 -22.2758) (xy 119.6848 -22.2758)
				)
			)
		)
	)
	(footprint ""
		(layer "F.Cu")
		(at 36.703 -94.615 -90)
		(property "Reference" "C74"
			(at 3.72237 -2.032 0)
			(unlocked yes)
			(layer "F.SilkS")
			(effects
				(font
					(size 0.7874 0.5842)
					(thickness 0.1524)
				)
			)
		)
		(property "Value" "VAL*"
			(at 0.0762 2.067306 270)
			(unlocked yes)
			(layer "F.Fab")
			(hide yes)
			(effects
				(font
					(size 0.7874 0.5842)
					(thickness 0.1524)
				)
			)
		)
		(property "Device Type" "CAPACITOR-G105-0B104-EK,0.1UF,A"
			(at 0.0508 1.127506 270)
			(unlocked yes)
			(layer "F.Fab")
			(hide yes)
			(effects
				(font
					(size 0.7874 0.5842)
					(thickness 0.1524)
				)
			)
		)
		(property "User Part Number" "PARTNUM*"
			(at 0.1016 4.023106 270)
			(unlocked yes)
			(layer "Cmts.User")
			(hide yes)
			(effects
				(font
					(size 0.7874 0.5842)
					(thickness 0.1524)
				)
			)
		)
		(property "Tolerance" "TOL*"
			(at 0.0762 3.032506 270)
			(unlocked yes)
			(layer "Cmts.User")
			(hide yes)
			(effects
				(font
					(size 0.7874 0.5842)
					(thickness 0.1524)
				)
			)
		)
		(duplicate_pad_numbers_are_jumpers no)
		(fp_line
			(start -1.143 0.5588)
			(end 1.143 0.5588)
			(stroke
				(width 0.1)
				(type default)
			)
			(layer "F.SilkS")
		)
		(fp_line
			(start 1.143 0.5588)
			(end 1.143 -0.5588)
			(stroke
				(width 0.1)
				(type default)
			)
			(layer "F.SilkS")
		)
		(fp_line
			(start -1.143 -0.5588)
			(end -1.143 0.5588)
			(stroke
				(width 0.1)
				(type default)
			)
			(layer "F.SilkS")
		)
		(fp_line
			(start 1.143 -0.5588)
			(end -1.143 -0.5588)
			(stroke
				(width 0.1)
				(type default)
			)
			(layer "F.SilkS")
		)
		(fp_rect
			(start -1.143 0.5588)
			(end 1.143 -0.5588)
			(stroke
				(width 0)
				(type default)
			)
			(fill no)
			(layer "F.CrtYd")
		)
		(fp_line
			(start -0.508 0.3048)
			(end 0.508 0.3048)
			(stroke
				(width 0.1)
				(type default)
			)
			(layer "F.Fab")
		)
		(fp_line
			(start 0.508 0.3048)
			(end 0.508 -0.3048)
			(stroke
				(width 0.1)
				(type default)
			)
			(layer "F.Fab")
		)
		(fp_line
			(start -0.508 -0.3048)
			(end -0.508 0.3048)
			(stroke
				(width 0.1)
				(type default)
			)
			(layer "F.Fab")
		)
		(fp_line
			(start 0.508 -0.3048)
			(end -0.508 -0.3048)
			(stroke
				(width 0.1)
				(type default)
			)
			(layer "F.Fab")
		)
		(pad "1" smd rect
			(at -0.5334 0 270)
			(size 0.7112 0.6096)
			(layers "F.Cu" "F.Mask" "F.Paste")
			(net "XP12R0V")
		)
		(pad "2" smd rect
			(at 0.5334 0 270)
			(size 0.7112 0.6096)
			(layers "F.Cu" "F.Mask" "F.Paste")
			(net "SG")
		)
		(zone
			(layer "F.Cu")
			(hatch none 0.5)
			(connect_pads
				(clearance 0)
			)
			(min_thickness 0.25)
			(keepout
				(tracks allowed)
				(vias not_allowed)
				(pads allowed)
				(copperpour not_allowed)
				(footprints allowed)
			)
			(placement
				(enabled no)
				(sheetname "")
			)
			(fill
				(thermal_gap 0.5)
				(thermal_bridge_width 0.5)
				(island_removal_mode 0)
			)
			(polygon
				(pts
					(xy 36.3982 -94.6912) (xy 36.3982 -94.5388) (xy 37.0078 -94.5388) (xy 37.0078 -94.6912)
				)
			)
		)
	)
	(footprint ""
		(layer "F.Cu")
		(at 112.1156 -26.7208 90)
		(property "Reference" "C251"
			(at -8.4328 -0.31623 90)
			(unlocked yes)
			(layer "F.SilkS")
			(effects
				(font
					(size 0.7874 0.5842)
					(thickness 0.1524)
				)
			)
		)
		(property "Value" "VAL*"
			(at 0.0762 2.067306 90)
			(unlocked yes)
			(layer "F.Fab")
			(hide yes)
			(effects
				(font
					(size 0.7874 0.5842)
					(thickness 0.1524)
				)
			)
		)
		(property "Device Type" "CAPACITOR-G105-0B104-CK,0.1UF,A"
			(at 0.0508 1.127506 90)
			(unlocked yes)
			(layer "F.Fab")
			(hide yes)
			(effects
				(font
					(size 0.7874 0.5842)
					(thickness 0.1524)
				)
			)
		)
		(property "User Part Number" "PARTNUM*"
			(at 0.1016 4.023106 90)
			(unlocked yes)
			(layer "Cmts.User")
			(hide yes)
			(effects
				(font
					(size 0.7874 0.5842)
					(thickness 0.1524)
				)
			)
		)
		(property "Tolerance" "TOL*"
			(at 0.0762 3.032506 90)
			(unlocked yes)
			(layer "Cmts.User")
			(hide yes)
			(effects
				(font
					(size 0.7874 0.5842)
					(thickness 0.1524)
				)
			)
		)
		(duplicate_pad_numbers_are_jumpers no)
		(fp_line
			(start 1.143 -0.5588)
			(end -1.143 -0.5588)
			(stroke
				(width 0.1)
				(type default)
			)
			(layer "F.SilkS")
		)
		(fp_line
			(start -1.143 -0.5588)
			(end -1.143 0.5588)
			(stroke
				(width 0.1)
				(type default)
			)
			(layer "F.SilkS")
		)
		(fp_line
			(start 1.143 0.5588)
			(end 1.143 -0.5588)
			(stroke
				(width 0.1)
				(type default)
			)
			(layer "F.SilkS")
		)
		(fp_line
			(start -1.143 0.5588)
			(end 1.143 0.5588)
			(stroke
				(width 0.1)
				(type default)
			)
			(layer "F.SilkS")
		)
		(fp_rect
			(start 1.143 -0.5588)
			(end -1.143 0.5588)
			(stroke
				(width 0)
				(type default)
			)
			(fill no)
			(layer "F.CrtYd")
		)
		(fp_line
			(start 0.508 -0.3048)
			(end -0.508 -0.3048)
			(stroke
				(width 0.1)
				(type default)
			)
			(layer "F.Fab")
		)
		(fp_line
			(start -0.508 -0.3048)
			(end -0.508 0.3048)
			(stroke
				(width 0.1)
				(type default)
			)
			(layer "F.Fab")
		)
		(fp_line
			(start 0.508 0.3048)
			(end 0.508 -0.3048)
			(stroke
				(width 0.1)
				(type default)
			)
			(layer "F.Fab")
		)
		(fp_line
			(start -0.508 0.3048)
			(end 0.508 0.3048)
			(stroke
				(width 0.1)
				(type default)
			)
			(layer "F.Fab")
		)
		(pad "1" smd rect
			(at -0.5334 0 90)
			(size 0.7112 0.6096)
			(layers "F.Cu" "F.Mask" "F.Paste")
			(net "OSC_200M_CLKP")
		)
		(pad "2" smd rect
			(at 0.5334 0 90)
			(size 0.7112 0.6096)
			(layers "F.Cu" "F.Mask" "F.Paste")
			(net "MHZ200CLKP_CLKIN")
		)
		(zone
			(layer "F.Cu")
			(hatch none 0.5)
			(connect_pads
				(clearance 0)
			)
			(min_thickness 0.25)
			(keepout
				(tracks allowed)
				(vias not_allowed)
				(pads allowed)
				(copperpour not_allowed)
				(footprints allowed)
			)
			(placement
				(enabled no)
				(sheetname "")
			)
			(fill
				(thermal_gap 0.5)
				(thermal_bridge_width 0.5)
				(island_removal_mode 0)
			)
			(polygon
				(pts
					(xy 111.8108 -26.797) (xy 111.8108 -26.6446) (xy 112.4204 -26.6446) (xy 112.4204 -26.797)
				)
			)
		)
	)
	(footprint ""
		(layer "F.Cu")
		(at 92.372942 -59.3344 -90)
		(property "Reference" "C47"
			(at 2.29235 -0.337058 0)
			(unlocked yes)
			(layer "F.SilkS")
			(effects
				(font
					(size 0.635 0.4064)
					(thickness 0.1524)
				)
			)
		)
		(property "Value" "VAL*"
			(at 0.193548 2.13614 270)
			(unlocked yes)
			(layer "F.Fab")
			(hide yes)
			(effects
				(font
					(size 0.7874 0.5842)
					(thickness 0.1524)
				)
			)
		)
		(property "Tolerance" "TOL*"
			(at 0.216154 3.1496 270)
			(unlocked yes)
			(layer "Cmts.User")
			(hide yes)
			(effects
				(font
					(size 0.7874 0.5842)
					(thickness 0.1524)
				)
			)
		)
		(property "Device Type" "CAPACITOR-G104-0A120-FJ,12PF,5%"
			(at 0.184404 1.180592 270)
			(unlocked yes)
			(layer "F.Fab")
			(hide yes)
			(effects
				(font
					(size 0.7874 0.5842)
					(thickness 0.1524)
				)
			)
		)
		(property "User Part Number" "PARTNUM*"
			(at 0.216154 4.185666 270)
			(unlocked yes)
			(layer "Cmts.User")
			(hide yes)
			(effects
				(font
					(size 0.7874 0.5842)
					(thickness 0.1524)
				)
			)
		)
		(duplicate_pad_numbers_are_jumpers no)
		(fp_line
			(start -0.671322 0.4445)
			(end -0.671322 -0.4445)
			(stroke
				(width 0.1)
				(type default)
			)
			(layer "F.SilkS")
		)
		(fp_line
			(start 0.671322 0.4445)
			(end -0.671322 0.4445)
			(stroke
				(width 0.1)
				(type default)
			)
			(layer "F.SilkS")
		)
		(fp_line
			(start -0.671322 -0.4445)
			(end 0.671322 -0.4445)
			(stroke
				(width 0.1)
				(type default)
			)
			(layer "F.SilkS")
		)
		(fp_line
			(start 0.671322 -0.4445)
			(end 0.671322 0.4445)
			(stroke
				(width 0.1)
				(type default)
			)
			(layer "F.SilkS")
		)
		(fp_rect
			(start 0.671322 0.4445)
			(end -0.671322 -0.4445)
			(stroke
				(width 0)
				(type default)
			)
			(fill no)
			(layer "F.CrtYd")
		)
		(fp_line
			(start -0.31496 0.1651)
			(end 0.31496 0.1651)
			(stroke
				(width 0.1)
				(type default)
			)
			(layer "F.Fab")
		)
		(fp_line
			(start 0.31496 0.1651)
			(end 0.31496 -0.1651)
			(stroke
				(width 0.1)
				(type default)
			)
			(layer "F.Fab")
		)
		(fp_line
			(start -0.31496 -0.1651)
			(end -0.31496 0.1651)
			(stroke
				(width 0.1)
				(type default)
			)
			(layer "F.Fab")
		)
		(fp_line
			(start 0.31496 -0.1651)
			(end -0.31496 -0.1651)
			(stroke
				(width 0.1)
				(type default)
			)
			(layer "F.Fab")
		)
		(pad "1" smd rect
			(at -0.264922 0 270)
			(size 0.3048 0.381)
			(layers "F.Cu" "F.Mask" "F.Paste")
			(net "UNNAMED_9_BNO080LGA28_I29_XOUT3")
		)
		(pad "2" smd rect
			(at 0.264922 0 270)
			(size 0.3048 0.381)
			(layers "F.Cu" "F.Mask" "F.Paste")
			(net "SG")
		)
		(zone
			(layer "F.Cu")
			(hatch none 0.5)
			(connect_pads
				(clearance 0)
			)
			(min_thickness 0.25)
			(keepout
				(tracks allowed)
				(vias not_allowed)
				(pads allowed)
				(copperpour not_allowed)
				(footprints allowed)
			)
			(placement
				(enabled no)
				(sheetname "")
			)
			(fill
				(thermal_gap 0.5)
				(thermal_bridge_width 0.5)
				(island_removal_mode 0)
			)
			(polygon
				(pts
					(xy 92.182442 -59.221878) (xy 92.563442 -59.221878) (xy 92.563442 -59.446922) (xy 92.182442 -59.446922)
				)
			)
		)
	)
	(footprint ""
		(layer "F.Cu")
		(at 80.772 -59.5376 180)
		(property "Reference" "R301"
			(at 10.287 19.51863 0)
			(unlocked yes)
			(layer "F.SilkS")
			(effects
				(font
					(size 0.7874 0.5842)
					(thickness 0.1524)
				)
			)
		)
		(property "Value" "VAL*"
			(at 0.02032 2.13233 180)
			(unlocked yes)
			(layer "F.Fab")
			(hide yes)
			(effects
				(font
					(size 0.7874 0.5842)
					(thickness 0.1524)
				)
			)
		)
		(property "Tolerance" "TOL*"
			(at 0.044704 3.05435 180)
			(unlocked yes)
			(layer "Cmts.User")
			(hide yes)
			(effects
				(font
					(size 0.7874 0.5842)
					(thickness 0.1524)
				)
			)
		)
		(property "User Part Number" "PARTNUM*"
			(at 0.02032 4.024884 180)
			(unlocked yes)
			(layer "Cmts.User")
			(hide yes)
			(effects
				(font
					(size 0.7874 0.5842)
					(thickness 0.1524)
				)
			)
		)
		(property "Device Type" "RESISTOR-G155-14701-01,4.7KOHMA"
			(at 0.008382 1.210564 180)
			(unlocked yes)
			(layer "F.Fab")
			(hide yes)
			(effects
				(font
					(size 0.7874 0.5842)
					(thickness 0.1524)
				)
			)
		)
		(duplicate_pad_numbers_are_jumpers no)
		(fp_line
			(start 1.143 0.5588)
			(end 1.143 -0.5588)
			(stroke
				(width 0.1)
				(type default)
			)
			(layer "F.SilkS")
		)
		(fp_line
			(start 1.143 -0.5588)
			(end -1.143 -0.5588)
			(stroke
				(width 0.1)
				(type default)
			)
			(layer "F.SilkS")
		)
		(fp_line
			(start -1.143 0.5588)
			(end 1.143 0.5588)
			(stroke
				(width 0.1)
				(type default)
			)
			(layer "F.SilkS")
		)
		(fp_line
			(start -1.143 -0.5588)
			(end -1.143 0.5588)
			(stroke
				(width 0.1)
				(type default)
			)
			(layer "F.SilkS")
		)
		(fp_rect
			(start 1.143 0.5588)
			(end -1.143 -0.5588)
			(stroke
				(width 0)
				(type default)
			)
			(fill no)
			(layer "F.CrtYd")
		)
		(fp_line
			(start 0.508 0.3048)
			(end 0.508 -0.3048)
			(stroke
				(width 0.1)
				(type default)
			)
			(layer "F.Fab")
		)
		(fp_line
			(start 0.508 -0.3048)
			(end -0.508 -0.3048)
			(stroke
				(width 0.1)
				(type default)
			)
			(layer "F.Fab")
		)
		(fp_line
			(start -0.508 0.3048)
			(end 0.508 0.3048)
			(stroke
				(width 0.1)
				(type default)
			)
			(layer "F.Fab")
		)
		(fp_line
			(start -0.508 -0.3048)
			(end -0.508 0.3048)
			(stroke
				(width 0.1)
				(type default)
			)
			(layer "F.Fab")
		)
		(pad "1" smd rect
			(at -0.5334 0 180)
			(size 0.7112 0.6096)
			(layers "F.Cu" "F.Mask" "F.Paste")
			(net "R_BNO080_RST_N")
		)
		(pad "2" smd rect
			(at 0.5334 0 180)
			(size 0.7112 0.6096)
			(layers "F.Cu" "F.Mask" "F.Paste")
			(net "SG")
		)
		(zone
			(layer "F.Cu")
			(hatch none 0.5)
			(connect_pads
				(clearance 0)
			)
			(min_thickness 0.25)
			(keepout
				(tracks allowed)
				(vias not_allowed)
				(pads allowed)
				(copperpour not_allowed)
				(footprints allowed)
			)
			(placement
				(enabled no)
				(sheetname "")
			)
			(fill
				(thermal_gap 0.5)
				(thermal_bridge_width 0.5)
				(island_removal_mode 0)
			)
			(polygon
				(pts
					(xy 80.6958 -59.8424) (xy 80.6958 -59.2328) (xy 80.8482 -59.2328) (xy 80.8482 -59.8424)
				)
			)
		)
	)
	(footprint ""
		(layer "F.Cu")
		(at 65.000124 -78.650084)
		(property "Reference" "ME2"
			(at -0.928624 -4.368546 0)
			(unlocked yes)
			(layer "F.SilkS")
			(effects
				(font
					(size 0.7874 0.5842)
					(thickness 0.1524)
				)
				(justify left)
			)
		)
		(property "Value" ""
			(at 0 0 0)
			(layer "F.Fab")
			(effects
				(font
					(size 1.27 1.27)
				)
			)
		)
		(property "User Part Number" "PARTNUM*"
			(at -3.048 5.242306 0)
			(unlocked yes)
			(layer "Cmts.User")
			(hide yes)
			(effects
				(font
					(size 0.7874 0.5842)
					(thickness 0.1524)
				)
				(justify left)
			)
		)
		(property "Device Type" "NUT-G340-10437-01"
			(at -1.4732 4.226306 0)
			(unlocked yes)
			(layer "F.Fab")
			(hide yes)
			(effects
				(font
					(size 0.7874 0.5842)
					(thickness 0.1524)
				)
				(justify left)
			)
		)
		(duplicate_pad_numbers_are_jumpers no)
		(fp_circle
			(center 0 0)
			(end 3.3528 0)
			(stroke
				(width 0.1)
				(type default)
			)
			(fill no)
			(layer "F.SilkS")
		)
		(fp_poly
			(pts
				(arc
					(start -2.102612 -0.1524)
					(mid -1.490671 -1.490671)
					(end -0.1524 -2.102612)
				)
				(arc
					(start -0.1524 -3.171444)
					(mid -2.245137 -2.245137)
					(end -3.171444 -0.1524)
				)
			)
			(stroke
				(width 0)
				(type default)
			)
			(fill yes)
			(layer "F.Paste")
		)
		(fp_poly
			(pts
				(arc
					(start -0.1524 2.102612)
					(mid -1.490671 1.490671)
					(end -2.102612 0.1524)
				)
				(arc
					(start -3.171444 0.1524)
					(mid -2.245137 2.245137)
					(end -0.1524 3.171444)
				)
			)
			(stroke
				(width 0)
				(type default)
			)
			(fill yes)
			(layer "F.Paste")
		)
		(fp_poly
			(pts
				(arc
					(start 0.1524 -2.102612)
					(mid 1.490671 -1.490671)
					(end 2.102612 -0.1524)
				)
				(arc
					(start 3.171444 -0.1524)
					(mid 2.245137 -2.245137)
					(end 0.1524 -3.171444)
				)
			)
			(stroke
				(width 0)
				(type default)
			)
			(fill yes)
			(layer "F.Paste")
		)
		(fp_poly
			(pts
				(arc
					(start 2.102612 0.1524)
					(mid 1.490671 1.490671)
					(end 0.1524 2.102612)
				)
				(arc
					(start 0.1524 3.171444)
					(mid 2.245137 2.245137)
					(end 3.171444 0.1524)
				)
			)
			(stroke
				(width 0)
				(type default)
			)
			(fill yes)
			(layer "F.Paste")
		)
		(fp_rect
			(start -7.5946 7.5946)
			(end 7.5946 -7.5946)
			(stroke
				(width 0)
				(type default)
			)
			(fill no)
			(layer "B.CrtYd")
		)
		(fp_poly
			(pts
				(arc
					(start 3.6068 0)
					(mid -3.6068 0)
					(end 3.6068 0)
				)
			)
			(stroke
				(width 0)
				(type default)
			)
			(fill no)
			(layer "F.CrtYd")
		)
		(fp_circle
			(center 0 0)
			(end 2.8448 0)
			(stroke
				(width 0.1)
				(type default)
			)
			(fill no)
			(layer "F.Fab")
		)
		(pad "1" thru_hole circle
			(at 0 0)
			(size 6.1976 6.1976)
			(drill 4.2164)
			(layers "*.Cu" "*.Mask")
			(remove_unused_layers no)
			(net "SG")
			(padstack
				(mode front_inner_back)
				(layer "Inner"
					(shape circle)
					(size 5.0292 5.0292)
					(clearance -0.1143)
				)
				(layer "B.Cu"
					(shape circle)
					(size 5.0292 5.0292)
				)
			)
		)
	)
	(footprint ""
		(layer "F.Cu")
		(at 142.24 -101.854)
		(property "Reference" "TP36"
			(at 0.4826 0.15875 0)
			(unlocked yes)
			(layer "F.SilkS")
			(effects
				(font
					(size 0.635 0.4064)
					(thickness 0.1524)
				)
				(justify left)
			)
		)
		(property "Value" ""
			(at 0 0 0)
			(layer "F.Fab")
			(effects
				(font
					(size 1.27 1.27)
				)
			)
		)
		(property "Device Type" "TP_PIONT-TP010CT020B030_PTH-TPA"
			(at -1.341882 0.996696 0)
			(unlocked yes)
			(layer "F.Fab")
			(hide yes)
			(effects
				(font
					(size 0.7874 0.5842)
					(thickness 0.000001)
				)
				(justify left)
			)
		)
		(duplicate_pad_numbers_are_jumpers no)
		(fp_poly
			(pts
				(arc
					(start 0.889 0)
					(mid -0.889 0)
					(end 0.889 0)
				)
			)
			(stroke
				(width 0)
				(type default)
			)
			(fill no)
			(layer "B.CrtYd")
		)
		(fp_poly
			(pts
				(arc
					(start 0.889 0)
					(mid -0.889 0)
					(end 0.889 0)
				)
			)
			(stroke
				(width 0)
				(type default)
			)
			(fill no)
			(layer "F.CrtYd")
		)
		(pad "1" thru_hole circle
			(at 0 0)
			(size 0.508 0.508)
			(drill 0.254)
			(layers "*.Cu" "*.Mask")
			(remove_unused_layers no)
			(net "XP12R0V_A_PG")
			(clearance 0.1016)
			(padstack
				(mode front_inner_back)
				(layer "Inner"
					(shape circle)
					(size 0.508 0.508)
					(clearance 0.1016)
				)
				(layer "B.Cu"
					(shape circle)
					(size 0.762 0.762)
					(clearance -0.0254)
				)
			)
		)
	)
	(footprint ""
		(layer "F.Cu")
		(at 111.125 -99.441 180)
		(property "Reference" "R324"
			(at -3.302 3.13563 0)
			(unlocked yes)
			(layer "F.SilkS")
			(effects
				(font
					(size 0.7874 0.5842)
					(thickness 0.1524)
				)
			)
		)
		(property "Value" "VAL*"
			(at 0.02032 2.13233 180)
			(unlocked yes)
			(layer "F.Fab")
			(hide yes)
			(effects
				(font
					(size 0.7874 0.5842)
					(thickness 0.1524)
				)
			)
		)
		(property "Tolerance" "TOL*"
			(at 0.044704 3.05435 180)
			(unlocked yes)
			(layer "Cmts.User")
			(hide yes)
			(effects
				(font
					(size 0.7874 0.5842)
					(thickness 0.1524)
				)
			)
		)
		(property "User Part Number" "PARTNUM*"
			(at 0.02032 4.024884 180)
			(unlocked yes)
			(layer "Cmts.User")
			(hide yes)
			(effects
				(font
					(size 0.7874 0.5842)
					(thickness 0.1524)
				)
			)
		)
		(property "Device Type" "RESISTOR-G155-100R0-J0,0OHM,-"
			(at 0.008382 1.210564 180)
			(unlocked yes)
			(layer "F.Fab")
			(hide yes)
			(effects
				(font
					(size 0.7874 0.5842)
					(thickness 0.1524)
				)
			)
		)
		(duplicate_pad_numbers_are_jumpers no)
		(fp_line
			(start 1.143 0.5588)
			(end 1.143 -0.5588)
			(stroke
				(width 0.1)
				(type default)
			)
			(layer "F.SilkS")
		)
		(fp_line
			(start 1.143 -0.5588)
			(end -1.143 -0.5588)
			(stroke
				(width 0.1)
				(type default)
			)
			(layer "F.SilkS")
		)
		(fp_line
			(start -1.143 0.5588)
			(end 1.143 0.5588)
			(stroke
				(width 0.1)
				(type default)
			)
			(layer "F.SilkS")
		)
		(fp_line
			(start -1.143 -0.5588)
			(end -1.143 0.5588)
			(stroke
				(width 0.1)
				(type default)
			)
			(layer "F.SilkS")
		)
		(fp_poly
			(pts
				(xy -1.143 0.5588) (xy 1.143 0.5588) (xy 1.143 -0.5588) (xy -1.143 -0.5588)
			)
			(stroke
				(width 0)
				(type default)
			)
			(fill no)
			(layer "F.CrtYd")
		)
		(fp_line
			(start 0.508 0.3048)
			(end 0.508 -0.3048)
			(stroke
				(width 0.1)
				(type default)
			)
			(layer "F.Fab")
		)
		(fp_line
			(start 0.508 -0.3048)
			(end -0.508 -0.3048)
			(stroke
				(width 0.1)
				(type default)
			)
			(layer "F.Fab")
		)
		(fp_line
			(start -0.508 0.3048)
			(end 0.508 0.3048)
			(stroke
				(width 0.1)
				(type default)
			)
			(layer "F.Fab")
		)
		(fp_line
			(start -0.508 -0.3048)
			(end -0.508 0.3048)
			(stroke
				(width 0.1)
				(type default)
			)
			(layer "F.Fab")
		)
		(pad "1" smd rect
			(at -0.5334 0 180)
			(size 0.7112 0.6096)
			(layers "F.Cu" "F.Mask" "F.Paste")
			(net "SG")
		)
		(pad "2" smd rect
			(at 0.5334 0 180)
			(size 0.7112 0.6096)
			(layers "F.Cu" "F.Mask" "F.Paste")
			(net "UNNAMED_14_IS32FL3207QWLA3TRQFN")
		)
		(zone
			(layer "F.Cu")
			(hatch none 0.5)
			(connect_pads
				(clearance 0)
			)
			(min_thickness 0.25)
			(keepout
				(tracks allowed)
				(vias not_allowed)
				(pads allowed)
				(copperpour not_allowed)
				(footprints allowed)
			)
			(placement
				(enabled no)
				(sheetname "")
			)
			(fill
				(thermal_gap 0.5)
				(thermal_bridge_width 0.5)
				(island_removal_mode 0)
			)
			(polygon
				(pts
					(xy 111.2012 -99.7458) (xy 111.0488 -99.7458) (xy 111.0488 -99.1362) (xy 111.2012 -99.1362)
				)
			)
		)
		(zone
			(layer "F.Cu")
			(hatch none 0.5)
			(connect_pads
				(clearance 0)
			)
			(min_thickness 0.25)
			(keepout
				(tracks not_allowed)
				(vias allowed)
				(pads allowed)
				(copperpour not_allowed)
				(footprints allowed)
			)
			(placement
				(enabled no)
				(sheetname "")
			)
			(fill
				(thermal_gap 0.5)
				(thermal_bridge_width 0.5)
				(island_removal_mode 0)
			)
			(polygon
				(pts
					(xy 111.2012 -99.7458) (xy 111.0488 -99.7458) (xy 111.0488 -99.1362) (xy 111.2012 -99.1362)
				)
			)
		)
	)
	(footprint ""
		(layer "F.Cu")
		(at 150.381462 -59.182 180)
		(property "Reference" "R298"
			(at 1.410462 3.89763 0)
			(unlocked yes)
			(layer "F.SilkS")
			(effects
				(font
					(size 0.7874 0.5842)
					(thickness 0.1524)
				)
			)
		)
		(property "Value" "VAL*"
			(at 0.02032 2.13233 180)
			(unlocked yes)
			(layer "F.Fab")
			(hide yes)
			(effects
				(font
					(size 0.7874 0.5842)
					(thickness 0.1524)
				)
			)
		)
		(property "Tolerance" "TOL*"
			(at 0.044704 3.05435 180)
			(unlocked yes)
			(layer "Cmts.User")
			(hide yes)
			(effects
				(font
					(size 0.7874 0.5842)
					(thickness 0.1524)
				)
			)
		)
		(property "User Part Number" "PARTNUM*"
			(at 0.02032 4.024884 180)
			(unlocked yes)
			(layer "Cmts.User")
			(hide yes)
			(effects
				(font
					(size 0.7874 0.5842)
					(thickness 0.1524)
				)
			)
		)
		(property "Device Type" "RESISTOR-G155-133R0-01,33OHM,1%"
			(at 0.008382 1.210564 180)
			(unlocked yes)
			(layer "F.Fab")
			(hide yes)
			(effects
				(font
					(size 0.7874 0.5842)
					(thickness 0.1524)
				)
			)
		)
		(duplicate_pad_numbers_are_jumpers no)
		(fp_line
			(start 1.143 0.5588)
			(end 1.143 -0.5588)
			(stroke
				(width 0.1)
				(type default)
			)
			(layer "F.SilkS")
		)
		(fp_line
			(start 1.143 -0.5588)
			(end -1.143 -0.5588)
			(stroke
				(width 0.1)
				(type default)
			)
			(layer "F.SilkS")
		)
		(fp_line
			(start -1.143 0.5588)
			(end 1.143 0.5588)
			(stroke
				(width 0.1)
				(type default)
			)
			(layer "F.SilkS")
		)
		(fp_line
			(start -1.143 -0.5588)
			(end -1.143 0.5588)
			(stroke
				(width 0.1)
				(type default)
			)
			(layer "F.SilkS")
		)
		(fp_rect
			(start -1.143 0.5588)
			(end 1.143 -0.5588)
			(stroke
				(width 0)
				(type default)
			)
			(fill no)
			(layer "F.CrtYd")
		)
		(fp_line
			(start 0.508 0.3048)
			(end 0.508 -0.3048)
			(stroke
				(width 0.1)
				(type default)
			)
			(layer "F.Fab")
		)
		(fp_line
			(start 0.508 -0.3048)
			(end -0.508 -0.3048)
			(stroke
				(width 0.1)
				(type default)
			)
			(layer "F.Fab")
		)
		(fp_line
			(start -0.508 0.3048)
			(end 0.508 0.3048)
			(stroke
				(width 0.1)
				(type default)
			)
			(layer "F.Fab")
		)
		(fp_line
			(start -0.508 -0.3048)
			(end -0.508 0.3048)
			(stroke
				(width 0.1)
				(type default)
			)
			(layer "F.Fab")
		)
		(pad "1" smd rect
			(at -0.5334 0 180)
			(size 0.7112 0.6096)
			(layers "F.Cu" "F.Mask" "F.Paste")
			(net "R_SHT3X_RST_N")
		)
		(pad "2" smd rect
			(at 0.5334 0 180)
			(size 0.7112 0.6096)
			(layers "F.Cu" "F.Mask" "F.Paste")
			(net "FPGA_OUT_SHT3X_RST_N")
		)
		(zone
			(layer "F.Cu")
			(hatch none 0.5)
			(connect_pads
				(clearance 0)
			)
			(min_thickness 0.25)
			(keepout
				(tracks allowed)
				(vias not_allowed)
				(pads allowed)
				(copperpour not_allowed)
				(footprints allowed)
			)
			(placement
				(enabled no)
				(sheetname "")
			)
			(fill
				(thermal_gap 0.5)
				(thermal_bridge_width 0.5)
				(island_removal_mode 0)
			)
			(polygon
				(pts
					(xy 150.457662 -59.4868) (xy 150.305262 -59.4868) (xy 150.305262 -58.8772) (xy 150.457662 -58.8772)
				)
			)
		)
	)
	(footprint ""
		(layer "F.Cu")
		(at 145.8214 -95.4278 180)
		(property "Reference" "R46"
			(at -0.127 -8.92937 0)
			(unlocked yes)
			(layer "F.SilkS")
			(effects
				(font
					(size 0.7874 0.5842)
					(thickness 0.1524)
				)
			)
		)
		(property "Value" "VAL*"
			(at 0.02032 2.13233 180)
			(unlocked yes)
			(layer "F.Fab")
			(hide yes)
			(effects
				(font
					(size 0.7874 0.5842)
					(thickness 0.1524)
				)
			)
		)
		(property "Device Type" "RESISTOR-G155-02672-01,26.7K,1%"
			(at 0.008382 1.210564 180)
			(unlocked yes)
			(layer "F.Fab")
			(hide yes)
			(effects
				(font
					(size 0.7874 0.5842)
					(thickness 0.1524)
				)
			)
		)
		(property "User Part Number" "PARTNUM*"
			(at 0.02032 4.024884 180)
			(unlocked yes)
			(layer "Cmts.User")
			(hide yes)
			(effects
				(font
					(size 0.7874 0.5842)
					(thickness 0.1524)
				)
			)
		)
		(property "Tolerance" "TOL*"
			(at 0.044704 3.05435 180)
			(unlocked yes)
			(layer "Cmts.User")
			(hide yes)
			(effects
				(font
					(size 0.7874 0.5842)
					(thickness 0.1524)
				)
			)
		)
		(duplicate_pad_numbers_are_jumpers no)
		(fp_line
			(start 1.143 0.5588)
			(end 1.143 -0.5588)
			(stroke
				(width 0.1)
				(type default)
			)
			(layer "F.SilkS")
		)
		(fp_line
			(start 1.143 -0.5588)
			(end -1.143 -0.5588)
			(stroke
				(width 0.1)
				(type default)
			)
			(layer "F.SilkS")
		)
		(fp_line
			(start -1.143 0.5588)
			(end 1.143 0.5588)
			(stroke
				(width 0.1)
				(type default)
			)
			(layer "F.SilkS")
		)
		(fp_line
			(start -1.143 -0.5588)
			(end -1.143 0.5588)
			(stroke
				(width 0.1)
				(type default)
			)
			(layer "F.SilkS")
		)
		(fp_rect
			(start 1.143 -0.5588)
			(end -1.143 0.5588)
			(stroke
				(width 0)
				(type default)
			)
			(fill no)
			(layer "F.CrtYd")
		)
		(fp_line
			(start 0.508 0.3048)
			(end 0.508 -0.3048)
			(stroke
				(width 0.1)
				(type default)
			)
			(layer "F.Fab")
		)
		(fp_line
			(start 0.508 -0.3048)
			(end -0.508 -0.3048)
			(stroke
				(width 0.1)
				(type default)
			)
			(layer "F.Fab")
		)
		(fp_line
			(start -0.508 0.3048)
			(end 0.508 0.3048)
			(stroke
				(width 0.1)
				(type default)
			)
			(layer "F.Fab")
		)
		(fp_line
			(start -0.508 -0.3048)
			(end -0.508 0.3048)
			(stroke
				(width 0.1)
				(type default)
			)
			(layer "F.Fab")
		)
		(pad "1" smd rect
			(at -0.5334 0 180)
			(size 0.7112 0.6096)
			(layers "F.Cu" "F.Mask" "F.Paste")
			(net "SG")
		)
		(pad "2" smd rect
			(at 0.5334 0 180)
			(size 0.7112 0.6096)
			(layers "F.Cu" "F.Mask" "F.Paste")
			(net "XP12R0V_A_ISET")
		)
		(zone
			(layer "F.Cu")
			(hatch none 0.5)
			(connect_pads
				(clearance 0)
			)
			(min_thickness 0.25)
			(keepout
				(tracks allowed)
				(vias not_allowed)
				(pads allowed)
				(copperpour not_allowed)
				(footprints allowed)
			)
			(placement
				(enabled no)
				(sheetname "")
			)
			(fill
				(thermal_gap 0.5)
				(thermal_bridge_width 0.5)
				(island_removal_mode 0)
			)
			(polygon
				(pts
					(xy 145.7452 -95.123) (xy 145.8976 -95.123) (xy 145.8976 -95.7326) (xy 145.7452 -95.7326)
				)
			)
		)
	)
	(footprint ""
		(layer "F.Cu")
		(at 96.4438 -72.898 90)
		(property "Reference" "C196"
			(at 19.05 -27.82443 90)
			(unlocked yes)
			(layer "F.SilkS")
			(effects
				(font
					(size 0.7874 0.5842)
					(thickness 0.1524)
				)
			)
		)
		(property "Value" "VAL*"
			(at 0.0762 2.067306 90)
			(unlocked yes)
			(layer "F.Fab")
			(hide yes)
			(effects
				(font
					(size 0.7874 0.5842)
					(thickness 0.1524)
				)
			)
		)
		(property "Tolerance" "TOL*"
			(at 0.0762 3.032506 90)
			(unlocked yes)
			(layer "Cmts.User")
			(hide yes)
			(effects
				(font
					(size 0.7874 0.5842)
					(thickness 0.1524)
				)
			)
		)
		(property "User Part Number" "PARTNUM*"
			(at 0.1016 4.023106 90)
			(unlocked yes)
			(layer "Cmts.User")
			(hide yes)
			(effects
				(font
					(size 0.7874 0.5842)
					(thickness 0.1524)
				)
			)
		)
		(property "Device Type" "CAPACITOR-G105-0B104-EK,0.1UF,A"
			(at 0.0508 1.127506 90)
			(unlocked yes)
			(layer "F.Fab")
			(hide yes)
			(effects
				(font
					(size 0.7874 0.5842)
					(thickness 0.1524)
				)
			)
		)
		(duplicate_pad_numbers_are_jumpers no)
		(fp_line
			(start 1.143 -0.5588)
			(end -1.143 -0.5588)
			(stroke
				(width 0.1)
				(type default)
			)
			(layer "F.SilkS")
		)
		(fp_line
			(start -1.143 -0.5588)
			(end -1.143 0.5588)
			(stroke
				(width 0.1)
				(type default)
			)
			(layer "F.SilkS")
		)
		(fp_line
			(start 1.143 0.5588)
			(end 1.143 -0.5588)
			(stroke
				(width 0.1)
				(type default)
			)
			(layer "F.SilkS")
		)
		(fp_line
			(start -1.143 0.5588)
			(end 1.143 0.5588)
			(stroke
				(width 0.1)
				(type default)
			)
			(layer "F.SilkS")
		)
		(fp_rect
			(start 1.143 -0.5588)
			(end -1.143 0.5588)
			(stroke
				(width 0)
				(type default)
			)
			(fill no)
			(layer "F.CrtYd")
		)
		(fp_line
			(start 0.508 -0.3048)
			(end -0.508 -0.3048)
			(stroke
				(width 0.1)
				(type default)
			)
			(layer "F.Fab")
		)
		(fp_line
			(start -0.508 -0.3048)
			(end -0.508 0.3048)
			(stroke
				(width 0.1)
				(type default)
			)
			(layer "F.Fab")
		)
		(fp_line
			(start 0.508 0.3048)
			(end 0.508 -0.3048)
			(stroke
				(width 0.1)
				(type default)
			)
			(layer "F.Fab")
		)
		(fp_line
			(start -0.508 0.3048)
			(end 0.508 0.3048)
			(stroke
				(width 0.1)
				(type default)
			)
			(layer "F.Fab")
		)
		(pad "1" smd rect
			(at -0.5334 0 90)
			(size 0.7112 0.6096)
			(layers "F.Cu" "F.Mask" "F.Paste")
			(net "XP1R2V_FPGA")
		)
		(pad "2" smd rect
			(at 0.5334 0 90)
			(size 0.7112 0.6096)
			(layers "F.Cu" "F.Mask" "F.Paste")
			(net "SG")
		)
		(zone
			(layer "F.Cu")
			(hatch none 0.5)
			(connect_pads
				(clearance 0)
			)
			(min_thickness 0.25)
			(keepout
				(tracks allowed)
				(vias not_allowed)
				(pads allowed)
				(copperpour not_allowed)
				(footprints allowed)
			)
			(placement
				(enabled no)
				(sheetname "")
			)
			(fill
				(thermal_gap 0.5)
				(thermal_bridge_width 0.5)
				(island_removal_mode 0)
			)
			(polygon
				(pts
					(xy 96.139 -72.9742) (xy 96.139 -72.8218) (xy 96.7486 -72.8218) (xy 96.7486 -72.9742)
				)
			)
		)
	)
	(footprint ""
		(layer "F.Cu")
		(at 133.858 -20.828 180)
		(property "Reference" "R477"
			(at 0.127 5.29463 0)
			(unlocked yes)
			(layer "F.SilkS")
			(effects
				(font
					(size 0.7874 0.5842)
					(thickness 0.1524)
				)
			)
		)
		(property "Value" "VAL*"
			(at 0.02032 2.13233 180)
			(unlocked yes)
			(layer "F.Fab")
			(hide yes)
			(effects
				(font
					(size 0.7874 0.5842)
					(thickness 0.1524)
				)
			)
		)
		(property "Tolerance" "TOL*"
			(at 0.044704 3.05435 180)
			(unlocked yes)
			(layer "Cmts.User")
			(hide yes)
			(effects
				(font
					(size 0.7874 0.5842)
					(thickness 0.1524)
				)
			)
		)
		(property "User Part Number" "PARTNUM*"
			(at 0.02032 4.024884 180)
			(unlocked yes)
			(layer "Cmts.User")
			(hide yes)
			(effects
				(font
					(size 0.7874 0.5842)
					(thickness 0.1524)
				)
			)
		)
		(property "Device Type" "RESISTOR-G155-11003-01,100KOHMA"
			(at 0.008382 1.210564 180)
			(unlocked yes)
			(layer "F.Fab")
			(hide yes)
			(effects
				(font
					(size 0.7874 0.5842)
					(thickness 0.1524)
				)
			)
		)
		(duplicate_pad_numbers_are_jumpers no)
		(fp_line
			(start 1.143 0.5588)
			(end 1.143 -0.5588)
			(stroke
				(width 0.1)
				(type default)
			)
			(layer "F.SilkS")
		)
		(fp_line
			(start 1.143 -0.5588)
			(end -1.143 -0.5588)
			(stroke
				(width 0.1)
				(type default)
			)
			(layer "F.SilkS")
		)
		(fp_line
			(start -1.143 0.5588)
			(end 1.143 0.5588)
			(stroke
				(width 0.1)
				(type default)
			)
			(layer "F.SilkS")
		)
		(fp_line
			(start -1.143 -0.5588)
			(end -1.143 0.5588)
			(stroke
				(width 0.1)
				(type default)
			)
			(layer "F.SilkS")
		)
		(fp_poly
			(pts
				(xy -1.143 0.5588) (xy 1.143 0.5588) (xy 1.143 -0.5588) (xy -1.143 -0.5588)
			)
			(stroke
				(width 0)
				(type default)
			)
			(fill no)
			(layer "F.CrtYd")
		)
		(fp_line
			(start 0.508 0.3048)
			(end 0.508 -0.3048)
			(stroke
				(width 0.1)
				(type default)
			)
			(layer "F.Fab")
		)
		(fp_line
			(start 0.508 -0.3048)
			(end -0.508 -0.3048)
			(stroke
				(width 0.1)
				(type default)
			)
			(layer "F.Fab")
		)
		(fp_line
			(start -0.508 0.3048)
			(end 0.508 0.3048)
			(stroke
				(width 0.1)
				(type default)
			)
			(layer "F.Fab")
		)
		(fp_line
			(start -0.508 -0.3048)
			(end -0.508 0.3048)
			(stroke
				(width 0.1)
				(type default)
			)
			(layer "F.Fab")
		)
		(pad "1" smd rect
			(at -0.5334 0 180)
			(size 0.7112 0.6096)
			(layers "F.Cu" "F.Mask" "F.Paste")
			(net "XP3R3V_FPGA")
		)
		(pad "2" smd rect
			(at 0.5334 0 180)
			(size 0.7112 0.6096)
			(layers "F.Cu" "F.Mask" "F.Paste")
			(net "FPGA_EEPROM_I2C_SCL")
		)
		(zone
			(layer "F.Cu")
			(hatch none 0.5)
			(connect_pads
				(clearance 0)
			)
			(min_thickness 0.25)
			(keepout
				(tracks allowed)
				(vias not_allowed)
				(pads allowed)
				(copperpour not_allowed)
				(footprints allowed)
			)
			(placement
				(enabled no)
				(sheetname "")
			)
			(fill
				(thermal_gap 0.5)
				(thermal_bridge_width 0.5)
				(island_removal_mode 0)
			)
			(polygon
				(pts
					(xy 133.9342 -21.1328) (xy 133.7818 -21.1328) (xy 133.7818 -20.5232) (xy 133.9342 -20.5232)
				)
			)
		)
		(zone
			(layer "F.Cu")
			(hatch none 0.5)
			(connect_pads
				(clearance 0)
			)
			(min_thickness 0.25)
			(keepout
				(tracks not_allowed)
				(vias allowed)
				(pads allowed)
				(copperpour not_allowed)
				(footprints allowed)
			)
			(placement
				(enabled no)
				(sheetname "")
			)
			(fill
				(thermal_gap 0.5)
				(thermal_bridge_width 0.5)
				(island_removal_mode 0)
			)
			(polygon
				(pts
					(xy 133.9342 -21.1328) (xy 133.7818 -21.1328) (xy 133.7818 -20.5232) (xy 133.9342 -20.5232)
				)
			)
		)
	)
	(footprint ""
		(layer "F.Cu")
		(at 92.372942 -61.0108 90)
		(property "Reference" "C51"
			(at -2.95275 0.337058 0)
			(unlocked yes)
			(layer "F.SilkS")
			(effects
				(font
					(size 0.635 0.4064)
					(thickness 0.1524)
				)
			)
		)
		(property "Value" "VAL*"
			(at 0.193548 2.13614 90)
			(unlocked yes)
			(layer "F.Fab")
			(hide yes)
			(effects
				(font
					(size 0.7874 0.5842)
					(thickness 0.1524)
				)
			)
		)
		(property "Tolerance" "TOL*"
			(at 0.216154 3.1496 90)
			(unlocked yes)
			(layer "Cmts.User")
			(hide yes)
			(effects
				(font
					(size 0.7874 0.5842)
					(thickness 0.1524)
				)
			)
		)
		(property "Device Type" "CAPACITOR-G104-0A120-FJ,12PF,5%"
			(at 0.184404 1.180592 90)
			(unlocked yes)
			(layer "F.Fab")
			(hide yes)
			(effects
				(font
					(size 0.7874 0.5842)
					(thickness 0.1524)
				)
			)
		)
		(property "User Part Number" "PARTNUM*"
			(at 0.216154 4.185666 90)
			(unlocked yes)
			(layer "Cmts.User")
			(hide yes)
			(effects
				(font
					(size 0.7874 0.5842)
					(thickness 0.1524)
				)
			)
		)
		(duplicate_pad_numbers_are_jumpers no)
		(fp_line
			(start 0.671322 -0.4445)
			(end 0.671322 0.4445)
			(stroke
				(width 0.1)
				(type default)
			)
			(layer "F.SilkS")
		)
		(fp_line
			(start -0.671322 -0.4445)
			(end 0.671322 -0.4445)
			(stroke
				(width 0.1)
				(type default)
			)
			(layer "F.SilkS")
		)
		(fp_line
			(start 0.671322 0.4445)
			(end -0.671322 0.4445)
			(stroke
				(width 0.1)
				(type default)
			)
			(layer "F.SilkS")
		)
		(fp_line
			(start -0.671322 0.4445)
			(end -0.671322 -0.4445)
			(stroke
				(width 0.1)
				(type default)
			)
			(layer "F.SilkS")
		)
		(fp_rect
			(start -0.671322 -0.4445)
			(end 0.671322 0.4445)
			(stroke
				(width 0)
				(type default)
			)
			(fill no)
			(layer "F.CrtYd")
		)
		(fp_line
			(start 0.31496 -0.1651)
			(end -0.31496 -0.1651)
			(stroke
				(width 0.1)
				(type default)
			)
			(layer "F.Fab")
		)
		(fp_line
			(start -0.31496 -0.1651)
			(end -0.31496 0.1651)
			(stroke
				(width 0.1)
				(type default)
			)
			(layer "F.Fab")
		)
		(fp_line
			(start 0.31496 0.1651)
			(end 0.31496 -0.1651)
			(stroke
				(width 0.1)
				(type default)
			)
			(layer "F.Fab")
		)
		(fp_line
			(start -0.31496 0.1651)
			(end 0.31496 0.1651)
			(stroke
				(width 0.1)
				(type default)
			)
			(layer "F.Fab")
		)
		(pad "1" smd rect
			(at -0.264922 0 90)
			(size 0.3048 0.381)
			(layers "F.Cu" "F.Mask" "F.Paste")
			(net "UNNAMED_9_CAPACITOR_I17_1")
		)
		(pad "2" smd rect
			(at 0.264922 0 90)
			(size 0.3048 0.381)
			(layers "F.Cu" "F.Mask" "F.Paste")
			(net "SG")
		)
		(zone
			(layer "F.Cu")
			(hatch none 0.5)
			(connect_pads
				(clearance 0)
			)
			(min_thickness 0.25)
			(keepout
				(tracks allowed)
				(vias not_allowed)
				(pads allowed)
				(copperpour not_allowed)
				(footprints allowed)
			)
			(placement
				(enabled no)
				(sheetname "")
			)
			(fill
				(thermal_gap 0.5)
				(thermal_bridge_width 0.5)
				(island_removal_mode 0)
			)
			(polygon
				(pts
					(xy 92.182442 -60.898278) (xy 92.563442 -60.898278) (xy 92.563442 -61.123322) (xy 92.182442 -61.123322)
				)
			)
		)
	)
	(footprint ""
		(layer "F.Cu")
		(at 85.598 -87.376)
		(property "Reference" "TP21"
			(at -1.2192 -1.61163 0)
			(unlocked yes)
			(layer "F.SilkS")
			(effects
				(font
					(size 0.7874 0.5842)
					(thickness 0.1524)
				)
				(justify left)
			)
		)
		(property "Value" ""
			(at 0 0 0)
			(layer "F.Fab")
			(effects
				(font
					(size 1.27 1.27)
				)
			)
		)
		(property "Device Type" "TP_PIONT-TP010CT020B030_PTH-TPA"
			(at -1.341882 0.996696 0)
			(unlocked yes)
			(layer "F.Fab")
			(hide yes)
			(effects
				(font
					(size 0.7874 0.5842)
					(thickness 0.000001)
				)
				(justify left)
			)
		)
		(duplicate_pad_numbers_are_jumpers no)
		(fp_poly
			(pts
				(arc
					(start 0.889 0)
					(mid -0.889 0)
					(end 0.889 0)
				)
			)
			(stroke
				(width 0)
				(type default)
			)
			(fill no)
			(layer "B.CrtYd")
		)
		(fp_poly
			(pts
				(arc
					(start 0.889 0)
					(mid -0.889 0)
					(end 0.889 0)
				)
			)
			(stroke
				(width 0)
				(type default)
			)
			(fill no)
			(layer "F.CrtYd")
		)
		(pad "1" thru_hole circle
			(at 0 0)
			(size 0.508 0.508)
			(drill 0.254)
			(layers "*.Cu" "*.Mask")
			(remove_unused_layers no)
			(net "PCA9546_RST_N")
			(clearance 0.1016)
			(padstack
				(mode front_inner_back)
				(layer "Inner"
					(shape circle)
					(size 0.508 0.508)
					(clearance 0.1016)
				)
				(layer "B.Cu"
					(shape circle)
					(size 0.762 0.762)
					(clearance -0.0254)
				)
			)
		)
	)
	(footprint ""
		(layer "F.Cu")
		(at 57.277 -130.048)
		(property "Reference" "SP59"
			(at 0 0 0)
			(layer "F.SilkS")
			(hide yes)
			(effects
				(font
					(size 1.27 1.27)
				)
			)
		)
		(property "Value" ""
			(at 0 0 0)
			(layer "F.Fab")
			(effects
				(font
					(size 1.27 1.27)
				)
			)
		)
		(duplicate_pad_numbers_are_jumpers no)
	)
	(footprint ""
		(layer "F.Cu")
		(at 42.545 -123.19)
		(property "Reference" "SP22"
			(at 0 0 0)
			(layer "F.SilkS")
			(hide yes)
			(effects
				(font
					(size 1.27 1.27)
				)
			)
		)
		(property "Value" ""
			(at 0 0 0)
			(layer "F.Fab")
			(effects
				(font
					(size 1.27 1.27)
				)
			)
		)
		(duplicate_pad_numbers_are_jumpers no)
	)
	(footprint ""
		(layer "F.Cu")
		(at 141.732 -99.441)
		(property "Reference" "R14"
			(at 2.032 0.92075 0)
			(unlocked yes)
			(layer "F.SilkS")
			(effects
				(font
					(size 0.635 0.4064)
					(thickness 0.1524)
				)
			)
		)
		(property "Value" "VAL*"
			(at 0.0508 2.245106 0)
			(unlocked yes)
			(layer "F.Fab")
			(hide yes)
			(effects
				(font
					(size 0.7874 0.5842)
					(thickness 0.1524)
				)
			)
		)
		(property "Tolerance" "TOL*"
			(at 0.0508 3.261106 0)
			(unlocked yes)
			(layer "Cmts.User")
			(hide yes)
			(effects
				(font
					(size 0.7874 0.5842)
					(thickness 0.1524)
				)
			)
		)
		(property "Device Type" "RESISTOR-G155-03921-01,3.92KOHA"
			(at 0.0762 1.254506 0)
			(unlocked yes)
			(layer "F.Fab")
			(hide yes)
			(effects
				(font
					(size 0.7874 0.5842)
					(thickness 0.1524)
				)
			)
		)
		(property "User Part Number" "PARTNUM*"
			(at 0.0762 4.302506 0)
			(unlocked yes)
			(layer "Cmts.User")
			(hide yes)
			(effects
				(font
					(size 0.7874 0.5842)
					(thickness 0.1524)
				)
			)
		)
		(duplicate_pad_numbers_are_jumpers no)
		(fp_line
			(start -1.143 -0.5588)
			(end -1.143 0.5588)
			(stroke
				(width 0.1)
				(type default)
			)
			(layer "F.SilkS")
		)
		(fp_line
			(start -1.143 0.5588)
			(end 1.143 0.5588)
			(stroke
				(width 0.1)
				(type default)
			)
			(layer "F.SilkS")
		)
		(fp_line
			(start 1.143 -0.5588)
			(end -1.143 -0.5588)
			(stroke
				(width 0.1)
				(type default)
			)
			(layer "F.SilkS")
		)
		(fp_line
			(start 1.143 0.5588)
			(end 1.143 -0.5588)
			(stroke
				(width 0.1)
				(type default)
			)
			(layer "F.SilkS")
		)
		(fp_rect
			(start 1.143 -0.5588)
			(end -1.143 0.5588)
			(stroke
				(width 0)
				(type default)
			)
			(fill no)
			(layer "F.CrtYd")
		)
		(fp_line
			(start -0.508 -0.3048)
			(end -0.508 0.3048)
			(stroke
				(width 0.1)
				(type default)
			)
			(layer "F.Fab")
		)
		(fp_line
			(start -0.508 0.3048)
			(end 0.508 0.3048)
			(stroke
				(width 0.1)
				(type default)
			)
			(layer "F.Fab")
		)
		(fp_line
			(start 0.508 -0.3048)
			(end -0.508 -0.3048)
			(stroke
				(width 0.1)
				(type default)
			)
			(layer "F.Fab")
		)
		(fp_line
			(start 0.508 0.3048)
			(end 0.508 -0.3048)
			(stroke
				(width 0.1)
				(type default)
			)
			(layer "F.Fab")
		)
		(pad "1" smd rect
			(at -0.5334 0)
			(size 0.7112 0.6096)
			(layers "F.Cu" "F.Mask" "F.Paste")
			(net "XP12R0V_A_PG")
		)
		(pad "2" smd rect
			(at 0.5334 0)
			(size 0.7112 0.6096)
			(layers "F.Cu" "F.Mask" "F.Paste")
			(net "SG")
		)
		(zone
			(layer "F.Cu")
			(hatch none 0.5)
			(connect_pads
				(clearance 0)
			)
			(min_thickness 0.25)
			(keepout
				(tracks allowed)
				(vias not_allowed)
				(pads allowed)
				(copperpour not_allowed)
				(footprints allowed)
			)
			(placement
				(enabled no)
				(sheetname "")
			)
			(fill
				(thermal_gap 0.5)
				(thermal_bridge_width 0.5)
				(island_removal_mode 0)
			)
			(polygon
				(pts
					(xy 141.8082 -99.7458) (xy 141.6558 -99.7458) (xy 141.6558 -99.1362) (xy 141.8082 -99.1362)
				)
			)
		)
	)
	(footprint ""
		(layer "F.Cu")
		(at 115.062 -29.464 -90)
		(property "Reference" "R439"
			(at 2.794 -1.18237 90)
			(unlocked yes)
			(layer "F.SilkS")
			(effects
				(font
					(size 0.7874 0.5842)
					(thickness 0.1524)
				)
			)
		)
		(property "Value" "VAL*"
			(at 0.02032 2.13233 270)
			(unlocked yes)
			(layer "F.Fab")
			(hide yes)
			(effects
				(font
					(size 0.7874 0.5842)
					(thickness 0.1524)
				)
			)
		)
		(property "Tolerance" "TOL*"
			(at 0.044704 3.05435 270)
			(unlocked yes)
			(layer "Cmts.User")
			(hide yes)
			(effects
				(font
					(size 0.7874 0.5842)
					(thickness 0.1524)
				)
			)
		)
		(property "User Part Number" "PARTNUM*"
			(at 0.02032 4.024884 270)
			(unlocked yes)
			(layer "Cmts.User")
			(hide yes)
			(effects
				(font
					(size 0.7874 0.5842)
					(thickness 0.1524)
				)
			)
		)
		(property "Device Type" "RESISTOR-G155-11002-01,10KOHM,A"
			(at 0.008382 1.210564 270)
			(unlocked yes)
			(layer "F.Fab")
			(hide yes)
			(effects
				(font
					(size 0.7874 0.5842)
					(thickness 0.1524)
				)
			)
		)
		(duplicate_pad_numbers_are_jumpers no)
		(fp_line
			(start -1.143 0.5588)
			(end 1.143 0.5588)
			(stroke
				(width 0.1)
				(type default)
			)
			(layer "F.SilkS")
		)
		(fp_line
			(start 1.143 0.5588)
			(end 1.143 -0.5588)
			(stroke
				(width 0.1)
				(type default)
			)
			(layer "F.SilkS")
		)
		(fp_line
			(start -1.143 -0.5588)
			(end -1.143 0.5588)
			(stroke
				(width 0.1)
				(type default)
			)
			(layer "F.SilkS")
		)
		(fp_line
			(start 1.143 -0.5588)
			(end -1.143 -0.5588)
			(stroke
				(width 0.1)
				(type default)
			)
			(layer "F.SilkS")
		)
		(fp_poly
			(pts
				(xy -1.143 0.5588) (xy 1.143 0.5588) (xy 1.143 -0.5588) (xy -1.143 -0.5588)
			)
			(stroke
				(width 0)
				(type default)
			)
			(fill no)
			(layer "F.CrtYd")
		)
		(fp_line
			(start -0.508 0.3048)
			(end 0.508 0.3048)
			(stroke
				(width 0.1)
				(type default)
			)
			(layer "F.Fab")
		)
		(fp_line
			(start 0.508 0.3048)
			(end 0.508 -0.3048)
			(stroke
				(width 0.1)
				(type default)
			)
			(layer "F.Fab")
		)
		(fp_line
			(start -0.508 -0.3048)
			(end -0.508 0.3048)
			(stroke
				(width 0.1)
				(type default)
			)
			(layer "F.Fab")
		)
		(fp_line
			(start 0.508 -0.3048)
			(end -0.508 -0.3048)
			(stroke
				(width 0.1)
				(type default)
			)
			(layer "F.Fab")
		)
		(pad "1" smd rect
			(at -0.5334 0 270)
			(size 0.7112 0.6096)
			(layers "F.Cu" "F.Mask" "F.Paste")
			(net "FPGA_IN_MAC_PPS_OUTP")
		)
		(pad "2" smd rect
			(at 0.5334 0 270)
			(size 0.7112 0.6096)
			(layers "F.Cu" "F.Mask" "F.Paste")
			(net "XP2R5V_FPGA")
		)
		(zone
			(layer "F.Cu")
			(hatch none 0.5)
			(connect_pads
				(clearance 0)
			)
			(min_thickness 0.25)
			(keepout
				(tracks allowed)
				(vias not_allowed)
				(pads allowed)
				(copperpour not_allowed)
				(footprints allowed)
			)
			(placement
				(enabled no)
				(sheetname "")
			)
			(fill
				(thermal_gap 0.5)
				(thermal_bridge_width 0.5)
				(island_removal_mode 0)
			)
			(polygon
				(pts
					(xy 114.7572 -29.5402) (xy 114.7572 -29.3878) (xy 115.3668 -29.3878) (xy 115.3668 -29.5402)
				)
			)
		)
		(zone
			(layer "F.Cu")
			(hatch none 0.5)
			(connect_pads
				(clearance 0)
			)
			(min_thickness 0.25)
			(keepout
				(tracks not_allowed)
				(vias allowed)
				(pads allowed)
				(copperpour not_allowed)
				(footprints allowed)
			)
			(placement
				(enabled no)
				(sheetname "")
			)
			(fill
				(thermal_gap 0.5)
				(thermal_bridge_width 0.5)
				(island_removal_mode 0)
			)
			(polygon
				(pts
					(xy 114.7572 -29.5402) (xy 114.7572 -29.3878) (xy 115.3668 -29.3878) (xy 115.3668 -29.5402)
				)
			)
		)
	)
	(footprint ""
		(layer "F.Cu")
		(at 60.452 -123.952)
		(property "Reference" "SP29"
			(at 0 0 0)
			(layer "F.SilkS")
			(hide yes)
			(effects
				(font
					(size 1.27 1.27)
				)
			)
		)
		(property "Value" ""
			(at 0 0 0)
			(layer "F.Fab")
			(effects
				(font
					(size 1.27 1.27)
				)
			)
		)
		(duplicate_pad_numbers_are_jumpers no)
	)
	(footprint ""
		(layer "F.Cu")
		(at 147.32 -26.6192)
		(property "Reference" "TP22"
			(at -1.7272 -0.77343 0)
			(unlocked yes)
			(layer "F.SilkS")
			(effects
				(font
					(size 0.7874 0.5842)
					(thickness 0.1524)
				)
				(justify left)
			)
		)
		(property "Value" ""
			(at 0 0 0)
			(layer "F.Fab")
			(effects
				(font
					(size 1.27 1.27)
				)
			)
		)
		(property "Device Type" "TP_PIONT-TP010CT020B030_PTH-TPA"
			(at -1.341882 0.996696 0)
			(unlocked yes)
			(layer "F.Fab")
			(hide yes)
			(effects
				(font
					(size 0.7874 0.5842)
					(thickness 0.000001)
				)
				(justify left)
			)
		)
		(duplicate_pad_numbers_are_jumpers no)
		(fp_poly
			(pts
				(arc
					(start 0.889 0)
					(mid -0.889 0)
					(end 0.889 0)
				)
			)
			(stroke
				(width 0)
				(type default)
			)
			(fill no)
			(layer "B.CrtYd")
		)
		(fp_poly
			(pts
				(arc
					(start 0.889 0)
					(mid -0.889 0)
					(end 0.889 0)
				)
			)
			(stroke
				(width 0)
				(type default)
			)
			(fill no)
			(layer "F.CrtYd")
		)
		(pad "1" thru_hole circle
			(at 0 0)
			(size 0.508 0.508)
			(drill 0.254)
			(layers "*.Cu" "*.Mask")
			(remove_unused_layers no)
			(net "FPGA_IN_LM75B_INT3_N")
			(clearance 0.1016)
			(padstack
				(mode front_inner_back)
				(layer "Inner"
					(shape circle)
					(size 0.508 0.508)
					(clearance 0.1016)
				)
				(layer "B.Cu"
					(shape circle)
					(size 0.762 0.762)
					(clearance -0.0254)
				)
			)
		)
	)
	(footprint ""
		(layer "F.Cu")
		(at 97.282 -59.055 90)
		(property "Reference" "TP180"
			(at -2.9718 0.41275 90)
			(unlocked yes)
			(layer "F.SilkS")
			(effects
				(font
					(size 0.635 0.4064)
					(thickness 0.1524)
				)
				(justify left)
			)
		)
		(property "Value" ""
			(at 0 0 90)
			(layer "F.Fab")
			(effects
				(font
					(size 1.27 1.27)
				)
			)
		)
		(property "Device Type" "TP_PIONT-TP010CT020B030_PTH-TPA"
			(at -1.341882 0.996696 90)
			(unlocked yes)
			(layer "F.Fab")
			(hide yes)
			(effects
				(font
					(size 0.7874 0.5842)
					(thickness 0.1524)
				)
				(justify left)
			)
		)
		(duplicate_pad_numbers_are_jumpers no)
		(fp_poly
			(pts
				(arc
					(start 0 0.889)
					(mid 0 -0.889)
					(end 0 0.889)
				)
			)
			(stroke
				(width 0)
				(type default)
			)
			(fill no)
			(layer "B.CrtYd")
		)
		(fp_poly
			(pts
				(arc
					(start 0 0.889)
					(mid 0 -0.889)
					(end 0 0.889)
				)
			)
			(stroke
				(width 0)
				(type default)
			)
			(fill no)
			(layer "F.CrtYd")
		)
		(pad "1" thru_hole circle
			(at 0 0 90)
			(size 0.508 0.508)
			(drill 0.254)
			(layers "*.Cu" "*.Mask")
			(remove_unused_layers no)
			(net "IO_L20N_16")
			(clearance 0.1016)
			(padstack
				(mode front_inner_back)
				(layer "Inner"
					(shape circle)
					(size 0.508 0.508)
					(clearance 0.1016)
				)
				(layer "B.Cu"
					(shape circle)
					(size 0.762 0.762)
					(clearance -0.0254)
				)
			)
		)
	)
	(footprint ""
		(layer "F.Cu")
		(at 163.395406 -38.624002 90)
		(property "Reference" "J5"
			(at -0.524002 -14.258036 90)
			(unlocked yes)
			(layer "F.SilkS")
			(effects
				(font
					(size 0.7874 0.5842)
					(thickness 0.1524)
				)
			)
		)
		(property "Value" ""
			(at 0 0 90)
			(layer "F.Fab")
			(effects
				(font
					(size 1.27 1.27)
				)
			)
		)
		(property "Device Type" "CONN_HDR_2X6_F_S_SMT-G200-1313A"
			(at 0 5.682996 90)
			(unlocked yes)
			(layer "F.Fab")
			(hide yes)
			(effects
				(font
					(size 0.7874 0.5842)
					(thickness 0.000001)
				)
			)
		)
		(property "User Part Number" "PARTNUM*"
			(at 0 6.876796 90)
			(unlocked yes)
			(layer "Cmts.User")
			(hide yes)
			(effects
				(font
					(size 0.7874 0.5842)
					(thickness 0.000001)
				)
			)
		)
		(duplicate_pad_numbers_are_jumpers no)
		(fp_line
			(start 8.253984 -12.506706)
			(end 8.253984 4.574032)
			(stroke
				(width 0.1)
				(type default)
			)
			(layer "F.SilkS")
		)
		(fp_line
			(start -8.253984 -12.506706)
			(end 8.253984 -12.506706)
			(stroke
				(width 0.1)
				(type default)
			)
			(layer "F.SilkS")
		)
		(fp_line
			(start 8.253984 4.574032)
			(end -8.253984 4.574032)
			(stroke
				(width 0.1)
				(type default)
			)
			(layer "F.SilkS")
		)
		(fp_line
			(start -8.253984 4.574032)
			(end -8.253984 -12.506706)
			(stroke
				(width 0.1)
				(type default)
			)
			(layer "F.SilkS")
		)
		(fp_rect
			(start -8.507984 4.828032)
			(end 8.507984 -12.760706)
			(stroke
				(width 0)
				(type default)
			)
			(fill no)
			(layer "F.CrtYd")
		)
		(fp_line
			(start 7.999984 -4.320032)
			(end 7.999984 4.320032)
			(stroke
				(width 0.1)
				(type default)
			)
			(layer "F.Fab")
		)
		(fp_line
			(start -7.999984 -4.320032)
			(end 7.999984 -4.320032)
			(stroke
				(width 0.1)
				(type default)
			)
			(layer "F.Fab")
		)
		(fp_line
			(start 7.999984 4.320032)
			(end -7.999984 4.320032)
			(stroke
				(width 0.1)
				(type default)
			)
			(layer "F.Fab")
		)
		(fp_line
			(start -7.999984 4.320032)
			(end -7.999984 -4.320032)
			(stroke
				(width 0.1)
				(type default)
			)
			(layer "F.Fab")
		)
		(fp_text user "12"
			(at -6.786372 -14.170406 0)
			(unlocked yes)
			(layer "F.SilkS")
			(effects
				(font
					(size 0.7874 0.5842)
					(thickness 0.1524)
				)
			)
		)
		(fp_text user "2"
			(at 8.746998 -10.702036 90)
			(unlocked yes)
			(layer "F.SilkS")
			(effects
				(font
					(size 0.7874 0.5842)
					(thickness 0.1524)
				)
			)
		)
		(fp_text user "1"
			(at 8.492998 -7.527036 90)
			(unlocked yes)
			(layer "F.SilkS")
			(effects
				(font
					(size 0.7874 0.5842)
					(thickness 0.1524)
				)
			)
		)
		(fp_text user "11"
			(at -9.199372 -6.804406 0)
			(unlocked yes)
			(layer "F.SilkS")
			(effects
				(font
					(size 0.7874 0.5842)
					(thickness 0.1524)
				)
			)
		)
		(fp_text user "12"
			(at -8.310372 -12.392406 0)
			(unlocked yes)
			(layer "F.Fab")
			(effects
				(font
					(size 0.7874 0.5842)
					(thickness 0.1524)
				)
			)
		)
		(fp_text user "2"
			(at 8.326628 -11.884406 0)
			(unlocked yes)
			(layer "F.Fab")
			(effects
				(font
					(size 0.7874 0.5842)
					(thickness 0.1524)
				)
			)
		)
		(fp_text user "1"
			(at 8.580628 -6.296406 0)
			(unlocked yes)
			(layer "F.Fab")
			(effects
				(font
					(size 0.7874 0.5842)
					(thickness 0.1524)
				)
			)
		)
		(fp_text user "11"
			(at -8.437372 -5.915406 0)
			(unlocked yes)
			(layer "F.Fab")
			(effects
				(font
					(size 0.7874 0.5842)
					(thickness 0.1524)
				)
			)
		)
		(pad "1" smd rect
			(at 6.35 -7.274814 90)
			(size 1.4224 2.3368)
			(layers "F.Cu" "F.Mask" "F.Paste")
			(net "UNNAMED_16_CONNHDR2X6FSSMT_I161")
		)
		(pad "2" smd rect
			(at 6.35 -11.135106 90)
			(size 1.4224 2.2352)
			(layers "F.Cu" "F.Mask" "F.Paste")
			(net "UNNAMED_16_CONNHDR2X6FSSMT_I1_1")
		)
		(pad "3" smd rect
			(at 3.81 -7.274814 90)
			(size 1.4224 2.3368)
			(layers "F.Cu" "F.Mask" "F.Paste")
			(net "UNNAMED_16_CONNHDR2X6FSSMT_I1_2")
		)
		(pad "4" smd rect
			(at 3.81 -11.135106 90)
			(size 1.4224 2.2352)
			(layers "F.Cu" "F.Mask" "F.Paste")
			(net "UNNAMED_16_CONNHDR2X6FSSMT_I1_3")
		)
		(pad "5" smd rect
			(at 1.27 -7.274814 90)
			(size 1.4224 2.3368)
			(layers "F.Cu" "F.Mask" "F.Paste")
			(net "UNNAMED_16_CONNHDR2X6FSSMT_I1_6")
		)
		(pad "6" smd rect
			(at 1.27 -11.135106 90)
			(size 1.4224 2.2352)
			(layers "F.Cu" "F.Mask" "F.Paste")
			(net "UNNAMED_16_CONNHDR2X6FSSMT_I1_7")
		)
		(pad "7" smd rect
			(at -1.27 -7.274814 90)
			(size 1.4224 2.3368)
			(layers "F.Cu" "F.Mask" "F.Paste")
			(net "UNNAMED_16_CONNHDR2X6FSSMT_I1_4")
		)
		(pad "8" smd rect
			(at -1.27 -11.135106 90)
			(size 1.4224 2.2352)
			(layers "F.Cu" "F.Mask" "F.Paste")
			(net "UNNAMED_16_CONNHDR2X6FSSMT_I1_5")
		)
		(pad "9" smd rect
			(at -3.81 -7.274814 90)
			(size 1.4224 2.3368)
			(layers "F.Cu" "F.Mask" "F.Paste")
			(net "SG")
		)
		(pad "10" smd rect
			(at -3.81 -11.135106 90)
			(size 1.4224 2.2352)
			(layers "F.Cu" "F.Mask" "F.Paste")
			(net "SG")
		)
		(pad "11" smd rect
			(at -6.35 -7.274814 90)
			(size 1.4224 2.3368)
			(layers "F.Cu" "F.Mask" "F.Paste")
			(net "XP3R3V_FPGA")
		)
		(pad "12" smd rect
			(at -6.35 -11.135106 90)
			(size 1.4224 2.2352)
			(layers "F.Cu" "F.Mask" "F.Paste")
			(net "XP3R3V_FPGA")
		)
	)
	(footprint ""
		(layer "F.Cu")
		(at 11.798808 -57.2516 -90)
		(property "Reference" "R127"
			(at 0.3556 2.107438 90)
			(unlocked yes)
			(layer "F.SilkS")
			(effects
				(font
					(size 0.7874 0.5842)
					(thickness 0.1524)
				)
			)
		)
		(property "Value" "VAL*"
			(at 0.02032 2.13233 270)
			(unlocked yes)
			(layer "F.Fab")
			(hide yes)
			(effects
				(font
					(size 0.7874 0.5842)
					(thickness 0.1524)
				)
			)
		)
		(property "Tolerance" "TOL*"
			(at 0.044704 3.05435 270)
			(unlocked yes)
			(layer "Cmts.User")
			(hide yes)
			(effects
				(font
					(size 0.7874 0.5842)
					(thickness 0.1524)
				)
			)
		)
		(property "User Part Number" "PARTNUM*"
			(at 0.02032 4.024884 270)
			(unlocked yes)
			(layer "Cmts.User")
			(hide yes)
			(effects
				(font
					(size 0.7874 0.5842)
					(thickness 0.1524)
				)
			)
		)
		(property "Device Type" "RESISTOR-G155-149R9-01,49.9OHMA"
			(at 0.008382 1.210564 270)
			(unlocked yes)
			(layer "F.Fab")
			(hide yes)
			(effects
				(font
					(size 0.7874 0.5842)
					(thickness 0.1524)
				)
			)
		)
		(duplicate_pad_numbers_are_jumpers no)
		(fp_line
			(start -1.143 0.5588)
			(end 1.143 0.5588)
			(stroke
				(width 0.1)
				(type default)
			)
			(layer "F.SilkS")
		)
		(fp_line
			(start 1.143 0.5588)
			(end 1.143 -0.5588)
			(stroke
				(width 0.1)
				(type default)
			)
			(layer "F.SilkS")
		)
		(fp_line
			(start -1.143 -0.5588)
			(end -1.143 0.5588)
			(stroke
				(width 0.1)
				(type default)
			)
			(layer "F.SilkS")
		)
		(fp_line
			(start 1.143 -0.5588)
			(end -1.143 -0.5588)
			(stroke
				(width 0.1)
				(type default)
			)
			(layer "F.SilkS")
		)
		(fp_poly
			(pts
				(xy -1.143 0.5588) (xy 1.143 0.5588) (xy 1.143 -0.5588) (xy -1.143 -0.5588)
			)
			(stroke
				(width 0)
				(type default)
			)
			(fill no)
			(layer "F.CrtYd")
		)
		(fp_line
			(start -0.508 0.3048)
			(end 0.508 0.3048)
			(stroke
				(width 0.1)
				(type default)
			)
			(layer "F.Fab")
		)
		(fp_line
			(start 0.508 0.3048)
			(end 0.508 -0.3048)
			(stroke
				(width 0.1)
				(type default)
			)
			(layer "F.Fab")
		)
		(fp_line
			(start -0.508 -0.3048)
			(end -0.508 0.3048)
			(stroke
				(width 0.1)
				(type default)
			)
			(layer "F.Fab")
		)
		(fp_line
			(start 0.508 -0.3048)
			(end -0.508 -0.3048)
			(stroke
				(width 0.1)
				(type default)
			)
			(layer "F.Fab")
		)
		(pad "1" smd rect
			(at -0.5334 0 270)
			(size 0.7112 0.6096)
			(layers "F.Cu" "F.Mask" "F.Paste")
			(net "BF_SMA1_SIG_IO_CONN")
		)
		(pad "2" smd rect
			(at 0.5334 0 270)
			(size 0.7112 0.6096)
			(layers "F.Cu" "F.Mask" "F.Paste")
			(net "SMA1_SIG_IO_CONN")
		)
		(zone
			(layer "F.Cu")
			(hatch none 0.5)
			(connect_pads
				(clearance 0)
			)
			(min_thickness 0.25)
			(keepout
				(tracks allowed)
				(vias not_allowed)
				(pads allowed)
				(copperpour not_allowed)
				(footprints allowed)
			)
			(placement
				(enabled no)
				(sheetname "")
			)
			(fill
				(thermal_gap 0.5)
				(thermal_bridge_width 0.5)
				(island_removal_mode 0)
			)
			(polygon
				(pts
					(xy 11.494008 -57.3278) (xy 11.494008 -57.1754) (xy 12.103608 -57.1754) (xy 12.103608 -57.3278)
				)
			)
		)
		(zone
			(layer "F.Cu")
			(hatch none 0.5)
			(connect_pads
				(clearance 0)
			)
			(min_thickness 0.25)
			(keepout
				(tracks not_allowed)
				(vias allowed)
				(pads allowed)
				(copperpour not_allowed)
				(footprints allowed)
			)
			(placement
				(enabled no)
				(sheetname "")
			)
			(fill
				(thermal_gap 0.5)
				(thermal_bridge_width 0.5)
				(island_removal_mode 0)
			)
			(polygon
				(pts
					(xy 11.494008 -57.3278) (xy 11.494008 -57.1754) (xy 12.103608 -57.1754) (xy 12.103608 -57.3278)
				)
			)
		)
	)
	(footprint ""
		(layer "F.Cu")
		(at 16.4338 -63.9318)
		(property "Reference" "TP32"
			(at -0.52705 3.1242 90)
			(unlocked yes)
			(layer "F.SilkS")
			(effects
				(font
					(size 0.635 0.4064)
					(thickness 0.1524)
				)
				(justify left)
			)
		)
		(property "Value" ""
			(at 0 0 0)
			(layer "F.Fab")
			(effects
				(font
					(size 1.27 1.27)
				)
			)
		)
		(property "Device Type" "TP_PIONT-TP010CT020B030_PTH-TPA"
			(at -1.341882 0.996696 0)
			(unlocked yes)
			(layer "F.Fab")
			(hide yes)
			(effects
				(font
					(size 0.7874 0.5842)
					(thickness 0.000001)
				)
				(justify left)
			)
		)
		(duplicate_pad_numbers_are_jumpers no)
		(fp_poly
			(pts
				(arc
					(start 0.889 0)
					(mid -0.889 0)
					(end 0.889 0)
				)
			)
			(stroke
				(width 0)
				(type default)
			)
			(fill no)
			(layer "B.CrtYd")
		)
		(fp_poly
			(pts
				(arc
					(start 0.889 0)
					(mid -0.889 0)
					(end 0.889 0)
				)
			)
			(stroke
				(width 0)
				(type default)
			)
			(fill no)
			(layer "F.CrtYd")
		)
		(pad "1" thru_hole circle
			(at 0 0)
			(size 0.508 0.508)
			(drill 0.254)
			(layers "*.Cu" "*.Mask")
			(remove_unused_layers no)
			(net "SMA1_SIG_OUT_BF_EN_N")
			(clearance 0.1016)
			(padstack
				(mode front_inner_back)
				(layer "Inner"
					(shape circle)
					(size 0.508 0.508)
					(clearance 0.1016)
				)
				(layer "B.Cu"
					(shape circle)
					(size 0.762 0.762)
					(clearance -0.0254)
				)
			)
		)
	)
	(footprint ""
		(layer "F.Cu")
		(at 106.299 -29.718 90)
		(property "Reference" "TP196"
			(at -1.5748 -0.85725 90)
			(unlocked yes)
			(layer "F.SilkS")
			(effects
				(font
					(size 0.635 0.4064)
					(thickness 0.1524)
				)
				(justify left)
			)
		)
		(property "Value" ""
			(at 0 0 90)
			(layer "F.Fab")
			(effects
				(font
					(size 1.27 1.27)
				)
			)
		)
		(property "Device Type" "TP_PIONT-TP010CT020B030_PTH-TPA"
			(at -1.341882 0.996696 90)
			(unlocked yes)
			(layer "F.Fab")
			(hide yes)
			(effects
				(font
					(size 0.7874 0.5842)
					(thickness 0.1524)
				)
				(justify left)
			)
		)
		(duplicate_pad_numbers_are_jumpers no)
		(fp_poly
			(pts
				(arc
					(start 0 0.889)
					(mid 0 -0.889)
					(end 0 0.889)
				)
			)
			(stroke
				(width 0)
				(type default)
			)
			(fill no)
			(layer "B.CrtYd")
		)
		(fp_poly
			(pts
				(arc
					(start 0 0.889)
					(mid 0 -0.889)
					(end 0 0.889)
				)
			)
			(stroke
				(width 0)
				(type default)
			)
			(fill no)
			(layer "F.CrtYd")
		)
		(pad "1" thru_hole circle
			(at 0 0 90)
			(size 0.508 0.508)
			(drill 0.254)
			(layers "*.Cu" "*.Mask")
			(remove_unused_layers no)
			(net "IO_L23N_35")
			(clearance 0.1016)
			(padstack
				(mode front_inner_back)
				(layer "Inner"
					(shape circle)
					(size 0.508 0.508)
					(clearance 0.1016)
				)
				(layer "B.Cu"
					(shape circle)
					(size 0.762 0.762)
					(clearance -0.0254)
				)
			)
		)
	)
	(footprint ""
		(layer "F.Cu")
		(at 126.0094 -68.7578 90)
		(property "Reference" "C187"
			(at 4.10083 -0.0254 0)
			(unlocked yes)
			(layer "F.SilkS")
			(effects
				(font
					(size 0.7874 0.5842)
					(thickness 0.1524)
				)
			)
		)
		(property "Value" "VAL*"
			(at 0.0762 2.067306 90)
			(unlocked yes)
			(layer "F.Fab")
			(hide yes)
			(effects
				(font
					(size 0.7874 0.5842)
					(thickness 0.1524)
				)
			)
		)
		(property "Tolerance" "TOL*"
			(at 0.0762 3.032506 90)
			(unlocked yes)
			(layer "Cmts.User")
			(hide yes)
			(effects
				(font
					(size 0.7874 0.5842)
					(thickness 0.1524)
				)
			)
		)
		(property "User Part Number" "PARTNUM*"
			(at 0.1016 4.023106 90)
			(unlocked yes)
			(layer "Cmts.User")
			(hide yes)
			(effects
				(font
					(size 0.7874 0.5842)
					(thickness 0.1524)
				)
			)
		)
		(property "Device Type" "CAPACITOR-G105-0B104-EK,0.1UF,A"
			(at 0.0508 1.127506 90)
			(unlocked yes)
			(layer "F.Fab")
			(hide yes)
			(effects
				(font
					(size 0.7874 0.5842)
					(thickness 0.1524)
				)
			)
		)
		(duplicate_pad_numbers_are_jumpers no)
		(fp_line
			(start 1.143 -0.5588)
			(end -1.143 -0.5588)
			(stroke
				(width 0.1)
				(type default)
			)
			(layer "F.SilkS")
		)
		(fp_line
			(start -1.143 -0.5588)
			(end -1.143 0.5588)
			(stroke
				(width 0.1)
				(type default)
			)
			(layer "F.SilkS")
		)
		(fp_line
			(start 1.143 0.5588)
			(end 1.143 -0.5588)
			(stroke
				(width 0.1)
				(type default)
			)
			(layer "F.SilkS")
		)
		(fp_line
			(start -1.143 0.5588)
			(end 1.143 0.5588)
			(stroke
				(width 0.1)
				(type default)
			)
			(layer "F.SilkS")
		)
		(fp_rect
			(start 1.143 0.5588)
			(end -1.143 -0.5588)
			(stroke
				(width 0)
				(type default)
			)
			(fill no)
			(layer "F.CrtYd")
		)
		(fp_line
			(start 0.508 -0.3048)
			(end -0.508 -0.3048)
			(stroke
				(width 0.1)
				(type default)
			)
			(layer "F.Fab")
		)
		(fp_line
			(start -0.508 -0.3048)
			(end -0.508 0.3048)
			(stroke
				(width 0.1)
				(type default)
			)
			(layer "F.Fab")
		)
		(fp_line
			(start 0.508 0.3048)
			(end 0.508 -0.3048)
			(stroke
				(width 0.1)
				(type default)
			)
			(layer "F.Fab")
		)
		(fp_line
			(start -0.508 0.3048)
			(end 0.508 0.3048)
			(stroke
				(width 0.1)
				(type default)
			)
			(layer "F.Fab")
		)
		(pad "1" smd rect
			(at -0.5334 0 90)
			(size 0.7112 0.6096)
			(layers "F.Cu" "F.Mask" "F.Paste")
			(net "XP1R8V_EN_R")
		)
		(pad "2" smd rect
			(at 0.5334 0 90)
			(size 0.7112 0.6096)
			(layers "F.Cu" "F.Mask" "F.Paste")
			(net "SG")
		)
		(zone
			(layer "F.Cu")
			(hatch none 0.5)
			(connect_pads
				(clearance 0)
			)
			(min_thickness 0.25)
			(keepout
				(tracks allowed)
				(vias not_allowed)
				(pads allowed)
				(copperpour not_allowed)
				(footprints allowed)
			)
			(placement
				(enabled no)
				(sheetname "")
			)
			(fill
				(thermal_gap 0.5)
				(thermal_bridge_width 0.5)
				(island_removal_mode 0)
			)
			(polygon
				(pts
					(xy 126.3142 -68.834) (xy 125.7046 -68.834) (xy 125.7046 -68.6816) (xy 126.3142 -68.6816)
				)
			)
		)
	)
	(footprint ""
		(layer "F.Cu")
		(at 80.772 -62.9666 180)
		(property "Reference" "R307"
			(at 10.287 19.41703 0)
			(unlocked yes)
			(layer "F.SilkS")
			(effects
				(font
					(size 0.7874 0.5842)
					(thickness 0.1524)
				)
			)
		)
		(property "Value" "VAL*"
			(at 0.02032 2.13233 180)
			(unlocked yes)
			(layer "F.Fab")
			(hide yes)
			(effects
				(font
					(size 0.7874 0.5842)
					(thickness 0.1524)
				)
			)
		)
		(property "Device Type" "RESISTOR-G155-11001-01,1KOHM,1%"
			(at 0.008382 1.210564 180)
			(unlocked yes)
			(layer "F.Fab")
			(hide yes)
			(effects
				(font
					(size 0.7874 0.5842)
					(thickness 0.1524)
				)
			)
		)
		(property "User Part Number" "PARTNUM*"
			(at 0.02032 4.024884 180)
			(unlocked yes)
			(layer "Cmts.User")
			(hide yes)
			(effects
				(font
					(size 0.7874 0.5842)
					(thickness 0.1524)
				)
			)
		)
		(property "Tolerance" "TOL*"
			(at 0.044704 3.05435 180)
			(unlocked yes)
			(layer "Cmts.User")
			(hide yes)
			(effects
				(font
					(size 0.7874 0.5842)
					(thickness 0.1524)
				)
			)
		)
		(duplicate_pad_numbers_are_jumpers no)
		(fp_line
			(start 1.143 0.5588)
			(end 1.143 -0.5588)
			(stroke
				(width 0.1)
				(type default)
			)
			(layer "F.SilkS")
		)
		(fp_line
			(start 1.143 -0.5588)
			(end -1.143 -0.5588)
			(stroke
				(width 0.1)
				(type default)
			)
			(layer "F.SilkS")
		)
		(fp_line
			(start -1.143 0.5588)
			(end 1.143 0.5588)
			(stroke
				(width 0.1)
				(type default)
			)
			(layer "F.SilkS")
		)
		(fp_line
			(start -1.143 -0.5588)
			(end -1.143 0.5588)
			(stroke
				(width 0.1)
				(type default)
			)
			(layer "F.SilkS")
		)
		(fp_rect
			(start 1.143 -0.5588)
			(end -1.143 0.5588)
			(stroke
				(width 0)
				(type default)
			)
			(fill no)
			(layer "F.CrtYd")
		)
		(fp_line
			(start 0.508 0.3048)
			(end 0.508 -0.3048)
			(stroke
				(width 0.1)
				(type default)
			)
			(layer "F.Fab")
		)
		(fp_line
			(start 0.508 -0.3048)
			(end -0.508 -0.3048)
			(stroke
				(width 0.1)
				(type default)
			)
			(layer "F.Fab")
		)
		(fp_line
			(start -0.508 0.3048)
			(end 0.508 0.3048)
			(stroke
				(width 0.1)
				(type default)
			)
			(layer "F.Fab")
		)
		(fp_line
			(start -0.508 -0.3048)
			(end -0.508 0.3048)
			(stroke
				(width 0.1)
				(type default)
			)
			(layer "F.Fab")
		)
		(pad "1" smd rect
			(at -0.5334 0 180)
			(size 0.7112 0.6096)
			(layers "F.Cu" "F.Mask" "F.Paste")
			(net "UNNAMED_9_BNO080LGA28_I29_CLKSE")
		)
		(pad "2" smd rect
			(at 0.5334 0 180)
			(size 0.7112 0.6096)
			(layers "F.Cu" "F.Mask" "F.Paste")
			(net "SG")
		)
		(zone
			(layer "F.Cu")
			(hatch none 0.5)
			(connect_pads
				(clearance 0)
			)
			(min_thickness 0.25)
			(keepout
				(tracks allowed)
				(vias not_allowed)
				(pads allowed)
				(copperpour not_allowed)
				(footprints allowed)
			)
			(placement
				(enabled no)
				(sheetname "")
			)
			(fill
				(thermal_gap 0.5)
				(thermal_bridge_width 0.5)
				(island_removal_mode 0)
			)
			(polygon
				(pts
					(xy 80.6958 -62.6618) (xy 80.8482 -62.6618) (xy 80.8482 -63.2714) (xy 80.6958 -63.2714)
				)
			)
		)
	)
	(footprint ""
		(layer "F.Cu")
		(at 92.837 -56.007 180)
		(property "Reference" "L33"
			(at 1.0795 -1.30937 0)
			(unlocked yes)
			(layer "F.SilkS")
			(effects
				(font
					(size 0.7874 0.5842)
					(thickness 0.1524)
				)
				(justify left)
			)
		)
		(property "Value" "VAL*"
			(at -0.9398 3.70967 180)
			(unlocked yes)
			(layer "F.Fab")
			(hide yes)
			(effects
				(font
					(size 0.7874 0.5842)
					(thickness 0.1524)
				)
				(justify left)
			)
		)
		(property "Tolerance" "TOL*"
			(at -0.9906 5.00507 180)
			(unlocked yes)
			(layer "Cmts.User")
			(hide yes)
			(effects
				(font
					(size 0.7874 0.5842)
					(thickness 0.1524)
				)
				(justify left)
			)
		)
		(property "User Part Number" "PARTNUM*"
			(at -2.54 2.46507 180)
			(unlocked yes)
			(layer "Cmts.User")
			(hide yes)
			(effects
				(font
					(size 0.7874 0.5842)
					(thickness 0.1524)
				)
				(justify left)
			)
		)
		(property "Device Type" "FERRITEBEAD-G191-10100-01,120OA"
			(at -0.9906 1.22047 180)
			(unlocked yes)
			(layer "F.Fab")
			(hide yes)
			(effects
				(font
					(size 0.7874 0.5842)
					(thickness 0.1524)
				)
				(justify left)
			)
		)
		(duplicate_pad_numbers_are_jumpers no)
		(fp_line
			(start 1.3208 0.7112)
			(end -1.3208 0.7112)
			(stroke
				(width 0.1)
				(type default)
			)
			(layer "F.SilkS")
		)
		(fp_line
			(start 1.3208 -0.7112)
			(end 1.3208 0.7112)
			(stroke
				(width 0.1)
				(type default)
			)
			(layer "F.SilkS")
		)
		(fp_line
			(start -1.3208 0.7112)
			(end -1.3208 -0.7112)
			(stroke
				(width 0.1)
				(type default)
			)
			(layer "F.SilkS")
		)
		(fp_line
			(start -1.3208 -0.7112)
			(end 1.3208 -0.7112)
			(stroke
				(width 0.1)
				(type default)
			)
			(layer "F.SilkS")
		)
		(fp_rect
			(start -1.3208 0.7112)
			(end 1.3208 -0.7112)
			(stroke
				(width 0)
				(type default)
			)
			(fill no)
			(layer "F.CrtYd")
		)
		(fp_line
			(start 0.8128 0.4572)
			(end -0.8128 0.4572)
			(stroke
				(width 0.1)
				(type default)
			)
			(layer "F.Fab")
		)
		(fp_line
			(start 0.8128 -0.4572)
			(end 0.8128 0.4572)
			(stroke
				(width 0.1)
				(type default)
			)
			(layer "F.Fab")
		)
		(fp_line
			(start -0.8128 0.4572)
			(end -0.8128 -0.4572)
			(stroke
				(width 0.1)
				(type default)
			)
			(layer "F.Fab")
		)
		(fp_line
			(start -0.8128 -0.4572)
			(end 0.8128 -0.4572)
			(stroke
				(width 0.1)
				(type default)
			)
			(layer "F.Fab")
		)
		(pad "1" smd rect
			(at -0.6858 0 180)
			(size 0.762 0.8636)
			(layers "F.Cu" "F.Mask" "F.Paste")
			(net "XP1R8V_FPGA_VCCAUX")
		)
		(pad "2" smd rect
			(at 0.6858 0 180)
			(size 0.762 0.8636)
			(layers "F.Cu" "F.Mask" "F.Paste")
			(net "XP1R8V_FPGA")
		)
		(zone
			(layer "F.Cu")
			(hatch none 0.5)
			(connect_pads
				(clearance 0)
			)
			(min_thickness 0.25)
			(keepout
				(tracks not_allowed)
				(vias allowed)
				(pads allowed)
				(copperpour not_allowed)
				(footprints allowed)
			)
			(placement
				(enabled no)
				(sheetname "")
			)
			(fill
				(thermal_gap 0.5)
				(thermal_bridge_width 0.5)
				(island_removal_mode 0)
			)
			(polygon
				(pts
					(xy 92.9894 -56.4642) (xy 92.6846 -56.4642) (xy 92.6846 -55.5498) (xy 92.9894 -55.5498)
				)
			)
		)
		(zone
			(layer "F.Cu")
			(hatch none 0.5)
			(connect_pads
				(clearance 0)
			)
			(min_thickness 0.25)
			(keepout
				(tracks allowed)
				(vias not_allowed)
				(pads allowed)
				(copperpour not_allowed)
				(footprints allowed)
			)
			(placement
				(enabled no)
				(sheetname "")
			)
			(fill
				(thermal_gap 0.5)
				(thermal_bridge_width 0.5)
				(island_removal_mode 0)
			)
			(polygon
				(pts
					(xy 92.9894 -56.4642) (xy 92.6846 -56.4642) (xy 92.6846 -55.5498) (xy 92.9894 -55.5498)
				)
			)
		)
	)
	(footprint ""
		(layer "F.Cu")
		(at 90.9828 -73.0758 90)
		(property "Reference" "C199"
			(at 19.6342 -27.44343 90)
			(unlocked yes)
			(layer "F.SilkS")
			(effects
				(font
					(size 0.7874 0.5842)
					(thickness 0.1524)
				)
			)
		)
		(property "Value" "VAL*"
			(at 0.0762 2.067306 90)
			(unlocked yes)
			(layer "F.Fab")
			(hide yes)
			(effects
				(font
					(size 0.7874 0.5842)
					(thickness 0.1524)
				)
			)
		)
		(property "Device Type" "CAPACITOR-G105-0B104-CK,0.1UF,A"
			(at 0.0508 1.127506 90)
			(unlocked yes)
			(layer "F.Fab")
			(hide yes)
			(effects
				(font
					(size 0.7874 0.5842)
					(thickness 0.1524)
				)
			)
		)
		(property "User Part Number" "PARTNUM*"
			(at 0.1016 4.023106 90)
			(unlocked yes)
			(layer "Cmts.User")
			(hide yes)
			(effects
				(font
					(size 0.7874 0.5842)
					(thickness 0.1524)
				)
			)
		)
		(property "Tolerance" "TOL*"
			(at 0.0762 3.032506 90)
			(unlocked yes)
			(layer "Cmts.User")
			(hide yes)
			(effects
				(font
					(size 0.7874 0.5842)
					(thickness 0.1524)
				)
			)
		)
		(duplicate_pad_numbers_are_jumpers no)
		(fp_line
			(start 1.143 -0.5588)
			(end -1.143 -0.5588)
			(stroke
				(width 0.1)
				(type default)
			)
			(layer "F.SilkS")
		)
		(fp_line
			(start -1.143 -0.5588)
			(end -1.143 0.5588)
			(stroke
				(width 0.1)
				(type default)
			)
			(layer "F.SilkS")
		)
		(fp_line
			(start 1.143 0.5588)
			(end 1.143 -0.5588)
			(stroke
				(width 0.1)
				(type default)
			)
			(layer "F.SilkS")
		)
		(fp_line
			(start -1.143 0.5588)
			(end 1.143 0.5588)
			(stroke
				(width 0.1)
				(type default)
			)
			(layer "F.SilkS")
		)
		(fp_rect
			(start -1.143 -0.5588)
			(end 1.143 0.5588)
			(stroke
				(width 0)
				(type default)
			)
			(fill no)
			(layer "F.CrtYd")
		)
		(fp_line
			(start 0.508 -0.3048)
			(end -0.508 -0.3048)
			(stroke
				(width 0.1)
				(type default)
			)
			(layer "F.Fab")
		)
		(fp_line
			(start -0.508 -0.3048)
			(end -0.508 0.3048)
			(stroke
				(width 0.1)
				(type default)
			)
			(layer "F.Fab")
		)
		(fp_line
			(start 0.508 0.3048)
			(end 0.508 -0.3048)
			(stroke
				(width 0.1)
				(type default)
			)
			(layer "F.Fab")
		)
		(fp_line
			(start -0.508 0.3048)
			(end 0.508 0.3048)
			(stroke
				(width 0.1)
				(type default)
			)
			(layer "F.Fab")
		)
		(pad "1" smd rect
			(at -0.5334 0 90)
			(size 0.7112 0.6096)
			(layers "F.Cu" "F.Mask" "F.Paste")
			(net "XP3R3V_FPGA")
		)
		(pad "2" smd rect
			(at 0.5334 0 90)
			(size 0.7112 0.6096)
			(layers "F.Cu" "F.Mask" "F.Paste")
			(net "SG")
		)
		(zone
			(layer "F.Cu")
			(hatch none 0.5)
			(connect_pads
				(clearance 0)
			)
			(min_thickness 0.25)
			(keepout
				(tracks allowed)
				(vias not_allowed)
				(pads allowed)
				(copperpour not_allowed)
				(footprints allowed)
			)
			(placement
				(enabled no)
				(sheetname "")
			)
			(fill
				(thermal_gap 0.5)
				(thermal_bridge_width 0.5)
				(island_removal_mode 0)
			)
			(polygon
				(pts
					(xy 90.678 -72.9996) (xy 91.2876 -72.9996) (xy 91.2876 -73.152) (xy 90.678 -73.152)
				)
			)
		)
	)
	(footprint ""
		(layer "F.Cu")
		(at 1.500124 -39.099998 90)
		(property "Reference" "DS14"
			(at 2.770632 1.293876 0)
			(unlocked yes)
			(layer "F.SilkS")
			(effects
				(font
					(size 0.7874 0.5842)
					(thickness 0.1524)
				)
			)
		)
		(property "Value" ""
			(at 0 0 90)
			(layer "F.Fab")
			(effects
				(font
					(size 1.27 1.27)
				)
			)
		)
		(property "User Part Number" "PARTNUM*"
			(at 0.015494 4.486402 90)
			(unlocked yes)
			(layer "Cmts.User")
			(hide yes)
			(effects
				(font
					(size 0.7874 0.5842)
					(thickness 0.1524)
				)
			)
		)
		(property "Device Type" "LED_4P_V14-G170-10189-01"
			(at 0.015494 3.292602 90)
			(unlocked yes)
			(layer "F.Fab")
			(hide yes)
			(effects
				(font
					(size 0.7874 0.5842)
					(thickness 0.1524)
				)
			)
		)
		(duplicate_pad_numbers_are_jumpers no)
		(fp_line
			(start 1.378966 -0.829056)
			(end -1.378966 -0.829056)
			(stroke
				(width 0.1)
				(type default)
			)
			(layer "F.SilkS")
		)
		(fp_line
			(start -1.378966 -0.829056)
			(end -1.378966 -0.452628)
			(stroke
				(width 0.1)
				(type default)
			)
			(layer "F.SilkS")
		)
		(fp_line
			(start 1.998218 -0.452628)
			(end 1.378966 -0.452628)
			(stroke
				(width 0.1)
				(type default)
			)
			(layer "F.SilkS")
		)
		(fp_line
			(start 1.378966 -0.452628)
			(end 1.378966 -0.829056)
			(stroke
				(width 0.1)
				(type default)
			)
			(layer "F.SilkS")
		)
		(fp_line
			(start -1.378966 -0.452628)
			(end -1.998218 -0.452628)
			(stroke
				(width 0.1)
				(type default)
			)
			(layer "F.SilkS")
		)
		(fp_line
			(start -1.998218 -0.452628)
			(end -1.998218 1.103884)
			(stroke
				(width 0.1)
				(type default)
			)
			(layer "F.SilkS")
		)
		(fp_line
			(start 1.998218 1.103884)
			(end 1.998218 -0.452628)
			(stroke
				(width 0.1)
				(type default)
			)
			(layer "F.SilkS")
		)
		(fp_line
			(start -1.998218 1.103884)
			(end 1.998218 1.103884)
			(stroke
				(width 0.1)
				(type default)
			)
			(layer "F.SilkS")
		)
		(fp_poly
			(pts
				(xy 0.918464 -1.698498) (xy 1.223264 -1.46939) (xy 0.994664 -1.46939) (xy 0.994664 -1.24079) (xy 0.842264 -1.24079)
				(xy 0.842264 -1.46939) (xy 0.613664 -1.46939)
			)
			(stroke
				(width 0)
				(type default)
			)
			(fill yes)
			(layer "F.SilkS")
		)
		(fp_poly
			(pts
				(xy -0.73406 -1.677416) (xy -0.42926 -1.448308) (xy -0.65786 -1.448308) (xy -0.65786 -1.219708)
				(xy -0.81026 -1.219708) (xy -0.81026 -1.448308) (xy -1.03886 -1.448308)
			)
			(stroke
				(width 0)
				(type default)
			)
			(fill yes)
			(layer "F.SilkS")
		)
		(fp_poly
			(pts
				(xy -2.252218 1.357884) (xy -2.252218 -0.706628) (xy -1.632966 -0.706628) (xy -1.632966 -1.083056)
				(xy 1.632966 -1.083056) (xy 1.632966 -0.706628) (xy 2.252218 -0.706628) (xy 2.252218 1.357884)
			)
			(stroke
				(width 0)
				(type default)
			)
			(fill no)
			(layer "F.CrtYd")
		)
		(fp_line
			(start 1.124966 -0.575056)
			(end -1.124966 -0.575056)
			(stroke
				(width 0.1)
				(type default)
			)
			(layer "F.Fab")
		)
		(fp_line
			(start -1.124966 -0.575056)
			(end -1.124966 -0.075184)
			(stroke
				(width 0.1)
				(type default)
			)
			(layer "F.Fab")
		)
		(fp_line
			(start 1.325118 -0.075184)
			(end 1.124966 -0.075184)
			(stroke
				(width 0.1)
				(type default)
			)
			(layer "F.Fab")
		)
		(fp_line
			(start 1.124966 -0.075184)
			(end 1.124966 -0.575056)
			(stroke
				(width 0.1)
				(type default)
			)
			(layer "F.Fab")
		)
		(fp_line
			(start -1.124966 -0.075184)
			(end -1.325118 -0.075184)
			(stroke
				(width 0.1)
				(type default)
			)
			(layer "F.Fab")
		)
		(fp_line
			(start -1.325118 -0.075184)
			(end -1.325118 0.574802)
			(stroke
				(width 0.1)
				(type default)
			)
			(layer "F.Fab")
		)
		(fp_line
			(start 1.325118 0.574802)
			(end 1.325118 -0.075184)
			(stroke
				(width 0.1)
				(type default)
			)
			(layer "F.Fab")
		)
		(fp_line
			(start -1.325118 0.574802)
			(end 1.325118 0.574802)
			(stroke
				(width 0.1)
				(type default)
			)
			(layer "F.Fab")
		)
		(fp_poly
			(pts
				(xy 0.918464 -1.698498) (xy 1.223264 -1.46939) (xy 0.994664 -1.46939) (xy 0.994664 -1.24079) (xy 0.842264 -1.24079)
				(xy 0.842264 -1.46939) (xy 0.613664 -1.46939)
			)
			(stroke
				(width 0)
				(type default)
			)
			(fill yes)
			(layer "F.Fab")
		)
		(fp_poly
			(pts
				(xy -0.73406 -1.677416) (xy -0.42926 -1.448308) (xy -0.65786 -1.448308) (xy -0.65786 -1.219708)
				(xy -0.81026 -1.219708) (xy -0.81026 -1.448308) (xy -1.03886 -1.448308)
			)
			(stroke
				(width 0)
				(type default)
			)
			(fill yes)
			(layer "F.Fab")
		)
		(fp_text user "4"
			(at 2.778252 -0.611124 0)
			(unlocked yes)
			(layer "F.SilkS")
			(effects
				(font
					(size 0.635 0.4064)
					(thickness 0.1524)
				)
			)
		)
		(fp_text user "1"
			(at -2.37617 0.376936 90)
			(unlocked yes)
			(layer "F.SilkS")
			(effects
				(font
					(size 0.7874 0.5842)
					(thickness 0.1524)
				)
			)
		)
		(fp_text user "2"
			(at -1.158748 1.420876 0)
			(unlocked yes)
			(layer "F.SilkS")
			(effects
				(font
					(size 0.635 0.4064)
					(thickness 0.1524)
				)
			)
		)
		(fp_text user "3"
			(at 1.305052 1.547876 0)
			(unlocked yes)
			(layer "F.SilkS")
			(effects
				(font
					(size 0.635 0.4064)
					(thickness 0.1524)
				)
			)
		)
		(fp_text user "4"
			(at 1.92532 1.166876 0)
			(unlocked yes)
			(layer "F.Fab")
			(effects
				(font
					(size 0.7874 0.5842)
					(thickness 0.1524)
				)
			)
		)
		(fp_text user "3"
			(at 0.738632 1.166876 0)
			(unlocked yes)
			(layer "F.Fab")
			(effects
				(font
					(size 0.7874 0.5842)
					(thickness 0.1524)
				)
			)
		)
		(fp_text user "2"
			(at -0.531368 1.293876 0)
			(unlocked yes)
			(layer "F.Fab")
			(effects
				(font
					(size 0.7874 0.5842)
					(thickness 0.1524)
				)
			)
		)
		(fp_text user "1"
			(at -1.674368 1.293876 0)
			(unlocked yes)
			(layer "F.Fab")
			(effects
				(font
					(size 0.7874 0.5842)
					(thickness 0.1524)
				)
			)
		)
		(pad "1" smd rect
			(at -1.325118 0.245872 90)
			(size 0.8382 0.889)
			(layers "F.Cu" "F.Mask" "F.Paste")
			(net "UNNAMED_14_LED4PV14_I265_1")
		)
		(pad "2" smd rect
			(at -0.424942 0.595884 90)
			(size 0.4572 0.508)
			(layers "F.Cu" "F.Mask" "F.Paste")
			(net "XP3R3V_FPGA")
		)
		(pad "3" smd rect
			(at 0.424942 0.595884 90)
			(size 0.4572 0.508)
			(layers "F.Cu" "F.Mask" "F.Paste")
			(net "UNNAMED_14_LED4PV14_I265_3")
		)
		(pad "4" smd rect
			(at 1.325118 0.245872 90)
			(size 0.8382 0.889)
			(layers "F.Cu" "F.Mask" "F.Paste")
			(net "UNNAMED_14_LED4PV14_I265_4")
		)
	)
	(footprint ""
		(layer "F.Cu")
		(at 128.27 -98.298 -90)
		(property "Reference" "C72"
			(at -2.921 -1.43637 90)
			(unlocked yes)
			(layer "F.SilkS")
			(effects
				(font
					(size 0.7874 0.5842)
					(thickness 0.1524)
				)
			)
		)
		(property "Value" "VAL*"
			(at 0.0762 3.134106 270)
			(unlocked yes)
			(layer "F.Fab")
			(hide yes)
			(effects
				(font
					(size 0.7874 0.5842)
					(thickness 0.1524)
				)
			)
		)
		(property "Device Type" "CAPACITOR-G107-0F106-EM,10UF,2A"
			(at 0.0508 2.194306 270)
			(unlocked yes)
			(layer "F.Fab")
			(hide yes)
			(effects
				(font
					(size 0.7874 0.5842)
					(thickness 0.1524)
				)
			)
		)
		(property "User Part Number" "PARTNUM*"
			(at 0.1016 5.013706 270)
			(unlocked yes)
			(layer "Cmts.User")
			(hide yes)
			(effects
				(font
					(size 0.7874 0.5842)
					(thickness 0.1524)
				)
			)
		)
		(property "Tolerance" "TOL*"
			(at 0.0762 4.048506 270)
			(unlocked yes)
			(layer "Cmts.User")
			(hide yes)
			(effects
				(font
					(size 0.7874 0.5842)
					(thickness 0.1524)
				)
			)
		)
		(duplicate_pad_numbers_are_jumpers no)
		(fp_line
			(start -1.5748 0.9398)
			(end 1.5748 0.9398)
			(stroke
				(width 0.1)
				(type default)
			)
			(layer "F.SilkS")
		)
		(fp_line
			(start 1.5748 0.9398)
			(end 1.5748 -0.9398)
			(stroke
				(width 0.1)
				(type default)
			)
			(layer "F.SilkS")
		)
		(fp_line
			(start -1.5748 -0.9398)
			(end -1.5748 0.9398)
			(stroke
				(width 0.1)
				(type default)
			)
			(layer "F.SilkS")
		)
		(fp_line
			(start 1.5748 -0.9398)
			(end -1.5748 -0.9398)
			(stroke
				(width 0.1)
				(type default)
			)
			(layer "F.SilkS")
		)
		(fp_rect
			(start 1.5748 0.9398)
			(end -1.5748 -0.9398)
			(stroke
				(width 0)
				(type default)
			)
			(fill no)
			(layer "F.CrtYd")
		)
		(fp_line
			(start -1.016 0.635)
			(end 1.016 0.635)
			(stroke
				(width 0.1)
				(type default)
			)
			(layer "F.Fab")
		)
		(fp_line
			(start 1.016 0.635)
			(end 1.016 -0.635)
			(stroke
				(width 0.1)
				(type default)
			)
			(layer "F.Fab")
		)
		(fp_line
			(start -1.016 -0.635)
			(end -1.016 0.635)
			(stroke
				(width 0.1)
				(type default)
			)
			(layer "F.Fab")
		)
		(fp_line
			(start 1.016 -0.635)
			(end -1.016 -0.635)
			(stroke
				(width 0.1)
				(type default)
			)
			(layer "F.Fab")
		)
		(pad "1" smd rect
			(at -0.8382 0 270)
			(size 0.9652 1.3716)
			(layers "F.Cu" "F.Mask" "F.Paste")
			(net "XP5R0V_VCC_ANT")
		)
		(pad "2" smd rect
			(at 0.8382 0 270)
			(size 0.9652 1.3716)
			(layers "F.Cu" "F.Mask" "F.Paste")
			(net "SG")
		)
		(zone
			(layer "F.Cu")
			(hatch none 0.5)
			(connect_pads
				(clearance 0)
			)
			(min_thickness 0.25)
			(keepout
				(tracks allowed)
				(vias not_allowed)
				(pads allowed)
				(copperpour not_allowed)
				(footprints allowed)
			)
			(placement
				(enabled no)
				(sheetname "")
			)
			(fill
				(thermal_gap 0.5)
				(thermal_bridge_width 0.5)
				(island_removal_mode 0)
			)
			(polygon
				(pts
					(xy 127.635 -98.0694) (xy 128.905 -98.0694) (xy 128.905 -98.5266) (xy 127.635 -98.5266)
				)
			)
		)
	)
	(footprint ""
		(layer "F.Cu")
		(at 129.794 -95.885 180)
		(property "Reference" "C272"
			(at -0.127 -1.69037 0)
			(unlocked yes)
			(layer "F.SilkS")
			(effects
				(font
					(size 0.7874 0.5842)
					(thickness 0.1524)
				)
			)
		)
		(property "Value" "VAL*"
			(at 0.0762 2.067306 180)
			(unlocked yes)
			(layer "F.Fab")
			(hide yes)
			(effects
				(font
					(size 0.7874 0.5842)
					(thickness 0.1524)
				)
			)
		)
		(property "Device Type" "CAPACITOR-G105-0B104-EK,0.1UF,A"
			(at 0.0508 1.127506 180)
			(unlocked yes)
			(layer "F.Fab")
			(hide yes)
			(effects
				(font
					(size 0.7874 0.5842)
					(thickness 0.1524)
				)
			)
		)
		(property "User Part Number" "PARTNUM*"
			(at 0.1016 4.023106 180)
			(unlocked yes)
			(layer "Cmts.User")
			(hide yes)
			(effects
				(font
					(size 0.7874 0.5842)
					(thickness 0.1524)
				)
			)
		)
		(property "Tolerance" "TOL*"
			(at 0.0762 3.032506 180)
			(unlocked yes)
			(layer "Cmts.User")
			(hide yes)
			(effects
				(font
					(size 0.7874 0.5842)
					(thickness 0.1524)
				)
			)
		)
		(duplicate_pad_numbers_are_jumpers no)
		(fp_line
			(start 1.143 0.5588)
			(end 1.143 -0.5588)
			(stroke
				(width 0.1)
				(type default)
			)
			(layer "F.SilkS")
		)
		(fp_line
			(start 1.143 -0.5588)
			(end -1.143 -0.5588)
			(stroke
				(width 0.1)
				(type default)
			)
			(layer "F.SilkS")
		)
		(fp_line
			(start -1.143 0.5588)
			(end 1.143 0.5588)
			(stroke
				(width 0.1)
				(type default)
			)
			(layer "F.SilkS")
		)
		(fp_line
			(start -1.143 -0.5588)
			(end -1.143 0.5588)
			(stroke
				(width 0.1)
				(type default)
			)
			(layer "F.SilkS")
		)
		(fp_rect
			(start -1.143 0.5588)
			(end 1.143 -0.5588)
			(stroke
				(width 0)
				(type default)
			)
			(fill no)
			(layer "F.CrtYd")
		)
		(fp_line
			(start 0.508 0.3048)
			(end 0.508 -0.3048)
			(stroke
				(width 0.1)
				(type default)
			)
			(layer "F.Fab")
		)
		(fp_line
			(start 0.508 -0.3048)
			(end -0.508 -0.3048)
			(stroke
				(width 0.1)
				(type default)
			)
			(layer "F.Fab")
		)
		(fp_line
			(start -0.508 0.3048)
			(end 0.508 0.3048)
			(stroke
				(width 0.1)
				(type default)
			)
			(layer "F.Fab")
		)
		(fp_line
			(start -0.508 -0.3048)
			(end -0.508 0.3048)
			(stroke
				(width 0.1)
				(type default)
			)
			(layer "F.Fab")
		)
		(pad "1" smd rect
			(at -0.5334 0 180)
			(size 0.7112 0.6096)
			(layers "F.Cu" "F.Mask" "F.Paste")
			(net "XP5R0V")
		)
		(pad "2" smd rect
			(at 0.5334 0 180)
			(size 0.7112 0.6096)
			(layers "F.Cu" "F.Mask" "F.Paste")
			(net "SG")
		)
		(zone
			(layer "F.Cu")
			(hatch none 0.5)
			(connect_pads
				(clearance 0)
			)
			(min_thickness 0.25)
			(keepout
				(tracks allowed)
				(vias not_allowed)
				(pads allowed)
				(copperpour not_allowed)
				(footprints allowed)
			)
			(placement
				(enabled no)
				(sheetname "")
			)
			(fill
				(thermal_gap 0.5)
				(thermal_bridge_width 0.5)
				(island_removal_mode 0)
			)
			(polygon
				(pts
					(xy 129.8702 -96.1898) (xy 129.7178 -96.1898) (xy 129.7178 -95.5802) (xy 129.8702 -95.5802)
				)
			)
		)
	)
	(footprint ""
		(layer "F.Cu")
		(at 44.704 -80.264 -90)
		(property "Reference" "L23"
			(at -0.1905 -3.84937 90)
			(unlocked yes)
			(layer "F.SilkS")
			(effects
				(font
					(size 0.7874 0.5842)
					(thickness 0.1524)
				)
				(justify left)
			)
		)
		(property "Value" "VAL*"
			(at -0.9398 3.70967 270)
			(unlocked yes)
			(layer "F.Fab")
			(hide yes)
			(effects
				(font
					(size 0.7874 0.5842)
					(thickness 0.1524)
				)
				(justify left)
			)
		)
		(property "Tolerance" "TOL*"
			(at -0.9906 5.00507 270)
			(unlocked yes)
			(layer "Cmts.User")
			(hide yes)
			(effects
				(font
					(size 0.7874 0.5842)
					(thickness 0.1524)
				)
				(justify left)
			)
		)
		(property "User Part Number" "PARTNUM*"
			(at -2.54 2.46507 270)
			(unlocked yes)
			(layer "Cmts.User")
			(hide yes)
			(effects
				(font
					(size 0.7874 0.5842)
					(thickness 0.1524)
				)
				(justify left)
			)
		)
		(property "Device Type" "FERRITEBEAD-G191-10101-01,26OHA"
			(at -0.9906 1.22047 270)
			(unlocked yes)
			(layer "F.Fab")
			(hide yes)
			(effects
				(font
					(size 0.7874 0.5842)
					(thickness 0.1524)
				)
				(justify left)
			)
		)
		(duplicate_pad_numbers_are_jumpers no)
		(fp_line
			(start -1.3208 0.7112)
			(end -1.3208 -0.7112)
			(stroke
				(width 0.1)
				(type default)
			)
			(layer "F.SilkS")
		)
		(fp_line
			(start 1.3208 0.7112)
			(end -1.3208 0.7112)
			(stroke
				(width 0.1)
				(type default)
			)
			(layer "F.SilkS")
		)
		(fp_line
			(start -1.3208 -0.7112)
			(end 1.3208 -0.7112)
			(stroke
				(width 0.1)
				(type default)
			)
			(layer "F.SilkS")
		)
		(fp_line
			(start 1.3208 -0.7112)
			(end 1.3208 0.7112)
			(stroke
				(width 0.1)
				(type default)
			)
			(layer "F.SilkS")
		)
		(fp_rect
			(start -1.3208 0.7112)
			(end 1.3208 -0.7112)
			(stroke
				(width 0)
				(type default)
			)
			(fill no)
			(layer "F.CrtYd")
		)
		(fp_line
			(start -0.8128 0.4572)
			(end -0.8128 -0.4572)
			(stroke
				(width 0.1)
				(type default)
			)
			(layer "F.Fab")
		)
		(fp_line
			(start 0.8128 0.4572)
			(end -0.8128 0.4572)
			(stroke
				(width 0.1)
				(type default)
			)
			(layer "F.Fab")
		)
		(fp_line
			(start -0.8128 -0.4572)
			(end 0.8128 -0.4572)
			(stroke
				(width 0.1)
				(type default)
			)
			(layer "F.Fab")
		)
		(fp_line
			(start 0.8128 -0.4572)
			(end 0.8128 0.4572)
			(stroke
				(width 0.1)
				(type default)
			)
			(layer "F.Fab")
		)
		(pad "1" smd rect
			(at -0.6858 0 270)
			(size 0.762 0.8636)
			(layers "F.Cu" "F.Mask" "F.Paste")
			(net "UNNAMED_525_CAPACITOR_I7_1")
		)
		(pad "2" smd rect
			(at 0.6858 0 270)
			(size 0.762 0.8636)
			(layers "F.Cu" "F.Mask" "F.Paste")
			(net "UNNAMED_525_CAPACITOR_I16_1")
		)
		(zone
			(layer "F.Cu")
			(hatch none 0.5)
			(connect_pads
				(clearance 0)
			)
			(min_thickness 0.25)
			(keepout
				(tracks not_allowed)
				(vias allowed)
				(pads allowed)
				(copperpour not_allowed)
				(footprints allowed)
			)
			(placement
				(enabled no)
				(sheetname "")
			)
			(fill
				(thermal_gap 0.5)
				(thermal_bridge_width 0.5)
				(island_removal_mode 0)
			)
			(polygon
				(pts
					(xy 44.2468 -80.4164) (xy 44.2468 -80.1116) (xy 45.1612 -80.1116) (xy 45.1612 -80.4164)
				)
			)
		)
		(zone
			(layer "F.Cu")
			(hatch none 0.5)
			(connect_pads
				(clearance 0)
			)
			(min_thickness 0.25)
			(keepout
				(tracks allowed)
				(vias not_allowed)
				(pads allowed)
				(copperpour not_allowed)
				(footprints allowed)
			)
			(placement
				(enabled no)
				(sheetname "")
			)
			(fill
				(thermal_gap 0.5)
				(thermal_bridge_width 0.5)
				(island_removal_mode 0)
			)
			(polygon
				(pts
					(xy 44.2468 -80.4164) (xy 44.2468 -80.1116) (xy 45.1612 -80.1116) (xy 45.1612 -80.4164)
				)
			)
		)
	)
	(footprint ""
		(layer "F.Cu")
		(at 13.899896 -32.599884 -90)
		(property "Reference" "U13"
			(at 1.738884 -2.649474 90)
			(unlocked yes)
			(layer "F.SilkS")
			(effects
				(font
					(size 0.7874 0.5842)
					(thickness 0.1524)
				)
			)
		)
		(property "Value" ""
			(at 0 0 270)
			(layer "F.Fab")
			(effects
				(font
					(size 1.27 1.27)
				)
			)
		)
		(property "Device Type" "74HCT2G125DP_TSSOP8-G220-00055A"
			(at 0 2.413 270)
			(unlocked yes)
			(layer "F.Fab")
			(hide yes)
			(effects
				(font
					(size 0.7874 0.5842)
					(thickness 0.1524)
				)
			)
		)
		(property "User Part Number" "PARTNUM*"
			(at 0 3.6068 270)
			(unlocked yes)
			(layer "Cmts.User")
			(hide yes)
			(effects
				(font
					(size 0.7874 0.5842)
					(thickness 0.1524)
				)
			)
		)
		(duplicate_pad_numbers_are_jumpers no)
		(fp_line
			(start -2.426716 1.304036)
			(end -2.426716 -1.304036)
			(stroke
				(width 0.1)
				(type default)
			)
			(layer "F.SilkS")
		)
		(fp_line
			(start 2.426716 1.304036)
			(end -2.426716 1.304036)
			(stroke
				(width 0.1)
				(type default)
			)
			(layer "F.SilkS")
		)
		(fp_line
			(start -2.426716 -1.304036)
			(end 2.426716 -1.304036)
			(stroke
				(width 0.1)
				(type default)
			)
			(layer "F.SilkS")
		)
		(fp_line
			(start 2.426716 -1.304036)
			(end 2.426716 1.304036)
			(stroke
				(width 0.1)
				(type default)
			)
			(layer "F.SilkS")
		)
		(fp_poly
			(pts
				(arc
					(start -3.21437 -1.465326)
					(mid -3.21437 -0.703326)
					(end -3.21437 -1.465326)
				)
			)
			(stroke
				(width 0)
				(type default)
			)
			(fill yes)
			(layer "F.SilkS")
		)
		(fp_poly
			(pts
				(xy -2.680716 1.558036) (xy 2.680716 1.558036) (xy 2.680716 -1.558036) (xy -2.680716 -1.558036)
			)
			(stroke
				(width 0)
				(type default)
			)
			(fill no)
			(layer "F.CrtYd")
		)
		(fp_line
			(start -1.199896 1.050036)
			(end 1.199896 1.050036)
			(stroke
				(width 0.1)
				(type default)
			)
			(layer "F.Fab")
		)
		(fp_line
			(start 1.199896 1.050036)
			(end 1.199896 -1.050036)
			(stroke
				(width 0.1)
				(type default)
			)
			(layer "F.Fab")
		)
		(fp_line
			(start -1.199896 -1.050036)
			(end -1.199896 1.050036)
			(stroke
				(width 0.1)
				(type default)
			)
			(layer "F.Fab")
		)
		(fp_line
			(start 1.199896 -1.050036)
			(end -1.199896 -1.050036)
			(stroke
				(width 0.1)
				(type default)
			)
			(layer "F.Fab")
		)
		(fp_poly
			(pts
				(arc
					(start -1.94437 -1.211326)
					(mid -1.94437 -0.449326)
					(end -1.94437 -1.211326)
				)
			)
			(stroke
				(width 0)
				(type default)
			)
			(fill yes)
			(layer "F.Fab")
		)
		(fp_text user "4"
			(at -1.813052 1.834896 0)
			(unlocked yes)
			(layer "F.SilkS")
			(effects
				(font
					(size 0.635 0.4064)
					(thickness 0.1524)
				)
			)
		)
		(fp_text user "5"
			(at 2.913634 1.453896 0)
			(unlocked yes)
			(layer "F.SilkS")
			(effects
				(font
					(size 0.635 0.4064)
					(thickness 0.1524)
				)
			)
		)
		(fp_text user "8"
			(at 2.913634 -1.340104 0)
			(unlocked yes)
			(layer "F.SilkS")
			(effects
				(font
					(size 0.635 0.4064)
					(thickness 0.1524)
				)
			)
		)
		(fp_text user "4"
			(at -1.767332 0.945896 0)
			(unlocked yes)
			(layer "F.Fab")
			(effects
				(font
					(size 0.7874 0.5842)
					(thickness 0.1524)
				)
			)
		)
		(fp_text user "5"
			(at 1.947926 0.710184 0)
			(unlocked yes)
			(layer "F.Fab")
			(effects
				(font
					(size 0.7874 0.5842)
					(thickness 0.1524)
				)
			)
		)
		(fp_text user "8"
			(at 1.96088 -0.910844 0)
			(unlocked yes)
			(layer "F.Fab")
			(effects
				(font
					(size 0.7874 0.5842)
					(thickness 0.1524)
				)
			)
		)
		(pad "1" smd rect
			(at -1.690116 -0.749808 270)
			(size 0.9652 0.3048)
			(layers "F.Cu" "F.Mask" "F.Paste")
			(net "SMA3_SIG_OUT_BF_EN_N")
		)
		(pad "2" smd rect
			(at -1.690116 -0.249936 270)
			(size 0.9652 0.3048)
			(layers "F.Cu" "F.Mask" "F.Paste")
			(net "UNNAMED_12_74HCT2G125DPTSSOP8_I")
		)
		(pad "3" smd rect
			(at -1.690116 0.249936 270)
			(size 0.9652 0.3048)
			(layers "F.Cu" "F.Mask" "F.Paste")
			(net "BF_ANT3_IN")
		)
		(pad "4" smd rect
			(at -1.690116 0.749808 270)
			(size 0.9652 0.3048)
			(layers "F.Cu" "F.Mask" "F.Paste")
			(net "SG")
		)
		(pad "5" smd rect
			(at 1.690116 0.749808 270)
			(size 0.9652 0.3048)
			(layers "F.Cu" "F.Mask" "F.Paste")
			(net "BF_SMA3_SIG_IO_CONN")
		)
		(pad "6" smd rect
			(at 1.690116 0.249936 270)
			(size 0.9652 0.3048)
			(layers "F.Cu" "F.Mask" "F.Paste")
			(net "BF_SMA3_SIG_IO_CONN")
		)
		(pad "7" smd rect
			(at 1.690116 -0.249936 270)
			(size 0.9652 0.3048)
			(layers "F.Cu" "F.Mask" "F.Paste")
			(net "SMA3_SIG_IN_BF_EN_N")
		)
		(pad "8" smd rect
			(at 1.690116 -0.749808 270)
			(size 0.9652 0.3048)
			(layers "F.Cu" "F.Mask" "F.Paste")
			(net "XP3R3V_FPGA")
		)
	)
	(footprint ""
		(layer "F.Cu")
		(at 13.843 -43.434)
		(property "Reference" "TP29"
			(at 0.7366 -0.60325 0)
			(unlocked yes)
			(layer "F.SilkS")
			(effects
				(font
					(size 0.635 0.4064)
					(thickness 0.1524)
				)
				(justify left)
			)
		)
		(property "Value" ""
			(at 0 0 0)
			(layer "F.Fab")
			(effects
				(font
					(size 1.27 1.27)
				)
			)
		)
		(property "Device Type" "TP_PIONT-TP010CT020B030_PTH-TPA"
			(at -1.341882 0.996696 0)
			(unlocked yes)
			(layer "F.Fab")
			(hide yes)
			(effects
				(font
					(size 0.7874 0.5842)
					(thickness 0.000001)
				)
				(justify left)
			)
		)
		(duplicate_pad_numbers_are_jumpers no)
		(fp_poly
			(pts
				(arc
					(start 0.889 0)
					(mid -0.889 0)
					(end 0.889 0)
				)
			)
			(stroke
				(width 0)
				(type default)
			)
			(fill no)
			(layer "B.CrtYd")
		)
		(fp_poly
			(pts
				(arc
					(start 0.889 0)
					(mid -0.889 0)
					(end 0.889 0)
				)
			)
			(stroke
				(width 0)
				(type default)
			)
			(fill no)
			(layer "F.CrtYd")
		)
		(pad "1" thru_hole circle
			(at 0 0)
			(size 0.508 0.508)
			(drill 0.254)
			(layers "*.Cu" "*.Mask")
			(remove_unused_layers no)
			(net "SMA2_SIG_IN_BF_EN_N")
			(clearance 0.1016)
			(padstack
				(mode front_inner_back)
				(layer "Inner"
					(shape circle)
					(size 0.508 0.508)
					(clearance 0.1016)
				)
				(layer "B.Cu"
					(shape circle)
					(size 0.762 0.762)
					(clearance -0.0254)
				)
			)
		)
	)
	(footprint ""
		(layer "F.Cu")
		(at 29.337 -94.234 -90)
		(property "Reference" "R128"
			(at -4.953 0.84963 90)
			(unlocked yes)
			(layer "F.SilkS")
			(effects
				(font
					(size 0.7874 0.5842)
					(thickness 0.1524)
				)
			)
		)
		(property "Value" "VAL*"
			(at 0.02032 2.13233 270)
			(unlocked yes)
			(layer "F.Fab")
			(hide yes)
			(effects
				(font
					(size 0.7874 0.5842)
					(thickness 0.1524)
				)
			)
		)
		(property "Tolerance" "TOL*"
			(at 0.044704 3.05435 270)
			(unlocked yes)
			(layer "Cmts.User")
			(hide yes)
			(effects
				(font
					(size 0.7874 0.5842)
					(thickness 0.1524)
				)
			)
		)
		(property "User Part Number" "PARTNUM*"
			(at 0.02032 4.024884 270)
			(unlocked yes)
			(layer "Cmts.User")
			(hide yes)
			(effects
				(font
					(size 0.7874 0.5842)
					(thickness 0.1524)
				)
			)
		)
		(property "Device Type" "RESISTOR-G155-100R0-J0,0OHM,-"
			(at 0.008382 1.210564 270)
			(unlocked yes)
			(layer "F.Fab")
			(hide yes)
			(effects
				(font
					(size 0.7874 0.5842)
					(thickness 0.1524)
				)
			)
		)
		(duplicate_pad_numbers_are_jumpers no)
		(fp_line
			(start -1.143 0.5588)
			(end 1.143 0.5588)
			(stroke
				(width 0.1)
				(type default)
			)
			(layer "F.SilkS")
		)
		(fp_line
			(start 1.143 0.5588)
			(end 1.143 -0.5588)
			(stroke
				(width 0.1)
				(type default)
			)
			(layer "F.SilkS")
		)
		(fp_line
			(start -1.143 -0.5588)
			(end -1.143 0.5588)
			(stroke
				(width 0.1)
				(type default)
			)
			(layer "F.SilkS")
		)
		(fp_line
			(start 1.143 -0.5588)
			(end -1.143 -0.5588)
			(stroke
				(width 0.1)
				(type default)
			)
			(layer "F.SilkS")
		)
		(fp_poly
			(pts
				(xy -1.143 0.5588) (xy 1.143 0.5588) (xy 1.143 -0.5588) (xy -1.143 -0.5588)
			)
			(stroke
				(width 0)
				(type default)
			)
			(fill no)
			(layer "F.CrtYd")
		)
		(fp_line
			(start -0.508 0.3048)
			(end 0.508 0.3048)
			(stroke
				(width 0.1)
				(type default)
			)
			(layer "F.Fab")
		)
		(fp_line
			(start 0.508 0.3048)
			(end 0.508 -0.3048)
			(stroke
				(width 0.1)
				(type default)
			)
			(layer "F.Fab")
		)
		(fp_line
			(start -0.508 -0.3048)
			(end -0.508 0.3048)
			(stroke
				(width 0.1)
				(type default)
			)
			(layer "F.Fab")
		)
		(fp_line
			(start 0.508 -0.3048)
			(end -0.508 -0.3048)
			(stroke
				(width 0.1)
				(type default)
			)
			(layer "F.Fab")
		)
		(pad "1" smd rect
			(at -0.5334 0 270)
			(size 0.7112 0.6096)
			(layers "F.Cu" "F.Mask" "F.Paste")
			(net "FT_USB_DM")
		)
		(pad "2" smd rect
			(at 0.5334 0 270)
			(size 0.7112 0.6096)
			(layers "F.Cu" "F.Mask" "F.Paste")
			(net "R_FT_USB_DM")
		)
		(zone
			(layer "F.Cu")
			(hatch none 0.5)
			(connect_pads
				(clearance 0)
			)
			(min_thickness 0.25)
			(keepout
				(tracks not_allowed)
				(vias allowed)
				(pads allowed)
				(copperpour not_allowed)
				(footprints allowed)
			)
			(placement
				(enabled no)
				(sheetname "")
			)
			(fill
				(thermal_gap 0.5)
				(thermal_bridge_width 0.5)
				(island_removal_mode 0)
			)
			(polygon
				(pts
					(xy 29.0322 -94.3102) (xy 29.0322 -94.1578) (xy 29.6418 -94.1578) (xy 29.6418 -94.3102)
				)
			)
		)
		(zone
			(layer "F.Cu")
			(hatch none 0.5)
			(connect_pads
				(clearance 0)
			)
			(min_thickness 0.25)
			(keepout
				(tracks allowed)
				(vias not_allowed)
				(pads allowed)
				(copperpour not_allowed)
				(footprints allowed)
			)
			(placement
				(enabled no)
				(sheetname "")
			)
			(fill
				(thermal_gap 0.5)
				(thermal_bridge_width 0.5)
				(island_removal_mode 0)
			)
			(polygon
				(pts
					(xy 29.0322 -94.3102) (xy 29.0322 -94.1578) (xy 29.6418 -94.1578) (xy 29.6418 -94.3102)
				)
			)
		)
	)
	(footprint ""
		(layer "F.Cu")
		(at 42.4434 -103.9114)
		(property "Reference" "C33"
			(at 3.9116 -1.59893 0)
			(unlocked yes)
			(layer "F.SilkS")
			(effects
				(font
					(size 0.7874 0.5842)
					(thickness 0.1524)
				)
			)
		)
		(property "Value" "VAL*"
			(at 0.0762 2.067306 0)
			(unlocked yes)
			(layer "F.Fab")
			(hide yes)
			(effects
				(font
					(size 0.7874 0.5842)
					(thickness 0.1524)
				)
			)
		)
		(property "Device Type" "CAPACITOR-G105-0B104-EK,0.1UF,A"
			(at 0.0508 1.127506 0)
			(unlocked yes)
			(layer "F.Fab")
			(hide yes)
			(effects
				(font
					(size 0.7874 0.5842)
					(thickness 0.1524)
				)
			)
		)
		(property "User Part Number" "PARTNUM*"
			(at 0.1016 4.023106 0)
			(unlocked yes)
			(layer "Cmts.User")
			(hide yes)
			(effects
				(font
					(size 0.7874 0.5842)
					(thickness 0.1524)
				)
			)
		)
		(property "Tolerance" "TOL*"
			(at 0.0762 3.032506 0)
			(unlocked yes)
			(layer "Cmts.User")
			(hide yes)
			(effects
				(font
					(size 0.7874 0.5842)
					(thickness 0.1524)
				)
			)
		)
		(duplicate_pad_numbers_are_jumpers no)
		(fp_line
			(start -1.143 -0.5588)
			(end -1.143 0.5588)
			(stroke
				(width 0.1)
				(type default)
			)
			(layer "F.SilkS")
		)
		(fp_line
			(start -1.143 0.5588)
			(end 1.143 0.5588)
			(stroke
				(width 0.1)
				(type default)
			)
			(layer "F.SilkS")
		)
		(fp_line
			(start 1.143 -0.5588)
			(end -1.143 -0.5588)
			(stroke
				(width 0.1)
				(type default)
			)
			(layer "F.SilkS")
		)
		(fp_line
			(start 1.143 0.5588)
			(end 1.143 -0.5588)
			(stroke
				(width 0.1)
				(type default)
			)
			(layer "F.SilkS")
		)
		(fp_rect
			(start 1.143 -0.5588)
			(end -1.143 0.5588)
			(stroke
				(width 0)
				(type default)
			)
			(fill no)
			(layer "F.CrtYd")
		)
		(fp_line
			(start -0.508 -0.3048)
			(end -0.508 0.3048)
			(stroke
				(width 0.1)
				(type default)
			)
			(layer "F.Fab")
		)
		(fp_line
			(start -0.508 0.3048)
			(end 0.508 0.3048)
			(stroke
				(width 0.1)
				(type default)
			)
			(layer "F.Fab")
		)
		(fp_line
			(start 0.508 -0.3048)
			(end -0.508 -0.3048)
			(stroke
				(width 0.1)
				(type default)
			)
			(layer "F.Fab")
		)
		(fp_line
			(start 0.508 0.3048)
			(end 0.508 -0.3048)
			(stroke
				(width 0.1)
				(type default)
			)
			(layer "F.Fab")
		)
		(pad "1" smd rect
			(at -0.5334 0)
			(size 0.7112 0.6096)
			(layers "F.Cu" "F.Mask" "F.Paste")
			(net "VIN_XP5R0V")
		)
		(pad "2" smd rect
			(at 0.5334 0)
			(size 0.7112 0.6096)
			(layers "F.Cu" "F.Mask" "F.Paste")
			(net "SG")
		)
		(zone
			(layer "F.Cu")
			(hatch none 0.5)
			(connect_pads
				(clearance 0)
			)
			(min_thickness 0.25)
			(keepout
				(tracks allowed)
				(vias not_allowed)
				(pads allowed)
				(copperpour not_allowed)
				(footprints allowed)
			)
			(placement
				(enabled no)
				(sheetname "")
			)
			(fill
				(thermal_gap 0.5)
				(thermal_bridge_width 0.5)
				(island_removal_mode 0)
			)
			(polygon
				(pts
					(xy 42.5196 -104.2162) (xy 42.3672 -104.2162) (xy 42.3672 -103.6066) (xy 42.5196 -103.6066)
				)
			)
		)
	)
	(footprint ""
		(layer "F.Cu")
		(at 87.249 -64.3128 90)
		(property "Reference" "C281"
			(at 13.2842 -9.61263 90)
			(unlocked yes)
			(layer "F.SilkS")
			(effects
				(font
					(size 0.7874 0.5842)
					(thickness 0.1524)
				)
			)
		)
		(property "Value" "VAL*"
			(at 0.0762 2.067306 90)
			(unlocked yes)
			(layer "F.Fab")
			(hide yes)
			(effects
				(font
					(size 0.7874 0.5842)
					(thickness 0.1524)
				)
			)
		)
		(property "Device Type" "CAPACITOR-G105-0B104-EK,0.1UF,A"
			(at 0.0508 1.127506 90)
			(unlocked yes)
			(layer "F.Fab")
			(hide yes)
			(effects
				(font
					(size 0.7874 0.5842)
					(thickness 0.1524)
				)
			)
		)
		(property "User Part Number" "PARTNUM*"
			(at 0.1016 4.023106 90)
			(unlocked yes)
			(layer "Cmts.User")
			(hide yes)
			(effects
				(font
					(size 0.7874 0.5842)
					(thickness 0.1524)
				)
			)
		)
		(property "Tolerance" "TOL*"
			(at 0.0762 3.032506 90)
			(unlocked yes)
			(layer "Cmts.User")
			(hide yes)
			(effects
				(font
					(size 0.7874 0.5842)
					(thickness 0.1524)
				)
			)
		)
		(duplicate_pad_numbers_are_jumpers no)
		(fp_line
			(start 1.143 -0.5588)
			(end -1.143 -0.5588)
			(stroke
				(width 0.1)
				(type default)
			)
			(layer "F.SilkS")
		)
		(fp_line
			(start -1.143 -0.5588)
			(end -1.143 0.5588)
			(stroke
				(width 0.1)
				(type default)
			)
			(layer "F.SilkS")
		)
		(fp_line
			(start 1.143 0.5588)
			(end 1.143 -0.5588)
			(stroke
				(width 0.1)
				(type default)
			)
			(layer "F.SilkS")
		)
		(fp_line
			(start -1.143 0.5588)
			(end 1.143 0.5588)
			(stroke
				(width 0.1)
				(type default)
			)
			(layer "F.SilkS")
		)
		(fp_rect
			(start -1.143 -0.5588)
			(end 1.143 0.5588)
			(stroke
				(width 0)
				(type default)
			)
			(fill no)
			(layer "F.CrtYd")
		)
		(fp_line
			(start 0.508 -0.3048)
			(end -0.508 -0.3048)
			(stroke
				(width 0.1)
				(type default)
			)
			(layer "F.Fab")
		)
		(fp_line
			(start -0.508 -0.3048)
			(end -0.508 0.3048)
			(stroke
				(width 0.1)
				(type default)
			)
			(layer "F.Fab")
		)
		(fp_line
			(start 0.508 0.3048)
			(end 0.508 -0.3048)
			(stroke
				(width 0.1)
				(type default)
			)
			(layer "F.Fab")
		)
		(fp_line
			(start -0.508 0.3048)
			(end 0.508 0.3048)
			(stroke
				(width 0.1)
				(type default)
			)
			(layer "F.Fab")
		)
		(pad "1" smd rect
			(at -0.5334 0 90)
			(size 0.7112 0.6096)
			(layers "F.Cu" "F.Mask" "F.Paste")
			(net "VDD_BNO085")
		)
		(pad "2" smd rect
			(at 0.5334 0 90)
			(size 0.7112 0.6096)
			(layers "F.Cu" "F.Mask" "F.Paste")
			(net "SG")
		)
		(zone
			(layer "F.Cu")
			(hatch none 0.5)
			(connect_pads
				(clearance 0)
			)
			(min_thickness 0.25)
			(keepout
				(tracks allowed)
				(vias not_allowed)
				(pads allowed)
				(copperpour not_allowed)
				(footprints allowed)
			)
			(placement
				(enabled no)
				(sheetname "")
			)
			(fill
				(thermal_gap 0.5)
				(thermal_bridge_width 0.5)
				(island_removal_mode 0)
			)
			(polygon
				(pts
					(xy 86.9442 -64.2366) (xy 87.5538 -64.2366) (xy 87.5538 -64.389) (xy 86.9442 -64.389)
				)
			)
		)
	)
	(footprint ""
		(layer "F.Cu")
		(at 49.784 -131.572)
		(property "Reference" "SP52"
			(at 0 0 0)
			(layer "F.SilkS")
			(hide yes)
			(effects
				(font
					(size 1.27 1.27)
				)
			)
		)
		(property "Value" ""
			(at 0 0 0)
			(layer "F.Fab")
			(effects
				(font
					(size 1.27 1.27)
				)
			)
		)
		(duplicate_pad_numbers_are_jumpers no)
	)
	(footprint ""
		(layer "F.Cu")
		(at 41.656 -80.518 180)
		(property "Reference" "CR2"
			(at 0.635 4.40563 0)
			(unlocked yes)
			(layer "F.SilkS")
			(effects
				(font
					(size 0.7874 0.5842)
					(thickness 0.1524)
				)
			)
		)
		(property "Value" ""
			(at 0 0 180)
			(layer "F.Fab")
			(effects
				(font
					(size 1.27 1.27)
				)
			)
		)
		(property "Device Type" "DIODE_2F-G122-10186-01"
			(at 0 2.037842 180)
			(unlocked yes)
			(layer "F.Fab")
			(hide yes)
			(effects
				(font
					(size 0.7874 0.5842)
					(thickness 0.000001)
				)
			)
		)
		(property "User Part Number" "PARTNUM*"
			(at 0 3.231642 180)
			(unlocked yes)
			(layer "Cmts.User")
			(hide yes)
			(effects
				(font
					(size 0.7874 0.5842)
					(thickness 0.000001)
				)
			)
		)
		(duplicate_pad_numbers_are_jumpers no)
		(fp_line
			(start 1.608074 0.928878)
			(end -1.608074 0.928878)
			(stroke
				(width 0.1)
				(type default)
			)
			(layer "F.SilkS")
		)
		(fp_line
			(start 1.608074 -0.928878)
			(end 1.608074 0.928878)
			(stroke
				(width 0.1)
				(type default)
			)
			(layer "F.SilkS")
		)
		(fp_line
			(start -1.608074 0.928878)
			(end -1.608074 -0.928878)
			(stroke
				(width 0.1)
				(type default)
			)
			(layer "F.SilkS")
		)
		(fp_line
			(start -1.608074 -0.928878)
			(end 1.608074 -0.928878)
			(stroke
				(width 0.1)
				(type default)
			)
			(layer "F.SilkS")
		)
		(fp_poly
			(pts
				(xy -2.116074 -0.928878) (xy -2.116074 0.928878) (xy -1.608074 0.928878) (xy -1.608074 -0.928878)
			)
			(stroke
				(width 0)
				(type default)
			)
			(fill yes)
			(layer "F.SilkS")
		)
		(fp_poly
			(pts
				(xy -2.116074 1.182878) (xy 1.862074 1.182878) (xy 1.862074 -1.182878) (xy -2.116074 -1.182878)
			)
			(stroke
				(width 0)
				(type default)
			)
			(fill no)
			(layer "F.CrtYd")
		)
		(fp_line
			(start 0.899922 0.674878)
			(end -0.899922 0.674878)
			(stroke
				(width 0.1)
				(type default)
			)
			(layer "F.Fab")
		)
		(fp_line
			(start 0.899922 -0.674878)
			(end 0.899922 0.674878)
			(stroke
				(width 0.1)
				(type default)
			)
			(layer "F.Fab")
		)
		(fp_line
			(start -0.899922 0.674878)
			(end -0.899922 -0.674878)
			(stroke
				(width 0.1)
				(type default)
			)
			(layer "F.Fab")
		)
		(fp_line
			(start -0.899922 -0.674878)
			(end 0.899922 -0.674878)
			(stroke
				(width 0.1)
				(type default)
			)
			(layer "F.Fab")
		)
		(fp_poly
			(pts
				(xy -0.899922 -0.674878) (xy -0.899922 0.674878) (xy -0.391922 0.674878) (xy -0.391922 -0.674878)
			)
			(stroke
				(width 0)
				(type default)
			)
			(fill yes)
			(layer "F.Fab")
		)
		(fp_text user "A"
			(at 2.413 0.59563 0)
			(unlocked yes)
			(layer "F.SilkS")
			(effects
				(font
					(size 0.7874 0.5842)
					(thickness 0.1524)
				)
			)
		)
		(fp_text user "C"
			(at -2.032 -1.68275 0)
			(unlocked yes)
			(layer "F.SilkS")
			(effects
				(font
					(size 0.635 0.4064)
					(thickness 0.1524)
				)
			)
		)
		(fp_text user "A"
			(at 2.262124 0.156718 0)
			(unlocked yes)
			(layer "F.Fab")
			(effects
				(font
					(size 0.7874 0.5842)
					(thickness 0.1524)
				)
			)
		)
		(fp_text user "C"
			(at -1.778 0.97663 0)
			(unlocked yes)
			(layer "F.Fab")
			(effects
				(font
					(size 0.7874 0.5842)
					(thickness 0.1524)
				)
			)
		)
		(pad "A" smd rect
			(at 1.100074 0 180)
			(size 0.508 0.508)
			(layers "F.Cu" "F.Mask" "F.Paste")
			(net "XP5R0V_FT4232")
		)
		(pad "C" smd rect
			(at -1.100074 0 180)
			(size 0.508 0.508)
			(layers "F.Cu" "F.Mask" "F.Paste")
			(net "UNNAMED_525_CAPACITOR_I7_1")
		)
	)
	(footprint ""
		(layer "F.Cu")
		(at 57.531 -129.54)
		(property "Reference" "SP58"
			(at 0 0 0)
			(layer "F.SilkS")
			(hide yes)
			(effects
				(font
					(size 1.27 1.27)
				)
			)
		)
		(property "Value" ""
			(at 0 0 0)
			(layer "F.Fab")
			(effects
				(font
					(size 1.27 1.27)
				)
			)
		)
		(duplicate_pad_numbers_are_jumpers no)
	)
	(footprint ""
		(layer "F.Cu")
		(at 19.468338 -49.022 180)
		(property "Reference" "R395"
			(at -3.518662 0.21463 0)
			(unlocked yes)
			(layer "F.SilkS")
			(effects
				(font
					(size 0.7874 0.5842)
					(thickness 0.1524)
				)
			)
		)
		(property "Value" "VAL*"
			(at 0.02032 2.13233 180)
			(unlocked yes)
			(layer "F.Fab")
			(hide yes)
			(effects
				(font
					(size 0.7874 0.5842)
					(thickness 0.1524)
				)
			)
		)
		(property "Tolerance" "TOL*"
			(at 0.044704 3.05435 180)
			(unlocked yes)
			(layer "Cmts.User")
			(hide yes)
			(effects
				(font
					(size 0.7874 0.5842)
					(thickness 0.1524)
				)
			)
		)
		(property "User Part Number" "PARTNUM*"
			(at 0.02032 4.024884 180)
			(unlocked yes)
			(layer "Cmts.User")
			(hide yes)
			(effects
				(font
					(size 0.7874 0.5842)
					(thickness 0.1524)
				)
			)
		)
		(property "Device Type" "RESISTOR-G155-133R0-01,33OHM,1%"
			(at 0.008382 1.210564 180)
			(unlocked yes)
			(layer "F.Fab")
			(hide yes)
			(effects
				(font
					(size 0.7874 0.5842)
					(thickness 0.1524)
				)
			)
		)
		(duplicate_pad_numbers_are_jumpers no)
		(fp_line
			(start 1.143 0.5588)
			(end 1.143 -0.5588)
			(stroke
				(width 0.1)
				(type default)
			)
			(layer "F.SilkS")
		)
		(fp_line
			(start 1.143 -0.5588)
			(end -1.143 -0.5588)
			(stroke
				(width 0.1)
				(type default)
			)
			(layer "F.SilkS")
		)
		(fp_line
			(start -1.143 0.5588)
			(end 1.143 0.5588)
			(stroke
				(width 0.1)
				(type default)
			)
			(layer "F.SilkS")
		)
		(fp_line
			(start -1.143 -0.5588)
			(end -1.143 0.5588)
			(stroke
				(width 0.1)
				(type default)
			)
			(layer "F.SilkS")
		)
		(fp_rect
			(start -1.143 -0.5588)
			(end 1.143 0.5588)
			(stroke
				(width 0)
				(type default)
			)
			(fill no)
			(layer "F.CrtYd")
		)
		(fp_line
			(start 0.508 0.3048)
			(end 0.508 -0.3048)
			(stroke
				(width 0.1)
				(type default)
			)
			(layer "F.Fab")
		)
		(fp_line
			(start 0.508 -0.3048)
			(end -0.508 -0.3048)
			(stroke
				(width 0.1)
				(type default)
			)
			(layer "F.Fab")
		)
		(fp_line
			(start -0.508 0.3048)
			(end 0.508 0.3048)
			(stroke
				(width 0.1)
				(type default)
			)
			(layer "F.Fab")
		)
		(fp_line
			(start -0.508 -0.3048)
			(end -0.508 0.3048)
			(stroke
				(width 0.1)
				(type default)
			)
			(layer "F.Fab")
		)
		(pad "1" smd rect
			(at -0.5334 0 180)
			(size 0.7112 0.6096)
			(layers "F.Cu" "F.Mask" "F.Paste")
			(net "SMA4_LED_GREEN_N")
		)
		(pad "2" smd rect
			(at 0.5334 0 180)
			(size 0.7112 0.6096)
			(layers "F.Cu" "F.Mask" "F.Paste")
			(net "UNNAMED_14_LED4PV14_I268_4")
		)
		(zone
			(layer "F.Cu")
			(hatch none 0.5)
			(connect_pads
				(clearance 0)
			)
			(min_thickness 0.25)
			(keepout
				(tracks not_allowed)
				(vias allowed)
				(pads allowed)
				(copperpour not_allowed)
				(footprints allowed)
			)
			(placement
				(enabled no)
				(sheetname "")
			)
			(fill
				(thermal_gap 0.5)
				(thermal_bridge_width 0.5)
				(island_removal_mode 0)
			)
			(polygon
				(pts
					(xy 19.544538 -48.7172) (xy 19.544538 -49.3268) (xy 19.392138 -49.3268) (xy 19.392138 -48.7172)
				)
			)
		)
		(zone
			(layer "F.Cu")
			(hatch none 0.5)
			(connect_pads
				(clearance 0)
			)
			(min_thickness 0.25)
			(keepout
				(tracks allowed)
				(vias not_allowed)
				(pads allowed)
				(copperpour not_allowed)
				(footprints allowed)
			)
			(placement
				(enabled no)
				(sheetname "")
			)
			(fill
				(thermal_gap 0.5)
				(thermal_bridge_width 0.5)
				(island_removal_mode 0)
			)
			(polygon
				(pts
					(xy 19.544538 -48.7172) (xy 19.544538 -49.3268) (xy 19.392138 -49.3268) (xy 19.392138 -48.7172)
				)
			)
		)
	)
	(footprint ""
		(layer "F.Cu")
		(at 105.3846 -58.3692)
		(property "Reference" "TP183"
			(at 3.74015 2.159 90)
			(unlocked yes)
			(layer "F.SilkS")
			(effects
				(font
					(size 0.635 0.4064)
					(thickness 0.1524)
				)
				(justify left)
			)
		)
		(property "Value" ""
			(at 0 0 0)
			(layer "F.Fab")
			(effects
				(font
					(size 1.27 1.27)
				)
			)
		)
		(property "Device Type" "TP_PIONT-TP010CT020B030_PTH-TPA"
			(at -1.341882 0.996696 0)
			(unlocked yes)
			(layer "F.Fab")
			(hide yes)
			(effects
				(font
					(size 0.7874 0.5842)
					(thickness 0.1524)
				)
				(justify left)
			)
		)
		(duplicate_pad_numbers_are_jumpers no)
		(fp_poly
			(pts
				(arc
					(start 0.889 0)
					(mid -0.889 0)
					(end 0.889 0)
				)
			)
			(stroke
				(width 0)
				(type default)
			)
			(fill no)
			(layer "B.CrtYd")
		)
		(fp_poly
			(pts
				(arc
					(start 0.889 0)
					(mid -0.889 0)
					(end 0.889 0)
				)
			)
			(stroke
				(width 0)
				(type default)
			)
			(fill no)
			(layer "F.CrtYd")
		)
		(pad "1" thru_hole circle
			(at 0 0)
			(size 0.508 0.508)
			(drill 0.254)
			(layers "*.Cu" "*.Mask")
			(remove_unused_layers no)
			(net "IO_L22P_16")
			(clearance 0.1016)
			(padstack
				(mode front_inner_back)
				(layer "Inner"
					(shape circle)
					(size 0.508 0.508)
					(clearance 0.1016)
				)
				(layer "B.Cu"
					(shape circle)
					(size 0.762 0.762)
					(clearance -0.0254)
				)
			)
		)
	)
	(footprint ""
		(layer "F.Cu")
		(at 50.673 -131.826)
		(property "Reference" "SP61"
			(at 0 0 0)
			(layer "F.SilkS")
			(hide yes)
			(effects
				(font
					(size 1.27 1.27)
				)
			)
		)
		(property "Value" ""
			(at 0 0 0)
			(layer "F.Fab")
			(effects
				(font
					(size 1.27 1.27)
				)
			)
		)
		(duplicate_pad_numbers_are_jumpers no)
	)
	(footprint ""
		(layer "F.Cu")
		(at 111.887 -95.123)
		(property "Reference" "R453"
			(at 3.175 0.03937 0)
			(unlocked yes)
			(layer "F.SilkS")
			(effects
				(font
					(size 0.7874 0.5842)
					(thickness 0.1524)
				)
			)
		)
		(property "Value" "VAL*"
			(at 0.02032 2.13233 0)
			(unlocked yes)
			(layer "F.Fab")
			(hide yes)
			(effects
				(font
					(size 0.7874 0.5842)
					(thickness 0.1524)
				)
			)
		)
		(property "Tolerance" "TOL*"
			(at 0.044704 3.05435 0)
			(unlocked yes)
			(layer "Cmts.User")
			(hide yes)
			(effects
				(font
					(size 0.7874 0.5842)
					(thickness 0.1524)
				)
			)
		)
		(property "User Part Number" "PARTNUM*"
			(at 0.02032 4.024884 0)
			(unlocked yes)
			(layer "Cmts.User")
			(hide yes)
			(effects
				(font
					(size 0.7874 0.5842)
					(thickness 0.1524)
				)
			)
		)
		(property "Device Type" "RESISTOR-G155-11001-01,1KOHM,1%"
			(at 0.008382 1.210564 0)
			(unlocked yes)
			(layer "F.Fab")
			(hide yes)
			(effects
				(font
					(size 0.7874 0.5842)
					(thickness 0.1524)
				)
			)
		)
		(duplicate_pad_numbers_are_jumpers no)
		(fp_line
			(start -1.143 -0.5588)
			(end -1.143 0.5588)
			(stroke
				(width 0.1)
				(type default)
			)
			(layer "F.SilkS")
		)
		(fp_line
			(start -1.143 0.5588)
			(end 1.143 0.5588)
			(stroke
				(width 0.1)
				(type default)
			)
			(layer "F.SilkS")
		)
		(fp_line
			(start 1.143 -0.5588)
			(end -1.143 -0.5588)
			(stroke
				(width 0.1)
				(type default)
			)
			(layer "F.SilkS")
		)
		(fp_line
			(start 1.143 0.5588)
			(end 1.143 -0.5588)
			(stroke
				(width 0.1)
				(type default)
			)
			(layer "F.SilkS")
		)
		(fp_poly
			(pts
				(xy -1.143 0.5588) (xy 1.143 0.5588) (xy 1.143 -0.5588) (xy -1.143 -0.5588)
			)
			(stroke
				(width 0)
				(type default)
			)
			(fill no)
			(layer "F.CrtYd")
		)
		(fp_line
			(start -0.508 -0.3048)
			(end -0.508 0.3048)
			(stroke
				(width 0.1)
				(type default)
			)
			(layer "F.Fab")
		)
		(fp_line
			(start -0.508 0.3048)
			(end 0.508 0.3048)
			(stroke
				(width 0.1)
				(type default)
			)
			(layer "F.Fab")
		)
		(fp_line
			(start 0.508 -0.3048)
			(end -0.508 -0.3048)
			(stroke
				(width 0.1)
				(type default)
			)
			(layer "F.Fab")
		)
		(fp_line
			(start 0.508 0.3048)
			(end 0.508 -0.3048)
			(stroke
				(width 0.1)
				(type default)
			)
			(layer "F.Fab")
		)
		(pad "1" smd rect
			(at -0.5334 0)
			(size 0.7112 0.6096)
			(layers "F.Cu" "F.Mask" "F.Paste")
			(net "UNNAMED_524_POWERMOS3PNCHV1_I44")
		)
		(pad "2" smd rect
			(at 0.5334 0)
			(size 0.7112 0.6096)
			(layers "F.Cu" "F.Mask" "F.Paste")
			(net "SG")
		)
		(zone
			(layer "F.Cu")
			(hatch none 0.5)
			(connect_pads
				(clearance 0)
			)
			(min_thickness 0.25)
			(keepout
				(tracks not_allowed)
				(vias allowed)
				(pads allowed)
				(copperpour not_allowed)
				(footprints allowed)
			)
			(placement
				(enabled no)
				(sheetname "")
			)
			(fill
				(thermal_gap 0.5)
				(thermal_bridge_width 0.5)
				(island_removal_mode 0)
			)
			(polygon
				(pts
					(xy 111.8108 -94.8182) (xy 111.9632 -94.8182) (xy 111.9632 -95.4278) (xy 111.8108 -95.4278)
				)
			)
		)
		(zone
			(layer "F.Cu")
			(hatch none 0.5)
			(connect_pads
				(clearance 0)
			)
			(min_thickness 0.25)
			(keepout
				(tracks allowed)
				(vias not_allowed)
				(pads allowed)
				(copperpour not_allowed)
				(footprints allowed)
			)
			(placement
				(enabled no)
				(sheetname "")
			)
			(fill
				(thermal_gap 0.5)
				(thermal_bridge_width 0.5)
				(island_removal_mode 0)
			)
			(polygon
				(pts
					(xy 111.8108 -94.8182) (xy 111.9632 -94.8182) (xy 111.9632 -95.4278) (xy 111.8108 -95.4278)
				)
			)
		)
	)
	(footprint ""
		(layer "F.Cu")
		(at 80.772 -60.6806)
		(property "Reference" "R291"
			(at -10.287 -19.51863 0)
			(unlocked yes)
			(layer "F.SilkS")
			(effects
				(font
					(size 0.7874 0.5842)
					(thickness 0.1524)
				)
			)
		)
		(property "Value" "VAL*"
			(at 0.02032 2.13233 0)
			(unlocked yes)
			(layer "F.Fab")
			(hide yes)
			(effects
				(font
					(size 0.7874 0.5842)
					(thickness 0.1524)
				)
			)
		)
		(property "Tolerance" "TOL*"
			(at 0.044704 3.05435 0)
			(unlocked yes)
			(layer "Cmts.User")
			(hide yes)
			(effects
				(font
					(size 0.7874 0.5842)
					(thickness 0.1524)
				)
			)
		)
		(property "User Part Number" "PARTNUM*"
			(at 0.02032 4.024884 0)
			(unlocked yes)
			(layer "Cmts.User")
			(hide yes)
			(effects
				(font
					(size 0.7874 0.5842)
					(thickness 0.1524)
				)
			)
		)
		(property "Device Type" "RESISTOR-G155-14701-01,4.7KOHMA"
			(at 0.008382 1.210564 0)
			(unlocked yes)
			(layer "F.Fab")
			(hide yes)
			(effects
				(font
					(size 0.7874 0.5842)
					(thickness 0.1524)
				)
			)
		)
		(duplicate_pad_numbers_are_jumpers no)
		(fp_line
			(start -1.143 -0.5588)
			(end -1.143 0.5588)
			(stroke
				(width 0.1)
				(type default)
			)
			(layer "F.SilkS")
		)
		(fp_line
			(start -1.143 0.5588)
			(end 1.143 0.5588)
			(stroke
				(width 0.1)
				(type default)
			)
			(layer "F.SilkS")
		)
		(fp_line
			(start 1.143 -0.5588)
			(end -1.143 -0.5588)
			(stroke
				(width 0.1)
				(type default)
			)
			(layer "F.SilkS")
		)
		(fp_line
			(start 1.143 0.5588)
			(end 1.143 -0.5588)
			(stroke
				(width 0.1)
				(type default)
			)
			(layer "F.SilkS")
		)
		(fp_rect
			(start -1.143 0.5588)
			(end 1.143 -0.5588)
			(stroke
				(width 0)
				(type default)
			)
			(fill no)
			(layer "F.CrtYd")
		)
		(fp_line
			(start -0.508 -0.3048)
			(end -0.508 0.3048)
			(stroke
				(width 0.1)
				(type default)
			)
			(layer "F.Fab")
		)
		(fp_line
			(start -0.508 0.3048)
			(end 0.508 0.3048)
			(stroke
				(width 0.1)
				(type default)
			)
			(layer "F.Fab")
		)
		(fp_line
			(start 0.508 -0.3048)
			(end -0.508 -0.3048)
			(stroke
				(width 0.1)
				(type default)
			)
			(layer "F.Fab")
		)
		(fp_line
			(start 0.508 0.3048)
			(end 0.508 -0.3048)
			(stroke
				(width 0.1)
				(type default)
			)
			(layer "F.Fab")
		)
		(pad "1" smd rect
			(at -0.5334 0)
			(size 0.7112 0.6096)
			(layers "F.Cu" "F.Mask" "F.Paste")
			(net "XP3R3V_FPGA")
		)
		(pad "2" smd rect
			(at 0.5334 0)
			(size 0.7112 0.6096)
			(layers "F.Cu" "F.Mask" "F.Paste")
			(net "R_BNO080_RST_N")
		)
		(zone
			(layer "F.Cu")
			(hatch none 0.5)
			(connect_pads
				(clearance 0)
			)
			(min_thickness 0.25)
			(keepout
				(tracks allowed)
				(vias not_allowed)
				(pads allowed)
				(copperpour not_allowed)
				(footprints allowed)
			)
			(placement
				(enabled no)
				(sheetname "")
			)
			(fill
				(thermal_gap 0.5)
				(thermal_bridge_width 0.5)
				(island_removal_mode 0)
			)
			(polygon
				(pts
					(xy 80.6958 -60.3758) (xy 80.8482 -60.3758) (xy 80.8482 -60.9854) (xy 80.6958 -60.9854)
				)
			)
		)
	)
	(footprint ""
		(layer "F.Cu")
		(at 150.749 -24.511)
		(property "Reference" "R423"
			(at 0.127 2.45237 0)
			(unlocked yes)
			(layer "F.SilkS")
			(effects
				(font
					(size 0.7874 0.5842)
					(thickness 0.1524)
				)
			)
		)
		(property "Value" "VAL*"
			(at 0.02032 2.13233 0)
			(unlocked yes)
			(layer "F.Fab")
			(hide yes)
			(effects
				(font
					(size 0.7874 0.5842)
					(thickness 0.1524)
				)
			)
		)
		(property "Tolerance" "TOL*"
			(at 0.044704 3.05435 0)
			(unlocked yes)
			(layer "Cmts.User")
			(hide yes)
			(effects
				(font
					(size 0.7874 0.5842)
					(thickness 0.1524)
				)
			)
		)
		(property "User Part Number" "PARTNUM*"
			(at 0.02032 4.024884 0)
			(unlocked yes)
			(layer "Cmts.User")
			(hide yes)
			(effects
				(font
					(size 0.7874 0.5842)
					(thickness 0.1524)
				)
			)
		)
		(property "Device Type" "RESISTOR-G155-14701-01,4.7KOHMA"
			(at 0.008382 1.210564 0)
			(unlocked yes)
			(layer "F.Fab")
			(hide yes)
			(effects
				(font
					(size 0.7874 0.5842)
					(thickness 0.1524)
				)
			)
		)
		(duplicate_pad_numbers_are_jumpers no)
		(fp_line
			(start -1.143 -0.5588)
			(end -1.143 0.5588)
			(stroke
				(width 0.1)
				(type default)
			)
			(layer "F.SilkS")
		)
		(fp_line
			(start -1.143 0.5588)
			(end 1.143 0.5588)
			(stroke
				(width 0.1)
				(type default)
			)
			(layer "F.SilkS")
		)
		(fp_line
			(start 1.143 -0.5588)
			(end -1.143 -0.5588)
			(stroke
				(width 0.1)
				(type default)
			)
			(layer "F.SilkS")
		)
		(fp_line
			(start 1.143 0.5588)
			(end 1.143 -0.5588)
			(stroke
				(width 0.1)
				(type default)
			)
			(layer "F.SilkS")
		)
		(fp_rect
			(start -1.143 0.5588)
			(end 1.143 -0.5588)
			(stroke
				(width 0)
				(type default)
			)
			(fill no)
			(layer "F.CrtYd")
		)
		(fp_line
			(start -0.508 -0.3048)
			(end -0.508 0.3048)
			(stroke
				(width 0.1)
				(type default)
			)
			(layer "F.Fab")
		)
		(fp_line
			(start -0.508 0.3048)
			(end 0.508 0.3048)
			(stroke
				(width 0.1)
				(type default)
			)
			(layer "F.Fab")
		)
		(fp_line
			(start 0.508 -0.3048)
			(end -0.508 -0.3048)
			(stroke
				(width 0.1)
				(type default)
			)
			(layer "F.Fab")
		)
		(fp_line
			(start 0.508 0.3048)
			(end 0.508 -0.3048)
			(stroke
				(width 0.1)
				(type default)
			)
			(layer "F.Fab")
		)
		(pad "1" smd rect
			(at -0.5334 0)
			(size 0.7112 0.6096)
			(layers "F.Cu" "F.Mask" "F.Paste")
			(net "XP3R3V_FPGA")
		)
		(pad "2" smd rect
			(at 0.5334 0)
			(size 0.7112 0.6096)
			(layers "F.Cu" "F.Mask" "F.Paste")
			(net "FPGA_IN_LM75B_INT3_N")
		)
		(zone
			(layer "F.Cu")
			(hatch none 0.5)
			(connect_pads
				(clearance 0)
			)
			(min_thickness 0.25)
			(keepout
				(tracks allowed)
				(vias not_allowed)
				(pads allowed)
				(copperpour not_allowed)
				(footprints allowed)
			)
			(placement
				(enabled no)
				(sheetname "")
			)
			(fill
				(thermal_gap 0.5)
				(thermal_bridge_width 0.5)
				(island_removal_mode 0)
			)
			(polygon
				(pts
					(xy 150.6728 -24.2062) (xy 150.8252 -24.2062) (xy 150.8252 -24.8158) (xy 150.6728 -24.8158)
				)
			)
		)
		(zone
			(layer "F.Cu")
			(hatch none 0.5)
			(connect_pads
				(clearance 0)
			)
			(min_thickness 0.25)
			(keepout
				(tracks not_allowed)
				(vias allowed)
				(pads allowed)
				(copperpour not_allowed)
				(footprints allowed)
			)
			(placement
				(enabled no)
				(sheetname "")
			)
			(fill
				(thermal_gap 0.5)
				(thermal_bridge_width 0.5)
				(island_removal_mode 0)
			)
			(polygon
				(pts
					(xy 150.6728 -24.2062) (xy 150.8252 -24.2062) (xy 150.8252 -24.8158) (xy 150.6728 -24.8158)
				)
			)
		)
	)
	(footprint ""
		(layer "F.Cu")
		(at 111.125 -104.521 180)
		(property "Reference" "R366"
			(at -3.175 3.00863 0)
			(unlocked yes)
			(layer "F.SilkS")
			(effects
				(font
					(size 0.7874 0.5842)
					(thickness 0.1524)
				)
			)
		)
		(property "Value" "VAL*"
			(at 0.02032 2.13233 180)
			(unlocked yes)
			(layer "F.Fab")
			(hide yes)
			(effects
				(font
					(size 0.7874 0.5842)
					(thickness 0.1524)
				)
			)
		)
		(property "Tolerance" "TOL*"
			(at 0.044704 3.05435 180)
			(unlocked yes)
			(layer "Cmts.User")
			(hide yes)
			(effects
				(font
					(size 0.7874 0.5842)
					(thickness 0.1524)
				)
			)
		)
		(property "User Part Number" "PARTNUM*"
			(at 0.02032 4.024884 180)
			(unlocked yes)
			(layer "Cmts.User")
			(hide yes)
			(effects
				(font
					(size 0.7874 0.5842)
					(thickness 0.1524)
				)
			)
		)
		(property "Device Type" "RESISTOR-G155-133R0-01,33OHM,1%"
			(at 0.008382 1.210564 180)
			(unlocked yes)
			(layer "F.Fab")
			(hide yes)
			(effects
				(font
					(size 0.7874 0.5842)
					(thickness 0.1524)
				)
			)
		)
		(duplicate_pad_numbers_are_jumpers no)
		(fp_line
			(start 1.143 0.5588)
			(end 1.143 -0.5588)
			(stroke
				(width 0.1)
				(type default)
			)
			(layer "F.SilkS")
		)
		(fp_line
			(start 1.143 -0.5588)
			(end -1.143 -0.5588)
			(stroke
				(width 0.1)
				(type default)
			)
			(layer "F.SilkS")
		)
		(fp_line
			(start -1.143 0.5588)
			(end 1.143 0.5588)
			(stroke
				(width 0.1)
				(type default)
			)
			(layer "F.SilkS")
		)
		(fp_line
			(start -1.143 -0.5588)
			(end -1.143 0.5588)
			(stroke
				(width 0.1)
				(type default)
			)
			(layer "F.SilkS")
		)
		(fp_poly
			(pts
				(xy -1.143 0.5588) (xy 1.143 0.5588) (xy 1.143 -0.5588) (xy -1.143 -0.5588)
			)
			(stroke
				(width 0)
				(type default)
			)
			(fill no)
			(layer "F.CrtYd")
		)
		(fp_line
			(start 0.508 0.3048)
			(end 0.508 -0.3048)
			(stroke
				(width 0.1)
				(type default)
			)
			(layer "F.Fab")
		)
		(fp_line
			(start 0.508 -0.3048)
			(end -0.508 -0.3048)
			(stroke
				(width 0.1)
				(type default)
			)
			(layer "F.Fab")
		)
		(fp_line
			(start -0.508 0.3048)
			(end 0.508 0.3048)
			(stroke
				(width 0.1)
				(type default)
			)
			(layer "F.Fab")
		)
		(fp_line
			(start -0.508 -0.3048)
			(end -0.508 0.3048)
			(stroke
				(width 0.1)
				(type default)
			)
			(layer "F.Fab")
		)
		(pad "1" smd rect
			(at -0.5334 0 180)
			(size 0.7112 0.6096)
			(layers "F.Cu" "F.Mask" "F.Paste")
			(net "RGB_LED_I2C_SCL")
		)
		(pad "2" smd rect
			(at 0.5334 0 180)
			(size 0.7112 0.6096)
			(layers "F.Cu" "F.Mask" "F.Paste")
			(net "R_RGB_LED_I2C_SCL")
		)
		(zone
			(layer "F.Cu")
			(hatch none 0.5)
			(connect_pads
				(clearance 0)
			)
			(min_thickness 0.25)
			(keepout
				(tracks allowed)
				(vias not_allowed)
				(pads allowed)
				(copperpour not_allowed)
				(footprints allowed)
			)
			(placement
				(enabled no)
				(sheetname "")
			)
			(fill
				(thermal_gap 0.5)
				(thermal_bridge_width 0.5)
				(island_removal_mode 0)
			)
			(polygon
				(pts
					(xy 111.2012 -104.8258) (xy 111.0488 -104.8258) (xy 111.0488 -104.2162) (xy 111.2012 -104.2162)
				)
			)
		)
		(zone
			(layer "F.Cu")
			(hatch none 0.5)
			(connect_pads
				(clearance 0)
			)
			(min_thickness 0.25)
			(keepout
				(tracks not_allowed)
				(vias allowed)
				(pads allowed)
				(copperpour not_allowed)
				(footprints allowed)
			)
			(placement
				(enabled no)
				(sheetname "")
			)
			(fill
				(thermal_gap 0.5)
				(thermal_bridge_width 0.5)
				(island_removal_mode 0)
			)
			(polygon
				(pts
					(xy 111.2012 -104.8258) (xy 111.0488 -104.8258) (xy 111.0488 -104.2162) (xy 111.2012 -104.2162)
				)
			)
		)
	)
	(footprint ""
		(layer "F.Cu")
		(at 14.6812 -65.786 -90)
		(property "Reference" "R361"
			(at -5.334 0.41783 90)
			(unlocked yes)
			(layer "F.SilkS")
			(effects
				(font
					(size 0.7874 0.5842)
					(thickness 0.1524)
				)
			)
		)
		(property "Value" "VAL*"
			(at 0.02032 2.13233 270)
			(unlocked yes)
			(layer "F.Fab")
			(hide yes)
			(effects
				(font
					(size 0.7874 0.5842)
					(thickness 0.1524)
				)
			)
		)
		(property "Device Type" "RESISTOR-G155-14701-01,4.7KOHMA"
			(at 0.008382 1.210564 270)
			(unlocked yes)
			(layer "F.Fab")
			(hide yes)
			(effects
				(font
					(size 0.7874 0.5842)
					(thickness 0.1524)
				)
			)
		)
		(property "User Part Number" "PARTNUM*"
			(at 0.02032 4.024884 270)
			(unlocked yes)
			(layer "Cmts.User")
			(hide yes)
			(effects
				(font
					(size 0.7874 0.5842)
					(thickness 0.1524)
				)
			)
		)
		(property "Tolerance" "TOL*"
			(at 0.044704 3.05435 270)
			(unlocked yes)
			(layer "Cmts.User")
			(hide yes)
			(effects
				(font
					(size 0.7874 0.5842)
					(thickness 0.1524)
				)
			)
		)
		(duplicate_pad_numbers_are_jumpers no)
		(fp_line
			(start -1.143 0.5588)
			(end 1.143 0.5588)
			(stroke
				(width 0.1)
				(type default)
			)
			(layer "F.SilkS")
		)
		(fp_line
			(start 1.143 0.5588)
			(end 1.143 -0.5588)
			(stroke
				(width 0.1)
				(type default)
			)
			(layer "F.SilkS")
		)
		(fp_line
			(start -1.143 -0.5588)
			(end -1.143 0.5588)
			(stroke
				(width 0.1)
				(type default)
			)
			(layer "F.SilkS")
		)
		(fp_line
			(start 1.143 -0.5588)
			(end -1.143 -0.5588)
			(stroke
				(width 0.1)
				(type default)
			)
			(layer "F.SilkS")
		)
		(fp_rect
			(start -1.143 -0.5588)
			(end 1.143 0.5588)
			(stroke
				(width 0)
				(type default)
			)
			(fill no)
			(layer "F.CrtYd")
		)
		(fp_line
			(start -0.508 0.3048)
			(end 0.508 0.3048)
			(stroke
				(width 0.1)
				(type default)
			)
			(layer "F.Fab")
		)
		(fp_line
			(start 0.508 0.3048)
			(end 0.508 -0.3048)
			(stroke
				(width 0.1)
				(type default)
			)
			(layer "F.Fab")
		)
		(fp_line
			(start -0.508 -0.3048)
			(end -0.508 0.3048)
			(stroke
				(width 0.1)
				(type default)
			)
			(layer "F.Fab")
		)
		(fp_line
			(start 0.508 -0.3048)
			(end -0.508 -0.3048)
			(stroke
				(width 0.1)
				(type default)
			)
			(layer "F.Fab")
		)
		(pad "1" smd rect
			(at -0.5334 0 270)
			(size 0.7112 0.6096)
			(layers "F.Cu" "F.Mask" "F.Paste")
			(net "XP3R3V_FPGA")
		)
		(pad "2" smd rect
			(at 0.5334 0 270)
			(size 0.7112 0.6096)
			(layers "F.Cu" "F.Mask" "F.Paste")
			(net "SMA1_SIG_OUT_BF_EN_N")
		)
		(zone
			(layer "F.Cu")
			(hatch none 0.5)
			(connect_pads
				(clearance 0)
			)
			(min_thickness 0.25)
			(keepout
				(tracks not_allowed)
				(vias allowed)
				(pads allowed)
				(copperpour not_allowed)
				(footprints allowed)
			)
			(placement
				(enabled no)
				(sheetname "")
			)
			(fill
				(thermal_gap 0.5)
				(thermal_bridge_width 0.5)
				(island_removal_mode 0)
			)
			(polygon
				(pts
					(xy 14.986 -65.8622) (xy 14.3764 -65.8622) (xy 14.3764 -65.7098) (xy 14.986 -65.7098)
				)
			)
		)
		(zone
			(layer "F.Cu")
			(hatch none 0.5)
			(connect_pads
				(clearance 0)
			)
			(min_thickness 0.25)
			(keepout
				(tracks allowed)
				(vias not_allowed)
				(pads allowed)
				(copperpour not_allowed)
				(footprints allowed)
			)
			(placement
				(enabled no)
				(sheetname "")
			)
			(fill
				(thermal_gap 0.5)
				(thermal_bridge_width 0.5)
				(island_removal_mode 0)
			)
			(polygon
				(pts
					(xy 14.986 -65.8622) (xy 14.3764 -65.8622) (xy 14.3764 -65.7098) (xy 14.986 -65.7098)
				)
			)
		)
	)
	(footprint ""
		(layer "F.Cu")
		(at 7.112 -81.534 90)
		(property "Reference" "R427"
			(at -2.667 -0.34163 90)
			(unlocked yes)
			(layer "F.SilkS")
			(effects
				(font
					(size 0.7874 0.5842)
					(thickness 0.1524)
				)
			)
		)
		(property "Value" "VAL*"
			(at 0.02032 2.13233 90)
			(unlocked yes)
			(layer "F.Fab")
			(hide yes)
			(effects
				(font
					(size 0.7874 0.5842)
					(thickness 0.1524)
				)
			)
		)
		(property "Device Type" "RESISTOR-G155-11000-01,100OHM,A"
			(at 0.008382 1.210564 90)
			(unlocked yes)
			(layer "F.Fab")
			(hide yes)
			(effects
				(font
					(size 0.7874 0.5842)
					(thickness 0.1524)
				)
			)
		)
		(property "User Part Number" "PARTNUM*"
			(at 0.02032 4.024884 90)
			(unlocked yes)
			(layer "Cmts.User")
			(hide yes)
			(effects
				(font
					(size 0.7874 0.5842)
					(thickness 0.1524)
				)
			)
		)
		(property "Tolerance" "TOL*"
			(at 0.044704 3.05435 90)
			(unlocked yes)
			(layer "Cmts.User")
			(hide yes)
			(effects
				(font
					(size 0.7874 0.5842)
					(thickness 0.1524)
				)
			)
		)
		(duplicate_pad_numbers_are_jumpers no)
		(fp_line
			(start 1.143 -0.5588)
			(end -1.143 -0.5588)
			(stroke
				(width 0.1)
				(type default)
			)
			(layer "F.SilkS")
		)
		(fp_line
			(start -1.143 -0.5588)
			(end -1.143 0.5588)
			(stroke
				(width 0.1)
				(type default)
			)
			(layer "F.SilkS")
		)
		(fp_line
			(start 1.143 0.5588)
			(end 1.143 -0.5588)
			(stroke
				(width 0.1)
				(type default)
			)
			(layer "F.SilkS")
		)
		(fp_line
			(start -1.143 0.5588)
			(end 1.143 0.5588)
			(stroke
				(width 0.1)
				(type default)
			)
			(layer "F.SilkS")
		)
		(fp_poly
			(pts
				(xy -1.143 0.5588) (xy 1.143 0.5588) (xy 1.143 -0.5588) (xy -1.143 -0.5588)
			)
			(stroke
				(width 0)
				(type default)
			)
			(fill no)
			(layer "F.CrtYd")
		)
		(fp_line
			(start 0.508 -0.3048)
			(end -0.508 -0.3048)
			(stroke
				(width 0.1)
				(type default)
			)
			(layer "F.Fab")
		)
		(fp_line
			(start -0.508 -0.3048)
			(end -0.508 0.3048)
			(stroke
				(width 0.1)
				(type default)
			)
			(layer "F.Fab")
		)
		(fp_line
			(start 0.508 0.3048)
			(end 0.508 -0.3048)
			(stroke
				(width 0.1)
				(type default)
			)
			(layer "F.Fab")
		)
		(fp_line
			(start -0.508 0.3048)
			(end 0.508 0.3048)
			(stroke
				(width 0.1)
				(type default)
			)
			(layer "F.Fab")
		)
		(pad "1" smd rect
			(at -0.5334 0 90)
			(size 0.7112 0.6096)
			(layers "F.Cu" "F.Mask" "F.Paste")
			(net "FPGA_OUT_GPS_LED_RED_N")
		)
		(pad "2" smd rect
			(at 0.5334 0 90)
			(size 0.7112 0.6096)
			(layers "F.Cu" "F.Mask" "F.Paste")
			(net "UNNAMED_14_LED4PV14_I269_3")
		)
		(zone
			(layer "F.Cu")
			(hatch none 0.5)
			(connect_pads
				(clearance 0)
			)
			(min_thickness 0.25)
			(keepout
				(tracks not_allowed)
				(vias allowed)
				(pads allowed)
				(copperpour not_allowed)
				(footprints allowed)
			)
			(placement
				(enabled no)
				(sheetname "")
			)
			(fill
				(thermal_gap 0.5)
				(thermal_bridge_width 0.5)
				(island_removal_mode 0)
			)
			(polygon
				(pts
					(xy 7.4168 -81.4578) (xy 7.4168 -81.6102) (xy 6.8072 -81.6102) (xy 6.8072 -81.4578)
				)
			)
		)
		(zone
			(layer "F.Cu")
			(hatch none 0.5)
			(connect_pads
				(clearance 0)
			)
			(min_thickness 0.25)
			(keepout
				(tracks allowed)
				(vias not_allowed)
				(pads allowed)
				(copperpour not_allowed)
				(footprints allowed)
			)
			(placement
				(enabled no)
				(sheetname "")
			)
			(fill
				(thermal_gap 0.5)
				(thermal_bridge_width 0.5)
				(island_removal_mode 0)
			)
			(polygon
				(pts
					(xy 7.4168 -81.4578) (xy 7.4168 -81.6102) (xy 6.8072 -81.6102) (xy 6.8072 -81.4578)
				)
			)
		)
	)
	(footprint ""
		(layer "F.Cu")
		(at 30.34538 -16.72844 180)
		(property "Reference" "R345"
			(at 0.889 5.16763 0)
			(unlocked yes)
			(layer "F.SilkS")
			(effects
				(font
					(size 0.7874 0.5842)
					(thickness 0.1524)
				)
			)
		)
		(property "Value" "VAL*"
			(at 0.02032 2.13233 180)
			(unlocked yes)
			(layer "F.Fab")
			(hide yes)
			(effects
				(font
					(size 0.7874 0.5842)
					(thickness 0.1524)
				)
			)
		)
		(property "Tolerance" "TOL*"
			(at 0.044704 3.05435 180)
			(unlocked yes)
			(layer "Cmts.User")
			(hide yes)
			(effects
				(font
					(size 0.7874 0.5842)
					(thickness 0.1524)
				)
			)
		)
		(property "User Part Number" "PARTNUM*"
			(at 0.02032 4.024884 180)
			(unlocked yes)
			(layer "Cmts.User")
			(hide yes)
			(effects
				(font
					(size 0.7874 0.5842)
					(thickness 0.1524)
				)
			)
		)
		(property "Device Type" "RESISTOR-G155-133R0-01,33OHM,1%"
			(at 0.008382 1.210564 180)
			(unlocked yes)
			(layer "F.Fab")
			(hide yes)
			(effects
				(font
					(size 0.7874 0.5842)
					(thickness 0.1524)
				)
			)
		)
		(duplicate_pad_numbers_are_jumpers no)
		(fp_line
			(start 1.143 0.5588)
			(end 1.143 -0.5588)
			(stroke
				(width 0.1)
				(type default)
			)
			(layer "F.SilkS")
		)
		(fp_line
			(start 1.143 -0.5588)
			(end -1.143 -0.5588)
			(stroke
				(width 0.1)
				(type default)
			)
			(layer "F.SilkS")
		)
		(fp_line
			(start -1.143 0.5588)
			(end 1.143 0.5588)
			(stroke
				(width 0.1)
				(type default)
			)
			(layer "F.SilkS")
		)
		(fp_line
			(start -1.143 -0.5588)
			(end -1.143 0.5588)
			(stroke
				(width 0.1)
				(type default)
			)
			(layer "F.SilkS")
		)
		(fp_rect
			(start 1.143 -0.5588)
			(end -1.143 0.5588)
			(stroke
				(width 0)
				(type default)
			)
			(fill no)
			(layer "F.CrtYd")
		)
		(fp_line
			(start 0.508 0.3048)
			(end 0.508 -0.3048)
			(stroke
				(width 0.1)
				(type default)
			)
			(layer "F.Fab")
		)
		(fp_line
			(start 0.508 -0.3048)
			(end -0.508 -0.3048)
			(stroke
				(width 0.1)
				(type default)
			)
			(layer "F.Fab")
		)
		(fp_line
			(start -0.508 0.3048)
			(end 0.508 0.3048)
			(stroke
				(width 0.1)
				(type default)
			)
			(layer "F.Fab")
		)
		(fp_line
			(start -0.508 -0.3048)
			(end -0.508 0.3048)
			(stroke
				(width 0.1)
				(type default)
			)
			(layer "F.Fab")
		)
		(pad "1" smd rect
			(at -0.5334 0 180)
			(size 0.7112 0.6096)
			(layers "F.Cu" "F.Mask" "F.Paste")
			(net "EEPROM_SDA")
		)
		(pad "2" smd rect
			(at 0.5334 0 180)
			(size 0.7112 0.6096)
			(layers "F.Cu" "F.Mask" "F.Paste")
			(net "PRI_EEPROM_SDA")
		)
		(zone
			(layer "F.Cu")
			(hatch none 0.5)
			(connect_pads
				(clearance 0)
			)
			(min_thickness 0.25)
			(keepout
				(tracks allowed)
				(vias not_allowed)
				(pads allowed)
				(copperpour not_allowed)
				(footprints allowed)
			)
			(placement
				(enabled no)
				(sheetname "")
			)
			(fill
				(thermal_gap 0.5)
				(thermal_bridge_width 0.5)
				(island_removal_mode 0)
			)
			(polygon
				(pts
					(xy 30.26918 -16.42364) (xy 30.42158 -16.42364) (xy 30.42158 -17.03324) (xy 30.26918 -17.03324)
				)
			)
		)
	)
	(footprint ""
		(layer "F.Cu")
		(at 95.123 -106.299)
		(property "Reference" "TP38"
			(at 0.8382 -0.08763 0)
			(unlocked yes)
			(layer "F.SilkS")
			(effects
				(font
					(size 0.7874 0.5842)
					(thickness 0.1524)
				)
				(justify left)
			)
		)
		(property "Value" ""
			(at 0 0 0)
			(layer "F.Fab")
			(effects
				(font
					(size 1.27 1.27)
				)
			)
		)
		(property "Device Type" "TP_PIONT-TP010CT020B030_PTH-TPA"
			(at -1.341882 0.996696 0)
			(unlocked yes)
			(layer "F.Fab")
			(hide yes)
			(effects
				(font
					(size 0.7874 0.5842)
					(thickness 0.000001)
				)
				(justify left)
			)
		)
		(duplicate_pad_numbers_are_jumpers no)
		(fp_poly
			(pts
				(arc
					(start 0.889 0)
					(mid -0.889 0)
					(end 0.889 0)
				)
			)
			(stroke
				(width 0)
				(type default)
			)
			(fill no)
			(layer "B.CrtYd")
		)
		(fp_poly
			(pts
				(arc
					(start 0.889 0)
					(mid -0.889 0)
					(end 0.889 0)
				)
			)
			(stroke
				(width 0)
				(type default)
			)
			(fill no)
			(layer "F.CrtYd")
		)
		(pad "1" thru_hole circle
			(at 0 0)
			(size 0.508 0.508)
			(drill 0.254)
			(layers "*.Cu" "*.Mask")
			(remove_unused_layers no)
			(net "XP3R3V_PG")
			(clearance 0.1016)
			(padstack
				(mode front_inner_back)
				(layer "Inner"
					(shape circle)
					(size 0.508 0.508)
					(clearance 0.1016)
				)
				(layer "B.Cu"
					(shape circle)
					(size 0.762 0.762)
					(clearance -0.0254)
				)
			)
		)
	)
	(footprint ""
		(layer "F.Cu")
		(at 145.3134 -94.2848 180)
		(property "Reference" "C4"
			(at -0.2286 -8.85317 0)
			(unlocked yes)
			(layer "F.SilkS")
			(effects
				(font
					(size 0.7874 0.5842)
					(thickness 0.1524)
				)
			)
		)
		(property "Value" "VAL*"
			(at 0.193548 2.13614 180)
			(unlocked yes)
			(layer "F.Fab")
			(hide yes)
			(effects
				(font
					(size 0.7874 0.5842)
					(thickness 0.1524)
				)
			)
		)
		(property "Tolerance" "TOL*"
			(at 0.216154 3.1496 180)
			(unlocked yes)
			(layer "Cmts.User")
			(hide yes)
			(effects
				(font
					(size 0.7874 0.5842)
					(thickness 0.1524)
				)
			)
		)
		(property "Device Type" "CAPACITOR-G104-0F224-BK,0.22UFA"
			(at 0.184404 1.180592 180)
			(unlocked yes)
			(layer "F.Fab")
			(hide yes)
			(effects
				(font
					(size 0.7874 0.5842)
					(thickness 0.1524)
				)
			)
		)
		(property "User Part Number" "PARTNUM*"
			(at 0.216154 4.185666 180)
			(unlocked yes)
			(layer "Cmts.User")
			(hide yes)
			(effects
				(font
					(size 0.7874 0.5842)
					(thickness 0.1524)
				)
			)
		)
		(duplicate_pad_numbers_are_jumpers no)
		(fp_line
			(start 0.671322 0.4445)
			(end -0.671322 0.4445)
			(stroke
				(width 0.1)
				(type default)
			)
			(layer "F.SilkS")
		)
		(fp_line
			(start 0.671322 -0.4445)
			(end 0.671322 0.4445)
			(stroke
				(width 0.1)
				(type default)
			)
			(layer "F.SilkS")
		)
		(fp_line
			(start -0.671322 0.4445)
			(end -0.671322 -0.4445)
			(stroke
				(width 0.1)
				(type default)
			)
			(layer "F.SilkS")
		)
		(fp_line
			(start -0.671322 -0.4445)
			(end 0.671322 -0.4445)
			(stroke
				(width 0.1)
				(type default)
			)
			(layer "F.SilkS")
		)
		(fp_rect
			(start 0.671322 -0.4445)
			(end -0.671322 0.4445)
			(stroke
				(width 0)
				(type default)
			)
			(fill no)
			(layer "F.CrtYd")
		)
		(fp_line
			(start 0.31496 0.1651)
			(end 0.31496 -0.1651)
			(stroke
				(width 0.1)
				(type default)
			)
			(layer "F.Fab")
		)
		(fp_line
			(start 0.31496 -0.1651)
			(end -0.31496 -0.1651)
			(stroke
				(width 0.1)
				(type default)
			)
			(layer "F.Fab")
		)
		(fp_line
			(start -0.31496 0.1651)
			(end 0.31496 0.1651)
			(stroke
				(width 0.1)
				(type default)
			)
			(layer "F.Fab")
		)
		(fp_line
			(start -0.31496 -0.1651)
			(end -0.31496 0.1651)
			(stroke
				(width 0.1)
				(type default)
			)
			(layer "F.Fab")
		)
		(pad "1" smd rect
			(at -0.264922 0 180)
			(size 0.3048 0.381)
			(layers "F.Cu" "F.Mask" "F.Paste")
			(net "SG")
		)
		(pad "2" smd rect
			(at 0.264922 0 180)
			(size 0.3048 0.381)
			(layers "F.Cu" "F.Mask" "F.Paste")
			(net "XP12R0V_A_TIMER")
		)
		(zone
			(layer "F.Cu")
			(hatch none 0.5)
			(connect_pads
				(clearance 0)
			)
			(min_thickness 0.25)
			(keepout
				(tracks allowed)
				(vias not_allowed)
				(pads allowed)
				(copperpour not_allowed)
				(footprints allowed)
			)
			(placement
				(enabled no)
				(sheetname "")
			)
			(fill
				(thermal_gap 0.5)
				(thermal_bridge_width 0.5)
				(island_removal_mode 0)
			)
			(polygon
				(pts
					(xy 145.200878 -94.0943) (xy 145.425922 -94.0943) (xy 145.425922 -94.4753) (xy 145.200878 -94.4753)
				)
			)
		)
	)
	(footprint ""
		(layer "F.Cu")
		(at 20.4216 -53.1114 180)
		(property "Reference" "J18"
			(at -3.5814 0.31623 0)
			(unlocked yes)
			(layer "F.SilkS")
			(effects
				(font
					(size 0.7874 0.5842)
					(thickness 0.1524)
				)
			)
		)
		(property "Value" ""
			(at 0 0 180)
			(layer "F.Fab")
			(effects
				(font
					(size 1.27 1.27)
				)
			)
		)
		(property "User Part Number" "PARTNUM*"
			(at 0.126238 5.484368 180)
			(unlocked yes)
			(layer "Cmts.User")
			(hide yes)
			(effects
				(font
					(size 0.7874 0.5842)
					(thickness 0.1524)
				)
			)
		)
		(property "Device Type" "CONN_HDR_1X3_M_S_SMT-G205-1002A"
			(at 0.126238 4.290568 180)
			(unlocked yes)
			(layer "F.Fab")
			(hide yes)
			(effects
				(font
					(size 0.7874 0.5842)
					(thickness 0.1524)
				)
			)
		)
		(duplicate_pad_numbers_are_jumpers no)
		(fp_line
			(start 2.249678 2.299716)
			(end -2.249678 2.299716)
			(stroke
				(width 0.1)
				(type default)
			)
			(layer "F.SilkS")
		)
		(fp_line
			(start 2.249678 -1.67894)
			(end 2.249678 2.299716)
			(stroke
				(width 0.1)
				(type default)
			)
			(layer "F.SilkS")
		)
		(fp_line
			(start -2.249678 2.299716)
			(end -2.249678 -1.67894)
			(stroke
				(width 0.1)
				(type default)
			)
			(layer "F.SilkS")
		)
		(fp_line
			(start -2.249678 -1.67894)
			(end 2.249678 -1.67894)
			(stroke
				(width 0.1)
				(type default)
			)
			(layer "F.SilkS")
		)
		(fp_rect
			(start -2.503678 2.553716)
			(end 2.503678 -1.93294)
			(stroke
				(width 0)
				(type default)
			)
			(fill no)
			(layer "F.CrtYd")
		)
		(fp_line
			(start 1.42494 1.42494)
			(end 0.374904 1.42494)
			(stroke
				(width 0.1)
				(type default)
			)
			(layer "F.Fab")
		)
		(fp_line
			(start 1.42494 -1.42494)
			(end 1.42494 1.42494)
			(stroke
				(width 0.1)
				(type default)
			)
			(layer "F.Fab")
		)
		(fp_line
			(start 0.374904 1.674876)
			(end -0.374904 1.674876)
			(stroke
				(width 0.1)
				(type default)
			)
			(layer "F.Fab")
		)
		(fp_line
			(start 0.374904 1.42494)
			(end 0.374904 1.674876)
			(stroke
				(width 0.1)
				(type default)
			)
			(layer "F.Fab")
		)
		(fp_line
			(start -0.374904 1.674876)
			(end -0.374904 1.42494)
			(stroke
				(width 0.1)
				(type default)
			)
			(layer "F.Fab")
		)
		(fp_line
			(start -0.374904 1.42494)
			(end -1.42494 1.42494)
			(stroke
				(width 0.1)
				(type default)
			)
			(layer "F.Fab")
		)
		(fp_line
			(start -1.42494 1.42494)
			(end -1.42494 -1.42494)
			(stroke
				(width 0.1)
				(type default)
			)
			(layer "F.Fab")
		)
		(fp_line
			(start -1.42494 -1.42494)
			(end 1.42494 -1.42494)
			(stroke
				(width 0.1)
				(type default)
			)
			(layer "F.Fab")
		)
		(fp_text user "3"
			(at 2.6416 -0.69215 0)
			(unlocked yes)
			(layer "F.SilkS")
			(effects
				(font
					(size 0.635 0.4064)
					(thickness 0.1524)
				)
			)
		)
		(fp_text user "2"
			(at -2.5654 1.97485 0)
			(unlocked yes)
			(layer "F.SilkS")
			(effects
				(font
					(size 0.635 0.4064)
					(thickness 0.1524)
				)
			)
		)
		(fp_text user "1"
			(at -2.9464 -0.89535 0)
			(unlocked yes)
			(layer "F.SilkS")
			(effects
				(font
					(size 0.635 0.4064)
					(thickness 0.1524)
				)
			)
		)
		(fp_text user "3"
			(at 2.2606 0.96393 0)
			(unlocked yes)
			(layer "F.Fab")
			(effects
				(font
					(size 0.7874 0.5842)
					(thickness 0.1524)
				)
			)
		)
		(fp_text user "2"
			(at -1.0414 2.22123 0)
			(unlocked yes)
			(layer "F.Fab")
			(effects
				(font
					(size 0.7874 0.5842)
					(thickness 0.1524)
				)
			)
		)
		(fp_text user "1"
			(at -2.1844 0.07493 0)
			(unlocked yes)
			(layer "F.Fab")
			(effects
				(font
					(size 0.7874 0.5842)
					(thickness 0.1524)
				)
			)
		)
		(pad "1" smd rect
			(at -1.474978 0 180)
			(size 1.0414 2.2098)
			(layers "F.Cu" "F.Mask" "F.Paste")
			(net "SG")
		)
		(pad "2" smd rect
			(at 0 1.525016 180)
			(size 0.9906 1.0414)
			(layers "F.Cu" "F.Mask" "F.Paste")
			(net "SMA_ANALOG_TUNING_IN")
		)
		(pad "3" smd rect
			(at 1.474978 0 180)
			(size 1.0414 2.2098)
			(layers "F.Cu" "F.Mask" "F.Paste")
			(net "SG")
		)
	)
	(footprint ""
		(layer "F.Cu")
		(at 141.605 -54.737)
		(property "Reference" "U26"
			(at 0.127 -2.75463 0)
			(unlocked yes)
			(layer "F.SilkS")
			(effects
				(font
					(size 0.7874 0.5842)
					(thickness 0.1524)
				)
			)
		)
		(property "Value" ""
			(at 0 0 0)
			(layer "F.Fab")
			(effects
				(font
					(size 1.27 1.27)
				)
			)
		)
		(property "User Part Number" "PARTNUM*"
			(at 0.33782 5.715254 0)
			(unlocked yes)
			(layer "Cmts.User")
			(hide yes)
			(effects
				(font
					(size 0.7874 0.5842)
					(thickness 0.1524)
				)
			)
		)
		(property "Device Type" "TPS54824RNVR_VQFN18-G220-10657A"
			(at 0.33782 4.521454 0)
			(unlocked yes)
			(layer "F.Fab")
			(hide yes)
			(effects
				(font
					(size 0.7874 0.5842)
					(thickness 0.1524)
				)
			)
		)
		(duplicate_pad_numbers_are_jumpers no)
		(fp_line
			(start -2.208784 -2.208784)
			(end 2.208784 -2.208784)
			(stroke
				(width 0.1)
				(type default)
			)
			(layer "F.SilkS")
		)
		(fp_line
			(start -2.208784 2.200148)
			(end -2.208784 -2.208784)
			(stroke
				(width 0.1)
				(type default)
			)
			(layer "F.SilkS")
		)
		(fp_line
			(start 2.208784 -2.208784)
			(end 2.208784 2.200148)
			(stroke
				(width 0.1)
				(type default)
			)
			(layer "F.SilkS")
		)
		(fp_line
			(start 2.208784 2.200148)
			(end -2.208784 2.200148)
			(stroke
				(width 0.1)
				(type default)
			)
			(layer "F.SilkS")
		)
		(fp_poly
			(pts
				(arc
					(start -2.576068 -0.99314)
					(mid -3.592068 -0.99314)
					(end -2.576068 -0.99314)
				)
			)
			(stroke
				(width 0)
				(type default)
			)
			(fill yes)
			(layer "F.SilkS")
		)
		(fp_rect
			(start -2.462784 2.454148)
			(end 2.462784 -2.462784)
			(stroke
				(width 0)
				(type default)
			)
			(fill no)
			(layer "F.CrtYd")
		)
		(fp_line
			(start -1.800098 -1.800098)
			(end 1.800098 -1.800098)
			(stroke
				(width 0.1)
				(type default)
			)
			(layer "F.Fab")
		)
		(fp_line
			(start -1.800098 1.800098)
			(end -1.800098 -1.800098)
			(stroke
				(width 0.1)
				(type default)
			)
			(layer "F.Fab")
		)
		(fp_line
			(start 1.800098 -1.800098)
			(end 1.800098 1.800098)
			(stroke
				(width 0.1)
				(type default)
			)
			(layer "F.Fab")
		)
		(fp_line
			(start 1.800098 1.800098)
			(end -1.800098 1.800098)
			(stroke
				(width 0.1)
				(type default)
			)
			(layer "F.Fab")
		)
		(fp_circle
			(center -2.60604 -1.09982)
			(end -2.09804 -1.09982)
			(stroke
				(width 0.1)
				(type default)
			)
			(fill no)
			(layer "F.Fab")
		)
		(fp_text user "18"
			(at -2.413 -2.81305 0)
			(unlocked yes)
			(layer "F.SilkS")
			(effects
				(font
					(size 0.635 0.4064)
					(thickness 0.1524)
				)
			)
		)
		(fp_text user "5"
			(at -2.286 2.90195 0)
			(unlocked yes)
			(layer "F.SilkS")
			(effects
				(font
					(size 0.635 0.4064)
					(thickness 0.1524)
				)
			)
		)
		(fp_text user "6"
			(at -0.333502 3.002788 0)
			(unlocked yes)
			(layer "F.SilkS")
			(effects
				(font
					(size 0.635 0.4064)
					(thickness 0.1524)
				)
			)
		)
		(fp_text user "7"
			(at 0.484124 3.003296 0)
			(unlocked yes)
			(layer "F.SilkS")
			(effects
				(font
					(size 0.635 0.4064)
					(thickness 0.1524)
				)
			)
		)
		(fp_text user "8"
			(at 2.413 3.02895 0)
			(unlocked yes)
			(layer "F.SilkS")
			(effects
				(font
					(size 0.635 0.4064)
					(thickness 0.1524)
				)
			)
		)
		(fp_text user "13"
			(at 2.667 -2.50825 0)
			(unlocked yes)
			(layer "F.SilkS")
			(effects
				(font
					(size 0.635 0.4064)
					(thickness 0.1524)
				)
			)
		)
		(fp_text user "12"
			(at 3.175 -1.23825 0)
			(unlocked yes)
			(layer "F.SilkS")
			(effects
				(font
					(size 0.635 0.4064)
					(thickness 0.1524)
				)
			)
		)
		(fp_text user "5"
			(at -2.286 1.29667 0)
			(unlocked yes)
			(layer "F.Fab")
			(effects
				(font
					(size 0.7874 0.5842)
					(thickness 0.1524)
				)
			)
		)
		(fp_text user "18"
			(at -1.884934 -2.4638 0)
			(unlocked yes)
			(layer "F.Fab")
			(effects
				(font
					(size 0.7874 0.5842)
					(thickness 0.1524)
				)
			)
		)
		(fp_text user "6"
			(at -1.397 2.56667 0)
			(unlocked yes)
			(layer "F.Fab")
			(effects
				(font
					(size 0.7874 0.5842)
					(thickness 0.1524)
				)
			)
		)
		(fp_text user "13"
			(at 0.889 -2.25933 0)
			(unlocked yes)
			(layer "F.Fab")
			(effects
				(font
					(size 0.7874 0.5842)
					(thickness 0.1524)
				)
			)
		)
		(fp_text user "7"
			(at 1.524 2.43967 0)
			(unlocked yes)
			(layer "F.Fab")
			(effects
				(font
					(size 0.7874 0.5842)
					(thickness 0.1524)
				)
			)
		)
		(fp_text user "8"
			(at 2.286 1.29667 0)
			(unlocked yes)
			(layer "F.Fab")
			(effects
				(font
					(size 0.7874 0.5842)
					(thickness 0.1524)
				)
			)
		)
		(fp_text user "12"
			(at 2.54 -1.49733 0)
			(unlocked yes)
			(layer "F.Fab")
			(effects
				(font
					(size 0.7874 0.5842)
					(thickness 0.1524)
				)
			)
		)
		(pad "1" smd rect
			(at -1.649984 -0.94996)
			(size 0.6096 0.3048)
			(layers "F.Cu" "F.Mask" "F.Paste")
			(net "XP1R0V_BT")
		)
		(pad "2" smd rect
			(at -1.374902 -0.350012)
			(size 1.143 0.4064)
			(layers "F.Cu" "F.Mask" "F.Paste")
			(net "VIN_XP1R0V")
		)
		(pad "3" smd rect
			(at -1.374902 0.299974)
			(size 1.143 0.3048)
			(layers "F.Cu" "F.Mask" "F.Paste")
			(net "SG")
		)
		(pad "4" smd rect
			(at -1.374902 0.849884)
			(size 1.143 0.3048)
			(layers "F.Cu" "F.Mask" "F.Paste")
			(net "SG")
		)
		(pad "5" smd rect
			(at -1.374902 1.400048)
			(size 1.143 0.3048)
			(layers "F.Cu" "F.Mask" "F.Paste")
			(net "SG")
		)
		(pad "6" smd rect
			(at -0.32512 0.599948)
			(size 0.2032 2.6924)
			(layers "F.Cu" "F.Mask" "F.Paste")
			(net "XP1R0V_SW")
		)
		(pad "7" smd rect
			(at 0.32512 0.599948)
			(size 0.2032 2.6924)
			(layers "F.Cu" "F.Mask" "F.Paste")
			(net "XP1R0V_SW")
		)
		(pad "8" smd rect
			(at 1.374902 1.400048)
			(size 1.143 0.3048)
			(layers "F.Cu" "F.Mask" "F.Paste")
			(net "SG")
		)
		(pad "9" smd rect
			(at 1.374902 0.849884)
			(size 1.143 0.3048)
			(layers "F.Cu" "F.Mask" "F.Paste")
			(net "SG")
		)
		(pad "10" smd rect
			(at 1.374902 0.299974)
			(size 1.143 0.3048)
			(layers "F.Cu" "F.Mask" "F.Paste")
			(net "SG")
		)
		(pad "11" smd rect
			(at 1.374902 -0.350012)
			(size 1.143 0.4064)
			(layers "F.Cu" "F.Mask" "F.Paste")
			(net "VIN_XP1R0V")
		)
		(pad "12" smd rect
			(at 1.649984 -0.94996)
			(size 0.6096 0.3048)
			(layers "F.Cu" "F.Mask" "F.Paste")
			(net "XP1R0V_AGND")
		)
		(pad "13" smd rect
			(at 1.374902 -1.649984)
			(size 0.508 0.6096)
			(layers "F.Cu" "F.Mask" "F.Paste")
			(net "XP1R0V_RT")
		)
		(pad "14" smd rect
			(at 0.750062 -1.649984)
			(size 0.254 0.6096)
			(layers "F.Cu" "F.Mask" "F.Paste")
			(net "XP1R0V_FB_R_TO_AGND")
		)
		(pad "15" smd rect
			(at 0.249936 -1.649984)
			(size 0.254 0.6096)
			(layers "F.Cu" "F.Mask" "F.Paste")
			(net "XP1R0V_COMP")
		)
		(pad "16" smd rect
			(at -0.249936 -1.649984)
			(size 0.254 0.6096)
			(layers "F.Cu" "F.Mask" "F.Paste")
			(net "XP1R0V_SS")
		)
		(pad "17" smd rect
			(at -0.750062 -1.649984)
			(size 0.254 0.6096)
			(layers "F.Cu" "F.Mask" "F.Paste")
			(net "UNNAMED_523_CAPACITOR_I7_1")
		)
		(pad "18" smd rect
			(at -1.374902 -1.649984)
			(size 0.508 0.6096)
			(layers "F.Cu" "F.Mask" "F.Paste")
			(net "XP1R0V_PG")
		)
	)
	(footprint ""
		(layer "F.Cu")
		(at 101.092 -20.955 90)
		(property "Reference" "Y4"
			(at -3.83667 -0.762 0)
			(unlocked yes)
			(layer "F.SilkS")
			(effects
				(font
					(size 0.7874 0.5842)
					(thickness 0.1524)
				)
			)
		)
		(property "Value" ""
			(at 0 0 90)
			(layer "F.Fab")
			(effects
				(font
					(size 1.27 1.27)
				)
			)
		)
		(property "User Part Number" "PARTNUM*"
			(at 0 6.106668 90)
			(unlocked yes)
			(layer "Cmts.User")
			(hide yes)
			(effects
				(font
					(size 0.7874 0.5842)
					(thickness 0.1524)
				)
			)
		)
		(property "Device Type" "OSC6P_V2-A130-00004-AW"
			(at 0 4.912868 90)
			(unlocked yes)
			(layer "F.Fab")
			(hide yes)
			(effects
				(font
					(size 0.7874 0.5842)
					(thickness 0.1524)
				)
			)
		)
		(duplicate_pad_numbers_are_jumpers no)
		(fp_line
			(start 2.803906 -3.803904)
			(end 2.803906 3.803904)
			(stroke
				(width 0.1)
				(type default)
			)
			(layer "F.SilkS")
		)
		(fp_line
			(start -2.803906 -3.803904)
			(end 2.803906 -3.803904)
			(stroke
				(width 0.1)
				(type default)
			)
			(layer "F.SilkS")
		)
		(fp_line
			(start 2.803906 3.803904)
			(end -2.803906 3.803904)
			(stroke
				(width 0.1)
				(type default)
			)
			(layer "F.SilkS")
		)
		(fp_line
			(start -2.803906 3.803904)
			(end -2.803906 -3.803904)
			(stroke
				(width 0.1)
				(type default)
			)
			(layer "F.SilkS")
		)
		(fp_rect
			(start -3.057906 -4.057904)
			(end 3.057906 4.057904)
			(stroke
				(width 0)
				(type default)
			)
			(fill no)
			(layer "F.CrtYd")
		)
		(fp_line
			(start 2.549906 -3.549904)
			(end 2.549906 3.549904)
			(stroke
				(width 0.1)
				(type default)
			)
			(layer "F.Fab")
		)
		(fp_line
			(start -2.549906 -3.549904)
			(end 2.549906 -3.549904)
			(stroke
				(width 0.1)
				(type default)
			)
			(layer "F.Fab")
		)
		(fp_line
			(start 2.549906 3.549904)
			(end -2.549906 3.549904)
			(stroke
				(width 0.1)
				(type default)
			)
			(layer "F.Fab")
		)
		(fp_line
			(start -2.549906 3.549904)
			(end -2.549906 -3.549904)
			(stroke
				(width 0.1)
				(type default)
			)
			(layer "F.Fab")
		)
		(fp_text user "1"
			(at -3.480562 -2.712212 90)
			(unlocked yes)
			(layer "F.SilkS")
			(effects
				(font
					(size 0.7874 0.5842)
					(thickness 0.1524)
				)
			)
		)
		(fp_text user "3"
			(at -3.584194 2.45237 90)
			(unlocked yes)
			(layer "F.SilkS")
			(effects
				(font
					(size 0.7874 0.5842)
					(thickness 0.1524)
				)
			)
		)
		(fp_text user "6"
			(at 2.13233 -4.064 0)
			(unlocked yes)
			(layer "F.Fab")
			(effects
				(font
					(size 0.7874 0.5842)
					(thickness 0.1524)
				)
			)
		)
		(fp_text user "1"
			(at -3.253232 -2.611882 0)
			(unlocked yes)
			(layer "F.Fab")
			(effects
				(font
					(size 0.7874 0.5842)
					(thickness 0.1524)
				)
			)
		)
		(fp_text user "3"
			(at -3.356864 2.5527 0)
			(unlocked yes)
			(layer "F.Fab")
			(effects
				(font
					(size 0.7874 0.5842)
					(thickness 0.1524)
				)
			)
		)
		(fp_text user "4"
			(at 1.87833 3.937 0)
			(unlocked yes)
			(layer "F.Fab")
			(effects
				(font
					(size 0.7874 0.5842)
					(thickness 0.1524)
				)
			)
		)
		(pad "1" smd rect
			(at -1.849882 -2.54 90)
			(size 0.9906 1.397)
			(layers "F.Cu" "F.Mask" "F.Paste")
			(net "CLK_125M_OE")
		)
		(pad "2" smd rect
			(at -1.849882 0 90)
			(size 0.9906 1.397)
			(layers "F.Cu" "F.Mask" "F.Paste")
			(net "Net_762")
		)
		(pad "3" smd rect
			(at -1.849882 2.54 90)
			(size 0.9906 1.397)
			(layers "F.Cu" "F.Mask" "F.Paste")
			(net "SG")
		)
		(pad "4" smd rect
			(at 1.849882 2.54 90)
			(size 0.9906 1.397)
			(layers "F.Cu" "F.Mask" "F.Paste")
			(net "OSC_125M_CLKP")
		)
		(pad "5" smd rect
			(at 1.849882 0 90)
			(size 0.9906 1.397)
			(layers "F.Cu" "F.Mask" "F.Paste")
			(net "OSC_125M_CLKN")
		)
		(pad "6" smd rect
			(at 1.849882 -2.54 90)
			(size 0.9906 1.397)
			(layers "F.Cu" "F.Mask" "F.Paste")
			(net "VDD3V3_OSC_125M")
		)
		(zone
			(layer "F.Cu")
			(hatch none 0.5)
			(connect_pads
				(clearance 0)
			)
			(min_thickness 0.25)
			(keepout
				(tracks allowed)
				(vias not_allowed)
				(pads allowed)
				(copperpour not_allowed)
				(footprints allowed)
			)
			(placement
				(enabled no)
				(sheetname "")
			)
			(fill
				(thermal_gap 0.5)
				(thermal_bridge_width 0.5)
				(island_removal_mode 0)
			)
			(polygon
				(pts
					(xy 97.542096 -18.405094) (xy 104.641904 -18.405094) (xy 104.641904 -23.504906) (xy 97.542096 -23.504906)
				)
			)
			(polygon
				(pts
					(xy 99.2505 -19.600418) (xy 99.2505 -18.609818) (xy 97.8535 -18.609818) (xy 97.8535 -19.600418)
				)
			)
			(polygon
				(pts
					(xy 99.2505 -23.300182) (xy 99.2505 -22.309582) (xy 97.8535 -22.309582) (xy 97.8535 -23.300182)
				)
			)
			(polygon
				(pts
					(xy 101.7905 -19.600418) (xy 101.7905 -18.609818) (xy 100.3935 -18.609818) (xy 100.3935 -19.600418)
				)
			)
			(polygon
				(pts
					(xy 101.7905 -23.300182) (xy 101.7905 -22.309582) (xy 100.3935 -22.309582) (xy 100.3935 -23.300182)
				)
			)
			(polygon
				(pts
					(xy 104.3305 -19.600418) (xy 104.3305 -18.609818) (xy 102.9335 -18.609818) (xy 102.9335 -19.600418)
				)
			)
			(polygon
				(pts
					(xy 104.3305 -23.300182) (xy 104.3305 -22.309582) (xy 102.9335 -22.309582) (xy 102.9335 -23.300182)
				)
			)
		)
	)
	(footprint ""
		(layer "F.Cu")
		(at 11.2522 -16.9672 -90)
		(property "Reference" "R497"
			(at -0.0508 1.05283 90)
			(unlocked yes)
			(layer "F.SilkS")
			(effects
				(font
					(size 0.7874 0.5842)
					(thickness 0.1524)
				)
			)
		)
		(property "Value" "VAL*"
			(at 0.02032 2.13233 270)
			(unlocked yes)
			(layer "F.Fab")
			(hide yes)
			(effects
				(font
					(size 0.7874 0.5842)
					(thickness 0.1524)
				)
			)
		)
		(property "Tolerance" "TOL*"
			(at 0.044704 3.05435 270)
			(unlocked yes)
			(layer "Cmts.User")
			(hide yes)
			(effects
				(font
					(size 0.7874 0.5842)
					(thickness 0.1524)
				)
			)
		)
		(property "User Part Number" "PARTNUM*"
			(at 0.02032 4.024884 270)
			(unlocked yes)
			(layer "Cmts.User")
			(hide yes)
			(effects
				(font
					(size 0.7874 0.5842)
					(thickness 0.1524)
				)
			)
		)
		(property "Device Type" "RESISTOR-G155-11004-01,1MOHM,1%"
			(at 0.008382 1.210564 270)
			(unlocked yes)
			(layer "F.Fab")
			(hide yes)
			(effects
				(font
					(size 0.7874 0.5842)
					(thickness 0.1524)
				)
			)
		)
		(duplicate_pad_numbers_are_jumpers no)
		(fp_line
			(start -1.143 0.5588)
			(end 1.143 0.5588)
			(stroke
				(width 0.1)
				(type default)
			)
			(layer "F.SilkS")
		)
		(fp_line
			(start 1.143 0.5588)
			(end 1.143 -0.5588)
			(stroke
				(width 0.1)
				(type default)
			)
			(layer "F.SilkS")
		)
		(fp_line
			(start -1.143 -0.5588)
			(end -1.143 0.5588)
			(stroke
				(width 0.1)
				(type default)
			)
			(layer "F.SilkS")
		)
		(fp_line
			(start 1.143 -0.5588)
			(end -1.143 -0.5588)
			(stroke
				(width 0.1)
				(type default)
			)
			(layer "F.SilkS")
		)
		(fp_poly
			(pts
				(xy -1.143 0.5588) (xy 1.143 0.5588) (xy 1.143 -0.5588) (xy -1.143 -0.5588)
			)
			(stroke
				(width 0)
				(type default)
			)
			(fill no)
			(layer "F.CrtYd")
		)
		(fp_line
			(start -0.508 0.3048)
			(end 0.508 0.3048)
			(stroke
				(width 0.1)
				(type default)
			)
			(layer "F.Fab")
		)
		(fp_line
			(start 0.508 0.3048)
			(end 0.508 -0.3048)
			(stroke
				(width 0.1)
				(type default)
			)
			(layer "F.Fab")
		)
		(fp_line
			(start -0.508 -0.3048)
			(end -0.508 0.3048)
			(stroke
				(width 0.1)
				(type default)
			)
			(layer "F.Fab")
		)
		(fp_line
			(start 0.508 -0.3048)
			(end -0.508 -0.3048)
			(stroke
				(width 0.1)
				(type default)
			)
			(layer "F.Fab")
		)
		(pad "1" smd rect
			(at -0.5334 0 270)
			(size 0.7112 0.6096)
			(layers "F.Cu" "F.Mask" "F.Paste")
			(net "SG")
		)
		(pad "2" smd rect
			(at 0.5334 0 270)
			(size 0.7112 0.6096)
			(layers "F.Cu" "F.Mask" "F.Paste")
			(net "BF_SMA4_SIG_IO_CONN")
		)
		(zone
			(layer "F.Cu")
			(hatch none 0.5)
			(connect_pads
				(clearance 0)
			)
			(min_thickness 0.25)
			(keepout
				(tracks allowed)
				(vias not_allowed)
				(pads allowed)
				(copperpour not_allowed)
				(footprints allowed)
			)
			(placement
				(enabled no)
				(sheetname "")
			)
			(fill
				(thermal_gap 0.5)
				(thermal_bridge_width 0.5)
				(island_removal_mode 0)
			)
			(polygon
				(pts
					(xy 10.9474 -17.0434) (xy 10.9474 -16.891) (xy 11.557 -16.891) (xy 11.557 -17.0434)
				)
			)
		)
		(zone
			(layer "F.Cu")
			(hatch none 0.5)
			(connect_pads
				(clearance 0)
			)
			(min_thickness 0.25)
			(keepout
				(tracks not_allowed)
				(vias allowed)
				(pads allowed)
				(copperpour not_allowed)
				(footprints allowed)
			)
			(placement
				(enabled no)
				(sheetname "")
			)
			(fill
				(thermal_gap 0.5)
				(thermal_bridge_width 0.5)
				(island_removal_mode 0)
			)
			(polygon
				(pts
					(xy 10.9474 -17.0434) (xy 10.9474 -16.891) (xy 11.557 -16.891) (xy 11.557 -17.0434)
				)
			)
		)
	)
	(footprint ""
		(layer "F.Cu")
		(at 147.049998 -104.350058 -90)
		(property "Reference" "DS5"
			(at 0.464058 -1.452372 90)
			(unlocked yes)
			(layer "F.SilkS")
			(effects
				(font
					(size 0.7874 0.5842)
					(thickness 0.1524)
				)
			)
		)
		(property "Value" ""
			(at 0 0 270)
			(layer "F.Fab")
			(effects
				(font
					(size 1.27 1.27)
				)
			)
		)
		(property "Device Type" "OPTICAL-G170-10143-01"
			(at 0.1778 1.483081 270)
			(unlocked yes)
			(layer "F.Fab")
			(hide yes)
			(effects
				(font
					(size 0.786892 0.583946)
					(thickness 0.000001)
				)
			)
		)
		(property "User Part Number" "PARTNUM*"
			(at 0.1778 2.422881 270)
			(unlocked yes)
			(layer "Cmts.User")
			(hide yes)
			(effects
				(font
					(size 0.786892 0.583946)
					(thickness 0.000001)
				)
			)
		)
		(duplicate_pad_numbers_are_jumpers no)
		(fp_line
			(start -0.9398 1.3462)
			(end -2.2098 1.3462)
			(stroke
				(width 0.1)
				(type default)
			)
			(layer "F.SilkS")
		)
		(fp_line
			(start -1.5748 0.7112)
			(end -1.5748 1.9812)
			(stroke
				(width 0.1)
				(type default)
			)
			(layer "F.SilkS")
		)
		(fp_line
			(start -1.397508 0.704088)
			(end -1.397508 -0.704088)
			(stroke
				(width 0.1)
				(type default)
			)
			(layer "F.SilkS")
		)
		(fp_line
			(start 1.397508 0.704088)
			(end -1.397508 0.704088)
			(stroke
				(width 0.1)
				(type default)
			)
			(layer "F.SilkS")
		)
		(fp_line
			(start -1.397508 -0.704088)
			(end 1.397508 -0.704088)
			(stroke
				(width 0.1)
				(type default)
			)
			(layer "F.SilkS")
		)
		(fp_line
			(start 1.397508 -0.704088)
			(end 1.397508 0.704088)
			(stroke
				(width 0.1)
				(type default)
			)
			(layer "F.SilkS")
		)
		(fp_rect
			(start 1.905508 0.704088)
			(end 1.397508 -0.704088)
			(stroke
				(width 0)
				(type default)
			)
			(fill yes)
			(layer "F.SilkS")
		)
		(fp_rect
			(start 1.905508 0.958088)
			(end -1.651508 -0.958088)
			(stroke
				(width 0)
				(type default)
			)
			(fill no)
			(layer "F.CrtYd")
		)
		(fp_line
			(start -0.9398 0.9652)
			(end -2.2098 0.9652)
			(stroke
				(width 0.1)
				(type default)
			)
			(layer "F.Fab")
		)
		(fp_line
			(start -0.850138 0.450088)
			(end 0.850138 0.450088)
			(stroke
				(width 0.1)
				(type default)
			)
			(layer "F.Fab")
		)
		(fp_line
			(start 0.850138 0.450088)
			(end 0.850138 -0.450088)
			(stroke
				(width 0.1)
				(type default)
			)
			(layer "F.Fab")
		)
		(fp_line
			(start -1.5748 0.3302)
			(end -1.5748 1.6002)
			(stroke
				(width 0.1)
				(type default)
			)
			(layer "F.Fab")
		)
		(fp_line
			(start -0.850138 -0.450088)
			(end -0.850138 0.450088)
			(stroke
				(width 0.1)
				(type default)
			)
			(layer "F.Fab")
		)
		(fp_line
			(start 0.850138 -0.450088)
			(end -0.850138 -0.450088)
			(stroke
				(width 0.1)
				(type default)
			)
			(layer "F.Fab")
		)
		(fp_rect
			(start 0.850138 0.450088)
			(end 0.342138 -0.450088)
			(stroke
				(width 0)
				(type default)
			)
			(fill yes)
			(layer "F.Fab")
		)
		(fp_text user "C"
			(at 2.400808 -0.397002 0)
			(unlocked yes)
			(layer "F.SilkS")
			(effects
				(font
					(size 0.635 0.4064)
					(thickness 0.1524)
				)
			)
		)
		(fp_text user "A"
			(at -1.536192 -1.286002 0)
			(unlocked yes)
			(layer "F.SilkS")
			(effects
				(font
					(size 0.635 0.4064)
					(thickness 0.1524)
				)
			)
		)
		(fp_text user "C"
			(at 1.80467 0.0762 0)
			(unlocked yes)
			(layer "F.Fab")
			(effects
				(font
					(size 0.7874 0.5842)
					(thickness 0.1524)
				)
			)
		)
		(fp_text user "A"
			(at -1.528572 -0.651002 0)
			(unlocked yes)
			(layer "F.Fab")
			(effects
				(font
					(size 0.7874 0.5842)
					(thickness 0.1524)
				)
			)
		)
		(pad "A" smd rect
			(at -0.749808 0 270)
			(size 0.7874 0.7874)
			(layers "F.Cu" "F.Mask" "F.Paste")
			(net "UNNAMED_14_OPTICAL_I143_A")
		)
		(pad "C" smd rect
			(at 0.749808 0 270)
			(size 0.7874 0.7874)
			(layers "F.Cu" "F.Mask" "F.Paste")
			(net "SG")
		)
	)
	(footprint ""
		(layer "F.Cu")
		(at 36.9824 -100.2284 180)
		(property "Reference" "C29"
			(at 4.064 1.86563 0)
			(unlocked yes)
			(layer "F.SilkS")
			(effects
				(font
					(size 0.7874 0.5842)
					(thickness 0.1524)
				)
			)
		)
		(property "Value" "VAL*"
			(at 0.0762 2.067306 180)
			(unlocked yes)
			(layer "F.Fab")
			(hide yes)
			(effects
				(font
					(size 0.7874 0.5842)
					(thickness 0.1524)
				)
			)
		)
		(property "Device Type" "CAPACITOR-G105-0B104-CK,0.1UF,A"
			(at 0.0508 1.127506 180)
			(unlocked yes)
			(layer "F.Fab")
			(hide yes)
			(effects
				(font
					(size 0.7874 0.5842)
					(thickness 0.1524)
				)
			)
		)
		(property "User Part Number" "PARTNUM*"
			(at 0.1016 4.023106 180)
			(unlocked yes)
			(layer "Cmts.User")
			(hide yes)
			(effects
				(font
					(size 0.7874 0.5842)
					(thickness 0.1524)
				)
			)
		)
		(property "Tolerance" "TOL*"
			(at 0.0762 3.032506 180)
			(unlocked yes)
			(layer "Cmts.User")
			(hide yes)
			(effects
				(font
					(size 0.7874 0.5842)
					(thickness 0.1524)
				)
			)
		)
		(duplicate_pad_numbers_are_jumpers no)
		(fp_line
			(start 1.143 0.5588)
			(end 1.143 -0.5588)
			(stroke
				(width 0.1)
				(type default)
			)
			(layer "F.SilkS")
		)
		(fp_line
			(start 1.143 -0.5588)
			(end -1.143 -0.5588)
			(stroke
				(width 0.1)
				(type default)
			)
			(layer "F.SilkS")
		)
		(fp_line
			(start -1.143 0.5588)
			(end 1.143 0.5588)
			(stroke
				(width 0.1)
				(type default)
			)
			(layer "F.SilkS")
		)
		(fp_line
			(start -1.143 -0.5588)
			(end -1.143 0.5588)
			(stroke
				(width 0.1)
				(type default)
			)
			(layer "F.SilkS")
		)
		(fp_rect
			(start -1.143 0.5588)
			(end 1.143 -0.5588)
			(stroke
				(width 0)
				(type default)
			)
			(fill no)
			(layer "F.CrtYd")
		)
		(fp_line
			(start 0.508 0.3048)
			(end 0.508 -0.3048)
			(stroke
				(width 0.1)
				(type default)
			)
			(layer "F.Fab")
		)
		(fp_line
			(start 0.508 -0.3048)
			(end -0.508 -0.3048)
			(stroke
				(width 0.1)
				(type default)
			)
			(layer "F.Fab")
		)
		(fp_line
			(start -0.508 0.3048)
			(end 0.508 0.3048)
			(stroke
				(width 0.1)
				(type default)
			)
			(layer "F.Fab")
		)
		(fp_line
			(start -0.508 -0.3048)
			(end -0.508 0.3048)
			(stroke
				(width 0.1)
				(type default)
			)
			(layer "F.Fab")
		)
		(pad "1" smd rect
			(at -0.5334 0 180)
			(size 0.7112 0.6096)
			(layers "F.Cu" "F.Mask" "F.Paste")
			(net "R_XP5R0V_EN")
		)
		(pad "2" smd rect
			(at 0.5334 0 180)
			(size 0.7112 0.6096)
			(layers "F.Cu" "F.Mask" "F.Paste")
			(net "SG")
		)
		(zone
			(layer "F.Cu")
			(hatch none 0.5)
			(connect_pads
				(clearance 0)
			)
			(min_thickness 0.25)
			(keepout
				(tracks allowed)
				(vias not_allowed)
				(pads allowed)
				(copperpour not_allowed)
				(footprints allowed)
			)
			(placement
				(enabled no)
				(sheetname "")
			)
			(fill
				(thermal_gap 0.5)
				(thermal_bridge_width 0.5)
				(island_removal_mode 0)
			)
			(polygon
				(pts
					(xy 37.0586 -100.5332) (xy 36.9062 -100.5332) (xy 36.9062 -99.9236) (xy 37.0586 -99.9236)
				)
			)
		)
	)
	(footprint ""
		(layer "F.Cu")
		(at 95.758 -22.733 -90)
		(property "Reference" "R236"
			(at 2.794 0.08763 90)
			(unlocked yes)
			(layer "F.SilkS")
			(effects
				(font
					(size 0.7874 0.5842)
					(thickness 0.1524)
				)
			)
		)
		(property "Value" "VAL*"
			(at 0.02032 2.13233 270)
			(unlocked yes)
			(layer "F.Fab")
			(hide yes)
			(effects
				(font
					(size 0.7874 0.5842)
					(thickness 0.1524)
				)
			)
		)
		(property "Device Type" "RESISTOR-G155-14701-01,4.7KOHMA"
			(at 0.008382 1.210564 270)
			(unlocked yes)
			(layer "F.Fab")
			(hide yes)
			(effects
				(font
					(size 0.7874 0.5842)
					(thickness 0.1524)
				)
			)
		)
		(property "User Part Number" "PARTNUM*"
			(at 0.02032 4.024884 270)
			(unlocked yes)
			(layer "Cmts.User")
			(hide yes)
			(effects
				(font
					(size 0.7874 0.5842)
					(thickness 0.1524)
				)
			)
		)
		(property "Tolerance" "TOL*"
			(at 0.044704 3.05435 270)
			(unlocked yes)
			(layer "Cmts.User")
			(hide yes)
			(effects
				(font
					(size 0.7874 0.5842)
					(thickness 0.1524)
				)
			)
		)
		(duplicate_pad_numbers_are_jumpers no)
		(fp_line
			(start -1.143 0.5588)
			(end 1.143 0.5588)
			(stroke
				(width 0.1)
				(type default)
			)
			(layer "F.SilkS")
		)
		(fp_line
			(start 1.143 0.5588)
			(end 1.143 -0.5588)
			(stroke
				(width 0.1)
				(type default)
			)
			(layer "F.SilkS")
		)
		(fp_line
			(start -1.143 -0.5588)
			(end -1.143 0.5588)
			(stroke
				(width 0.1)
				(type default)
			)
			(layer "F.SilkS")
		)
		(fp_line
			(start 1.143 -0.5588)
			(end -1.143 -0.5588)
			(stroke
				(width 0.1)
				(type default)
			)
			(layer "F.SilkS")
		)
		(fp_rect
			(start 1.143 0.5588)
			(end -1.143 -0.5588)
			(stroke
				(width 0)
				(type default)
			)
			(fill no)
			(layer "F.CrtYd")
		)
		(fp_line
			(start -0.508 0.3048)
			(end 0.508 0.3048)
			(stroke
				(width 0.1)
				(type default)
			)
			(layer "F.Fab")
		)
		(fp_line
			(start 0.508 0.3048)
			(end 0.508 -0.3048)
			(stroke
				(width 0.1)
				(type default)
			)
			(layer "F.Fab")
		)
		(fp_line
			(start -0.508 -0.3048)
			(end -0.508 0.3048)
			(stroke
				(width 0.1)
				(type default)
			)
			(layer "F.Fab")
		)
		(fp_line
			(start 0.508 -0.3048)
			(end -0.508 -0.3048)
			(stroke
				(width 0.1)
				(type default)
			)
			(layer "F.Fab")
		)
		(pad "1" smd rect
			(at -0.5334 0 270)
			(size 0.7112 0.6096)
			(layers "F.Cu" "F.Mask" "F.Paste")
			(net "VDD3V3_OSC_125M")
		)
		(pad "2" smd rect
			(at 0.5334 0 270)
			(size 0.7112 0.6096)
			(layers "F.Cu" "F.Mask" "F.Paste")
			(net "CLK_125M_OE")
		)
		(zone
			(layer "F.Cu")
			(hatch none 0.5)
			(connect_pads
				(clearance 0)
			)
			(min_thickness 0.25)
			(keepout
				(tracks allowed)
				(vias not_allowed)
				(pads allowed)
				(copperpour not_allowed)
				(footprints allowed)
			)
			(placement
				(enabled no)
				(sheetname "")
			)
			(fill
				(thermal_gap 0.5)
				(thermal_bridge_width 0.5)
				(island_removal_mode 0)
			)
			(polygon
				(pts
					(xy 95.4532 -22.6568) (xy 96.0628 -22.6568) (xy 96.0628 -22.8092) (xy 95.4532 -22.8092)
				)
			)
		)
	)
	(footprint ""
		(layer "F.Cu")
		(at 18.161 -61.5442 90)
		(property "Reference" "C312"
			(at 0.1778 -0.97663 90)
			(unlocked yes)
			(layer "F.SilkS")
			(effects
				(font
					(size 0.7874 0.5842)
					(thickness 0.1524)
				)
			)
		)
		(property "Value" "VAL*"
			(at 0.0762 2.067306 90)
			(unlocked yes)
			(layer "F.Fab")
			(hide yes)
			(effects
				(font
					(size 0.7874 0.5842)
					(thickness 0.1524)
				)
			)
		)
		(property "Tolerance" "TOL*"
			(at 0.0762 3.032506 90)
			(unlocked yes)
			(layer "Cmts.User")
			(hide yes)
			(effects
				(font
					(size 0.7874 0.5842)
					(thickness 0.1524)
				)
			)
		)
		(property "User Part Number" "PARTNUM*"
			(at 0.1016 4.023106 90)
			(unlocked yes)
			(layer "Cmts.User")
			(hide yes)
			(effects
				(font
					(size 0.7874 0.5842)
					(thickness 0.1524)
				)
			)
		)
		(property "Device Type" "CAPACITOR-G105-0B104-CK,0.1UF,A"
			(at 0.0508 1.127506 90)
			(unlocked yes)
			(layer "F.Fab")
			(hide yes)
			(effects
				(font
					(size 0.7874 0.5842)
					(thickness 0.1524)
				)
			)
		)
		(duplicate_pad_numbers_are_jumpers no)
		(fp_line
			(start 1.143 -0.5588)
			(end -1.143 -0.5588)
			(stroke
				(width 0.1)
				(type default)
			)
			(layer "F.SilkS")
		)
		(fp_line
			(start -1.143 -0.5588)
			(end -1.143 0.5588)
			(stroke
				(width 0.1)
				(type default)
			)
			(layer "F.SilkS")
		)
		(fp_line
			(start 1.143 0.5588)
			(end 1.143 -0.5588)
			(stroke
				(width 0.1)
				(type default)
			)
			(layer "F.SilkS")
		)
		(fp_line
			(start -1.143 0.5588)
			(end 1.143 0.5588)
			(stroke
				(width 0.1)
				(type default)
			)
			(layer "F.SilkS")
		)
		(fp_poly
			(pts
				(xy -1.143 0.5588) (xy 1.143 0.5588) (xy 1.143 -0.5588) (xy -1.143 -0.5588)
			)
			(stroke
				(width 0)
				(type default)
			)
			(fill no)
			(layer "F.CrtYd")
		)
		(fp_line
			(start 0.508 -0.3048)
			(end -0.508 -0.3048)
			(stroke
				(width 0.1)
				(type default)
			)
			(layer "F.Fab")
		)
		(fp_line
			(start -0.508 -0.3048)
			(end -0.508 0.3048)
			(stroke
				(width 0.1)
				(type default)
			)
			(layer "F.Fab")
		)
		(fp_line
			(start 0.508 0.3048)
			(end 0.508 -0.3048)
			(stroke
				(width 0.1)
				(type default)
			)
			(layer "F.Fab")
		)
		(fp_line
			(start -0.508 0.3048)
			(end 0.508 0.3048)
			(stroke
				(width 0.1)
				(type default)
			)
			(layer "F.Fab")
		)
		(pad "1" smd rect
			(at -0.5334 0 90)
			(size 0.7112 0.6096)
			(layers "F.Cu" "F.Mask" "F.Paste")
			(net "XP3R3V")
		)
		(pad "2" smd rect
			(at 0.5334 0 90)
			(size 0.7112 0.6096)
			(layers "F.Cu" "F.Mask" "F.Paste")
			(net "SG")
		)
		(zone
			(layer "F.Cu")
			(hatch none 0.5)
			(connect_pads
				(clearance 0)
			)
			(min_thickness 0.25)
			(keepout
				(tracks not_allowed)
				(vias allowed)
				(pads allowed)
				(copperpour not_allowed)
				(footprints allowed)
			)
			(placement
				(enabled no)
				(sheetname "")
			)
			(fill
				(thermal_gap 0.5)
				(thermal_bridge_width 0.5)
				(island_removal_mode 0)
			)
			(polygon
				(pts
					(xy 18.4658 -61.468) (xy 18.4658 -61.6204) (xy 17.8562 -61.6204) (xy 17.8562 -61.468)
				)
			)
		)
		(zone
			(layer "F.Cu")
			(hatch none 0.5)
			(connect_pads
				(clearance 0)
			)
			(min_thickness 0.25)
			(keepout
				(tracks allowed)
				(vias not_allowed)
				(pads allowed)
				(copperpour not_allowed)
				(footprints allowed)
			)
			(placement
				(enabled no)
				(sheetname "")
			)
			(fill
				(thermal_gap 0.5)
				(thermal_bridge_width 0.5)
				(island_removal_mode 0)
			)
			(polygon
				(pts
					(xy 18.4658 -61.468) (xy 18.4658 -61.6204) (xy 17.8562 -61.6204) (xy 17.8562 -61.468)
				)
			)
		)
	)
	(footprint ""
		(layer "F.Cu")
		(at 111.125 -100.711)
		(property "Reference" "C314"
			(at 3.175 -3.13563 0)
			(unlocked yes)
			(layer "F.SilkS")
			(effects
				(font
					(size 0.7874 0.5842)
					(thickness 0.1524)
				)
			)
		)
		(property "Value" "VAL*"
			(at 0.0762 2.067306 0)
			(unlocked yes)
			(layer "F.Fab")
			(hide yes)
			(effects
				(font
					(size 0.7874 0.5842)
					(thickness 0.1524)
				)
			)
		)
		(property "Tolerance" "TOL*"
			(at 0.0762 3.032506 0)
			(unlocked yes)
			(layer "Cmts.User")
			(hide yes)
			(effects
				(font
					(size 0.7874 0.5842)
					(thickness 0.1524)
				)
			)
		)
		(property "User Part Number" "PARTNUM*"
			(at 0.1016 4.023106 0)
			(unlocked yes)
			(layer "Cmts.User")
			(hide yes)
			(effects
				(font
					(size 0.7874 0.5842)
					(thickness 0.1524)
				)
			)
		)
		(property "Device Type" "CAPACITOR-G105-0C106-BM,10UF,2A"
			(at 0.0508 1.127506 0)
			(unlocked yes)
			(layer "F.Fab")
			(hide yes)
			(effects
				(font
					(size 0.7874 0.5842)
					(thickness 0.1524)
				)
			)
		)
		(duplicate_pad_numbers_are_jumpers no)
		(fp_line
			(start -1.143 -0.5588)
			(end -1.143 0.5588)
			(stroke
				(width 0.1)
				(type default)
			)
			(layer "F.SilkS")
		)
		(fp_line
			(start -1.143 0.5588)
			(end 1.143 0.5588)
			(stroke
				(width 0.1)
				(type default)
			)
			(layer "F.SilkS")
		)
		(fp_line
			(start 1.143 -0.5588)
			(end -1.143 -0.5588)
			(stroke
				(width 0.1)
				(type default)
			)
			(layer "F.SilkS")
		)
		(fp_line
			(start 1.143 0.5588)
			(end 1.143 -0.5588)
			(stroke
				(width 0.1)
				(type default)
			)
			(layer "F.SilkS")
		)
		(fp_poly
			(pts
				(xy -1.143 0.5588) (xy 1.143 0.5588) (xy 1.143 -0.5588) (xy -1.143 -0.5588)
			)
			(stroke
				(width 0)
				(type default)
			)
			(fill no)
			(layer "F.CrtYd")
		)
		(fp_line
			(start -0.508 -0.3048)
			(end -0.508 0.3048)
			(stroke
				(width 0.1)
				(type default)
			)
			(layer "F.Fab")
		)
		(fp_line
			(start -0.508 0.3048)
			(end 0.508 0.3048)
			(stroke
				(width 0.1)
				(type default)
			)
			(layer "F.Fab")
		)
		(fp_line
			(start 0.508 -0.3048)
			(end -0.508 -0.3048)
			(stroke
				(width 0.1)
				(type default)
			)
			(layer "F.Fab")
		)
		(fp_line
			(start 0.508 0.3048)
			(end 0.508 -0.3048)
			(stroke
				(width 0.1)
				(type default)
			)
			(layer "F.Fab")
		)
		(pad "1" smd rect
			(at -0.5334 0)
			(size 0.7112 0.6096)
			(layers "F.Cu" "F.Mask" "F.Paste")
			(net "XP3R3V_FPGA")
		)
		(pad "2" smd rect
			(at 0.5334 0)
			(size 0.7112 0.6096)
			(layers "F.Cu" "F.Mask" "F.Paste")
			(net "SG")
		)
		(zone
			(layer "F.Cu")
			(hatch none 0.5)
			(connect_pads
				(clearance 0)
			)
			(min_thickness 0.25)
			(keepout
				(tracks not_allowed)
				(vias allowed)
				(pads allowed)
				(copperpour not_allowed)
				(footprints allowed)
			)
			(placement
				(enabled no)
				(sheetname "")
			)
			(fill
				(thermal_gap 0.5)
				(thermal_bridge_width 0.5)
				(island_removal_mode 0)
			)
			(polygon
				(pts
					(xy 111.0488 -100.4062) (xy 111.2012 -100.4062) (xy 111.2012 -101.0158) (xy 111.0488 -101.0158)
				)
			)
		)
		(zone
			(layer "F.Cu")
			(hatch none 0.5)
			(connect_pads
				(clearance 0)
			)
			(min_thickness 0.25)
			(keepout
				(tracks allowed)
				(vias not_allowed)
				(pads allowed)
				(copperpour not_allowed)
				(footprints allowed)
			)
			(placement
				(enabled no)
				(sheetname "")
			)
			(fill
				(thermal_gap 0.5)
				(thermal_bridge_width 0.5)
				(island_removal_mode 0)
			)
			(polygon
				(pts
					(xy 111.0488 -100.4062) (xy 111.2012 -100.4062) (xy 111.2012 -101.0158) (xy 111.0488 -101.0158)
				)
			)
		)
	)
	(footprint ""
		(layer "F.Cu")
		(at 82.677 -93.599 90)
		(property "Reference" "C18"
			(at -3.81 -3.38963 90)
			(unlocked yes)
			(layer "F.SilkS")
			(effects
				(font
					(size 0.7874 0.5842)
					(thickness 0.1524)
				)
			)
		)
		(property "Value" "VAL*"
			(at 0.0762 2.067306 90)
			(unlocked yes)
			(layer "F.Fab")
			(hide yes)
			(effects
				(font
					(size 0.7874 0.5842)
					(thickness 0.1524)
				)
			)
		)
		(property "Tolerance" "TOL*"
			(at 0.0762 3.032506 90)
			(unlocked yes)
			(layer "Cmts.User")
			(hide yes)
			(effects
				(font
					(size 0.7874 0.5842)
					(thickness 0.1524)
				)
			)
		)
		(property "User Part Number" "PARTNUM*"
			(at 0.1016 4.023106 90)
			(unlocked yes)
			(layer "Cmts.User")
			(hide yes)
			(effects
				(font
					(size 0.7874 0.5842)
					(thickness 0.1524)
				)
			)
		)
		(property "Device Type" "CAPACITOR-G105-0B104-CK,0.1UF,A"
			(at 0.0508 1.127506 90)
			(unlocked yes)
			(layer "F.Fab")
			(hide yes)
			(effects
				(font
					(size 0.7874 0.5842)
					(thickness 0.1524)
				)
			)
		)
		(duplicate_pad_numbers_are_jumpers no)
		(fp_line
			(start 1.143 -0.5588)
			(end -1.143 -0.5588)
			(stroke
				(width 0.1)
				(type default)
			)
			(layer "F.SilkS")
		)
		(fp_line
			(start -1.143 -0.5588)
			(end -1.143 0.5588)
			(stroke
				(width 0.1)
				(type default)
			)
			(layer "F.SilkS")
		)
		(fp_line
			(start 1.143 0.5588)
			(end 1.143 -0.5588)
			(stroke
				(width 0.1)
				(type default)
			)
			(layer "F.SilkS")
		)
		(fp_line
			(start -1.143 0.5588)
			(end 1.143 0.5588)
			(stroke
				(width 0.1)
				(type default)
			)
			(layer "F.SilkS")
		)
		(fp_rect
			(start -1.143 -0.5588)
			(end 1.143 0.5588)
			(stroke
				(width 0)
				(type default)
			)
			(fill no)
			(layer "F.CrtYd")
		)
		(fp_line
			(start 0.508 -0.3048)
			(end -0.508 -0.3048)
			(stroke
				(width 0.1)
				(type default)
			)
			(layer "F.Fab")
		)
		(fp_line
			(start -0.508 -0.3048)
			(end -0.508 0.3048)
			(stroke
				(width 0.1)
				(type default)
			)
			(layer "F.Fab")
		)
		(fp_line
			(start 0.508 0.3048)
			(end 0.508 -0.3048)
			(stroke
				(width 0.1)
				(type default)
			)
			(layer "F.Fab")
		)
		(fp_line
			(start -0.508 0.3048)
			(end 0.508 0.3048)
			(stroke
				(width 0.1)
				(type default)
			)
			(layer "F.Fab")
		)
		(pad "1" smd rect
			(at -0.5334 0 90)
			(size 0.7112 0.6096)
			(layers "F.Cu" "F.Mask" "F.Paste")
			(net "XP3R3V")
		)
		(pad "2" smd rect
			(at 0.5334 0 90)
			(size 0.7112 0.6096)
			(layers "F.Cu" "F.Mask" "F.Paste")
			(net "SG")
		)
		(zone
			(layer "F.Cu")
			(hatch none 0.5)
			(connect_pads
				(clearance 0)
			)
			(min_thickness 0.25)
			(keepout
				(tracks allowed)
				(vias not_allowed)
				(pads allowed)
				(copperpour not_allowed)
				(footprints allowed)
			)
			(placement
				(enabled no)
				(sheetname "")
			)
			(fill
				(thermal_gap 0.5)
				(thermal_bridge_width 0.5)
				(island_removal_mode 0)
			)
			(polygon
				(pts
					(xy 82.3722 -93.5228) (xy 82.9818 -93.5228) (xy 82.9818 -93.6752) (xy 82.3722 -93.6752)
				)
			)
		)
	)
	(footprint ""
		(layer "F.Cu")
		(at 38.989 -78.867 -90)
		(property "Reference" "TP3"
			(at 0 0 270)
			(layer "F.SilkS")
			(hide yes)
			(effects
				(font
					(size 1.27 1.27)
				)
			)
		)
		(property "Value" ""
			(at 0 0 270)
			(layer "F.Fab")
			(effects
				(font
					(size 1.27 1.27)
				)
			)
		)
		(property "Device Type" "TP_PIONT-TP010CT020B030_PTH-TPA"
			(at -1.341882 0.996696 270)
			(unlocked yes)
			(layer "F.Fab")
			(hide yes)
			(effects
				(font
					(size 0.7874 0.5842)
					(thickness 0.1524)
				)
				(justify left)
			)
		)
		(duplicate_pad_numbers_are_jumpers no)
		(fp_poly
			(pts
				(arc
					(start 0 -0.889)
					(mid 0 0.889)
					(end 0 -0.889)
				)
			)
			(stroke
				(width 0)
				(type default)
			)
			(fill no)
			(layer "B.CrtYd")
		)
		(fp_poly
			(pts
				(arc
					(start 0 -0.889)
					(mid 0 0.889)
					(end 0 -0.889)
				)
			)
			(stroke
				(width 0)
				(type default)
			)
			(fill no)
			(layer "F.CrtYd")
		)
		(pad "1" thru_hole circle
			(at 0 0 270)
			(size 0.508 0.508)
			(drill 0.254)
			(layers "*.Cu" "*.Mask")
			(remove_unused_layers no)
			(net "XP3R3V_FT4232")
			(clearance 0.1016)
			(padstack
				(mode front_inner_back)
				(layer "Inner"
					(shape circle)
					(size 0.508 0.508)
					(clearance 0.1016)
				)
				(layer "B.Cu"
					(shape circle)
					(size 0.762 0.762)
					(clearance -0.0254)
				)
			)
		)
	)
	(footprint ""
		(layer "F.Cu")
		(at 12.8778 -68.072)
		(property "Reference" "C317"
			(at 0.3302 -5.67563 0)
			(unlocked yes)
			(layer "F.SilkS")
			(effects
				(font
					(size 0.7874 0.5842)
					(thickness 0.1524)
				)
			)
		)
		(property "Value" "VAL*"
			(at 0.193548 2.13614 0)
			(unlocked yes)
			(layer "F.Fab")
			(hide yes)
			(effects
				(font
					(size 0.7874 0.5842)
					(thickness 0.1524)
				)
			)
		)
		(property "User Part Number" "PARTNUM*"
			(at 0.216154 4.185666 0)
			(unlocked yes)
			(layer "Cmts.User")
			(hide yes)
			(effects
				(font
					(size 0.7874 0.5842)
					(thickness 0.1524)
				)
			)
		)
		(property "Device Type" "CAPACITOR-G104-0A180-FJ,18PF,5%"
			(at 0.184404 1.180592 0)
			(unlocked yes)
			(layer "F.Fab")
			(hide yes)
			(effects
				(font
					(size 0.7874 0.5842)
					(thickness 0.1524)
				)
			)
		)
		(property "Tolerance" "TOL*"
			(at 0.216154 3.1496 0)
			(unlocked yes)
			(layer "Cmts.User")
			(hide yes)
			(effects
				(font
					(size 0.7874 0.5842)
					(thickness 0.1524)
				)
			)
		)
		(duplicate_pad_numbers_are_jumpers no)
		(fp_line
			(start -0.671322 -0.4445)
			(end 0.671322 -0.4445)
			(stroke
				(width 0.1)
				(type default)
			)
			(layer "F.SilkS")
		)
		(fp_line
			(start -0.671322 0.4445)
			(end -0.671322 -0.4445)
			(stroke
				(width 0.1)
				(type default)
			)
			(layer "F.SilkS")
		)
		(fp_line
			(start 0.671322 -0.4445)
			(end 0.671322 0.4445)
			(stroke
				(width 0.1)
				(type default)
			)
			(layer "F.SilkS")
		)
		(fp_line
			(start 0.671322 0.4445)
			(end -0.671322 0.4445)
			(stroke
				(width 0.1)
				(type default)
			)
			(layer "F.SilkS")
		)
		(fp_rect
			(start -0.671322 0.4445)
			(end 0.671322 -0.4445)
			(stroke
				(width 0)
				(type default)
			)
			(fill no)
			(layer "F.CrtYd")
		)
		(fp_line
			(start -0.31496 -0.1651)
			(end -0.31496 0.1651)
			(stroke
				(width 0.1)
				(type default)
			)
			(layer "F.Fab")
		)
		(fp_line
			(start -0.31496 0.1651)
			(end 0.31496 0.1651)
			(stroke
				(width 0.1)
				(type default)
			)
			(layer "F.Fab")
		)
		(fp_line
			(start 0.31496 -0.1651)
			(end -0.31496 -0.1651)
			(stroke
				(width 0.1)
				(type default)
			)
			(layer "F.Fab")
		)
		(fp_line
			(start 0.31496 0.1651)
			(end 0.31496 -0.1651)
			(stroke
				(width 0.1)
				(type default)
			)
			(layer "F.Fab")
		)
		(pad "1" smd rect
			(at -0.264922 0)
			(size 0.3048 0.381)
			(layers "F.Cu" "F.Mask" "F.Paste")
			(net "SG")
		)
		(pad "2" smd rect
			(at 0.264922 0)
			(size 0.3048 0.381)
			(layers "F.Cu" "F.Mask" "F.Paste")
			(net "UNNAMED_12_CAPACITOR_I328_2")
		)
		(zone
			(layer "F.Cu")
			(hatch none 0.5)
			(connect_pads
				(clearance 0)
			)
			(min_thickness 0.25)
			(keepout
				(tracks allowed)
				(vias not_allowed)
				(pads allowed)
				(copperpour not_allowed)
				(footprints allowed)
			)
			(placement
				(enabled no)
				(sheetname "")
			)
			(fill
				(thermal_gap 0.5)
				(thermal_bridge_width 0.5)
				(island_removal_mode 0)
			)
			(polygon
				(pts
					(xy 12.765278 -68.2625) (xy 12.765278 -67.8815) (xy 12.990322 -67.8815) (xy 12.990322 -68.2625)
				)
			)
		)
		(zone
			(layer "F.Cu")
			(hatch none 0.5)
			(connect_pads
				(clearance 0)
			)
			(min_thickness 0.25)
			(keepout
				(tracks not_allowed)
				(vias allowed)
				(pads allowed)
				(copperpour not_allowed)
				(footprints allowed)
			)
			(placement
				(enabled no)
				(sheetname "")
			)
			(fill
				(thermal_gap 0.5)
				(thermal_bridge_width 0.5)
				(island_removal_mode 0)
			)
			(polygon
				(pts
					(xy 12.765278 -67.8815) (xy 12.990322 -67.8815) (xy 12.990322 -68.2625) (xy 12.765278 -68.2625)
				)
			)
		)
	)
	(footprint ""
		(layer "F.Cu")
		(at 95.1484 -45.2628)
		(property "Reference" "TP47"
			(at -0.80645 1.27 90)
			(unlocked yes)
			(layer "F.SilkS")
			(effects
				(font
					(size 0.635 0.4064)
					(thickness 0.1524)
				)
				(justify left)
			)
		)
		(property "Value" ""
			(at 0 0 0)
			(layer "F.Fab")
			(effects
				(font
					(size 1.27 1.27)
				)
			)
		)
		(property "Device Type" "TP_PIONT-TP010CT020B030_PTH-TPA"
			(at -1.341882 0.996696 0)
			(unlocked yes)
			(layer "F.Fab")
			(hide yes)
			(effects
				(font
					(size 0.7874 0.5842)
					(thickness 0.000001)
				)
				(justify left)
			)
		)
		(duplicate_pad_numbers_are_jumpers no)
		(fp_poly
			(pts
				(arc
					(start 0.889 0)
					(mid -0.889 0)
					(end 0.889 0)
				)
			)
			(stroke
				(width 0)
				(type default)
			)
			(fill no)
			(layer "B.CrtYd")
		)
		(fp_poly
			(pts
				(arc
					(start 0.889 0)
					(mid -0.889 0)
					(end 0.889 0)
				)
			)
			(stroke
				(width 0)
				(type default)
			)
			(fill no)
			(layer "F.CrtYd")
		)
		(pad "1" thru_hole circle
			(at 0 0)
			(size 0.508 0.508)
			(drill 0.254)
			(layers "*.Cu" "*.Mask")
			(remove_unused_layers no)
			(net "FPGA_MGTRREF")
			(clearance 0.1016)
			(padstack
				(mode front_inner_back)
				(layer "Inner"
					(shape circle)
					(size 0.508 0.508)
					(clearance 0.1016)
				)
				(layer "B.Cu"
					(shape circle)
					(size 0.762 0.762)
					(clearance -0.0254)
				)
			)
		)
	)
	(footprint ""
		(layer "F.Cu")
		(at 32.021018 -46.746922)
		(property "Reference" "MAC_PIN2"
			(at 0.127762 2.580132 0)
			(unlocked yes)
			(layer "F.SilkS")
			(effects
				(font
					(size 0.7874 0.5842)
					(thickness 0.1524)
				)
			)
		)
		(property "Value" ""
			(at 0 0 0)
			(layer "F.Fab")
			(effects
				(font
					(size 1.27 1.27)
				)
			)
		)
		(property "User Part Number" "PARTNUM*"
			(at 0 3.826764 0)
			(unlocked yes)
			(layer "Cmts.User")
			(hide yes)
			(effects
				(font
					(size 0.7874 0.5842)
					(thickness 0.1524)
				)
			)
		)
		(property "Device Type" "NUT-A200-00029-FB"
			(at 0 2.632964 0)
			(unlocked yes)
			(layer "F.Fab")
			(hide yes)
			(effects
				(font
					(size 0.7874 0.5842)
					(thickness 0.1524)
				)
			)
		)
		(duplicate_pad_numbers_are_jumpers no)
		(fp_circle
			(center 0 0)
			(end 1.524 0)
			(stroke
				(width 0.1)
				(type default)
			)
			(fill no)
			(layer "F.SilkS")
		)
		(fp_poly
			(pts
				(arc
					(start -1.260856 -0.1524)
					(mid -0.898049 -0.898049)
					(end -0.1524 -1.260856)
				)
				(arc
					(start -0.1524 -0.991616)
					(mid -0.709411 -0.709411)
					(end -0.991616 -0.1524)
				)
			)
			(stroke
				(width 0)
				(type default)
			)
			(fill yes)
			(layer "F.Paste")
		)
		(fp_poly
			(pts
				(arc
					(start -0.1524 1.260856)
					(mid -0.898049 0.898049)
					(end -1.260856 0.1524)
				)
				(arc
					(start -0.991616 0.1524)
					(mid -0.709411 0.709411)
					(end -0.1524 0.991616)
				)
			)
			(stroke
				(width 0)
				(type default)
			)
			(fill yes)
			(layer "F.Paste")
		)
		(fp_poly
			(pts
				(arc
					(start 0.1524 -1.260856)
					(mid 0.898049 -0.898049)
					(end 1.260856 -0.1524)
				)
				(arc
					(start 0.991616 -0.1524)
					(mid 0.709411 -0.709411)
					(end 0.1524 -0.991616)
				)
			)
			(stroke
				(width 0)
				(type default)
			)
			(fill yes)
			(layer "F.Paste")
		)
		(fp_poly
			(pts
				(arc
					(start 1.260856 0.1524)
					(mid 0.898049 0.898049)
					(end 0.1524 1.260856)
				)
				(arc
					(start 0.1524 0.991616)
					(mid 0.709411 0.709411)
					(end 0.991616 0.1524)
				)
			)
			(stroke
				(width 0)
				(type default)
			)
			(fill yes)
			(layer "F.Paste")
		)
		(fp_poly
			(pts
				(arc
					(start 6.35 0)
					(mid -6.35 0)
					(end 6.35 0)
				)
			)
			(stroke
				(width 0)
				(type default)
			)
			(fill no)
			(layer "B.CrtYd")
		)
		(fp_poly
			(pts
				(arc
					(start 1.778 0)
					(mid -1.778 0)
					(end 1.778 0)
				)
			)
			(stroke
				(width 0)
				(type default)
			)
			(fill no)
			(layer "F.CrtYd")
		)
		(fp_circle
			(center 0 0)
			(end 1.1684 0)
			(stroke
				(width 0.1)
				(type default)
			)
			(fill no)
			(layer "F.Fab")
		)
		(pad "1" thru_hole circle
			(at 0 0)
			(size 2.54 2.54)
			(drill 2.0066)
			(layers "*.Cu" "*.Mask")
			(remove_unused_layers no)
			(net "SG")
			(thermal_gap 0.0254)
			(padstack
				(mode front_inner_back)
				(layer "Inner"
					(shape circle)
					(size 2.54 2.54)
					(clearance 0.0254)
				)
				(layer "B.Cu"
					(shape circle)
					(size 2.54 2.54)
				)
			)
		)
	)
	(footprint ""
		(layer "F.Cu")
		(at 54.61 -15.621 90)
		(property "Reference" "C288"
			(at 3.556 0.54737 90)
			(unlocked yes)
			(layer "F.SilkS")
			(effects
				(font
					(size 0.7874 0.5842)
					(thickness 0.1524)
				)
			)
		)
		(property "Value" "VAL*"
			(at 0.0762 2.067306 90)
			(unlocked yes)
			(layer "F.Fab")
			(hide yes)
			(effects
				(font
					(size 0.7874 0.5842)
					(thickness 0.1524)
				)
			)
		)
		(property "Device Type" "CAPACITOR-G105-0B104-EK,0.1UF,A"
			(at 0.0508 1.127506 90)
			(unlocked yes)
			(layer "F.Fab")
			(hide yes)
			(effects
				(font
					(size 0.7874 0.5842)
					(thickness 0.1524)
				)
			)
		)
		(property "User Part Number" "PARTNUM*"
			(at 0.1016 4.023106 90)
			(unlocked yes)
			(layer "Cmts.User")
			(hide yes)
			(effects
				(font
					(size 0.7874 0.5842)
					(thickness 0.1524)
				)
			)
		)
		(property "Tolerance" "TOL*"
			(at 0.0762 3.032506 90)
			(unlocked yes)
			(layer "Cmts.User")
			(hide yes)
			(effects
				(font
					(size 0.7874 0.5842)
					(thickness 0.1524)
				)
			)
		)
		(duplicate_pad_numbers_are_jumpers no)
		(fp_line
			(start 1.143 -0.5588)
			(end -1.143 -0.5588)
			(stroke
				(width 0.1)
				(type default)
			)
			(layer "F.SilkS")
		)
		(fp_line
			(start -1.143 -0.5588)
			(end -1.143 0.5588)
			(stroke
				(width 0.1)
				(type default)
			)
			(layer "F.SilkS")
		)
		(fp_line
			(start 1.143 0.5588)
			(end 1.143 -0.5588)
			(stroke
				(width 0.1)
				(type default)
			)
			(layer "F.SilkS")
		)
		(fp_line
			(start -1.143 0.5588)
			(end 1.143 0.5588)
			(stroke
				(width 0.1)
				(type default)
			)
			(layer "F.SilkS")
		)
		(fp_poly
			(pts
				(xy -1.143 0.5588) (xy 1.143 0.5588) (xy 1.143 -0.5588) (xy -1.143 -0.5588)
			)
			(stroke
				(width 0)
				(type default)
			)
			(fill no)
			(layer "F.CrtYd")
		)
		(fp_line
			(start 0.508 -0.3048)
			(end -0.508 -0.3048)
			(stroke
				(width 0.1)
				(type default)
			)
			(layer "F.Fab")
		)
		(fp_line
			(start -0.508 -0.3048)
			(end -0.508 0.3048)
			(stroke
				(width 0.1)
				(type default)
			)
			(layer "F.Fab")
		)
		(fp_line
			(start 0.508 0.3048)
			(end 0.508 -0.3048)
			(stroke
				(width 0.1)
				(type default)
			)
			(layer "F.Fab")
		)
		(fp_line
			(start -0.508 0.3048)
			(end 0.508 0.3048)
			(stroke
				(width 0.1)
				(type default)
			)
			(layer "F.Fab")
		)
		(pad "1" smd rect
			(at -0.5334 0 90)
			(size 0.7112 0.6096)
			(layers "F.Cu" "F.Mask" "F.Paste")
			(net "XP3R3V_AUX_PCIE")
		)
		(pad "2" smd rect
			(at 0.5334 0 90)
			(size 0.7112 0.6096)
			(layers "F.Cu" "F.Mask" "F.Paste")
			(net "SG")
		)
		(zone
			(layer "F.Cu")
			(hatch none 0.5)
			(connect_pads
				(clearance 0)
			)
			(min_thickness 0.25)
			(keepout
				(tracks not_allowed)
				(vias allowed)
				(pads allowed)
				(copperpour not_allowed)
				(footprints allowed)
			)
			(placement
				(enabled no)
				(sheetname "")
			)
			(fill
				(thermal_gap 0.5)
				(thermal_bridge_width 0.5)
				(island_removal_mode 0)
			)
			(polygon
				(pts
					(xy 54.9148 -15.5448) (xy 54.9148 -15.6972) (xy 54.3052 -15.6972) (xy 54.3052 -15.5448)
				)
			)
		)
		(zone
			(layer "F.Cu")
			(hatch none 0.5)
			(connect_pads
				(clearance 0)
			)
			(min_thickness 0.25)
			(keepout
				(tracks allowed)
				(vias not_allowed)
				(pads allowed)
				(copperpour not_allowed)
				(footprints allowed)
			)
			(placement
				(enabled no)
				(sheetname "")
			)
			(fill
				(thermal_gap 0.5)
				(thermal_bridge_width 0.5)
				(island_removal_mode 0)
			)
			(polygon
				(pts
					(xy 54.9148 -15.5448) (xy 54.9148 -15.6972) (xy 54.3052 -15.6972) (xy 54.3052 -15.5448)
				)
			)
		)
	)
	(footprint ""
		(layer "F.Cu")
		(at 115.062 -98.298 90)
		(property "Reference" "C81"
			(at 0.127 -1.35763 90)
			(unlocked yes)
			(layer "F.SilkS")
			(effects
				(font
					(size 0.7874 0.5842)
					(thickness 0.1524)
				)
			)
		)
		(property "Value" "VAL*"
			(at 0.0762 2.067306 90)
			(unlocked yes)
			(layer "F.Fab")
			(hide yes)
			(effects
				(font
					(size 0.7874 0.5842)
					(thickness 0.1524)
				)
			)
		)
		(property "Tolerance" "TOL*"
			(at 0.0762 3.032506 90)
			(unlocked yes)
			(layer "Cmts.User")
			(hide yes)
			(effects
				(font
					(size 0.7874 0.5842)
					(thickness 0.1524)
				)
			)
		)
		(property "User Part Number" "PARTNUM*"
			(at 0.1016 4.023106 90)
			(unlocked yes)
			(layer "Cmts.User")
			(hide yes)
			(effects
				(font
					(size 0.7874 0.5842)
					(thickness 0.1524)
				)
			)
		)
		(property "Device Type" "CAPACITOR-G105-0B104-CK,0.1UF,A"
			(at 0.0508 1.127506 90)
			(unlocked yes)
			(layer "F.Fab")
			(hide yes)
			(effects
				(font
					(size 0.7874 0.5842)
					(thickness 0.1524)
				)
			)
		)
		(duplicate_pad_numbers_are_jumpers no)
		(fp_line
			(start 1.143 -0.5588)
			(end -1.143 -0.5588)
			(stroke
				(width 0.1)
				(type default)
			)
			(layer "F.SilkS")
		)
		(fp_line
			(start -1.143 -0.5588)
			(end -1.143 0.5588)
			(stroke
				(width 0.1)
				(type default)
			)
			(layer "F.SilkS")
		)
		(fp_line
			(start 1.143 0.5588)
			(end 1.143 -0.5588)
			(stroke
				(width 0.1)
				(type default)
			)
			(layer "F.SilkS")
		)
		(fp_line
			(start -1.143 0.5588)
			(end 1.143 0.5588)
			(stroke
				(width 0.1)
				(type default)
			)
			(layer "F.SilkS")
		)
		(fp_rect
			(start -1.143 0.5588)
			(end 1.143 -0.5588)
			(stroke
				(width 0)
				(type default)
			)
			(fill no)
			(layer "F.CrtYd")
		)
		(fp_line
			(start 0.508 -0.3048)
			(end -0.508 -0.3048)
			(stroke
				(width 0.1)
				(type default)
			)
			(layer "F.Fab")
		)
		(fp_line
			(start -0.508 -0.3048)
			(end -0.508 0.3048)
			(stroke
				(width 0.1)
				(type default)
			)
			(layer "F.Fab")
		)
		(fp_line
			(start 0.508 0.3048)
			(end 0.508 -0.3048)
			(stroke
				(width 0.1)
				(type default)
			)
			(layer "F.Fab")
		)
		(fp_line
			(start -0.508 0.3048)
			(end 0.508 0.3048)
			(stroke
				(width 0.1)
				(type default)
			)
			(layer "F.Fab")
		)
		(pad "1" smd rect
			(at -0.5334 0 90)
			(size 0.7112 0.6096)
			(layers "F.Cu" "F.Mask" "F.Paste")
			(net "XP3R3V_FPGA")
		)
		(pad "2" smd rect
			(at 0.5334 0 90)
			(size 0.7112 0.6096)
			(layers "F.Cu" "F.Mask" "F.Paste")
			(net "SG")
		)
		(zone
			(layer "F.Cu")
			(hatch none 0.5)
			(connect_pads
				(clearance 0)
			)
			(min_thickness 0.25)
			(keepout
				(tracks allowed)
				(vias not_allowed)
				(pads allowed)
				(copperpour not_allowed)
				(footprints allowed)
			)
			(placement
				(enabled no)
				(sheetname "")
			)
			(fill
				(thermal_gap 0.5)
				(thermal_bridge_width 0.5)
				(island_removal_mode 0)
			)
			(polygon
				(pts
					(xy 115.3668 -98.2218) (xy 115.3668 -98.3742) (xy 114.7572 -98.3742) (xy 114.7572 -98.2218)
				)
			)
		)
	)
	(footprint ""
		(layer "F.Cu")
		(at 28.5242 -85.0646 -90)
		(property "Reference" "U18"
			(at -1.4224 -8.09117 90)
			(unlocked yes)
			(layer "F.SilkS")
			(effects
				(font
					(size 0.7874 0.5842)
					(thickness 0.1524)
				)
			)
		)
		(property "Value" ""
			(at 0 0 270)
			(layer "F.Fab")
			(effects
				(font
					(size 1.27 1.27)
				)
			)
		)
		(property "Device Type" "FT4232HL_REEL_QFP64-G223-10282A"
			(at -0.0127 7.86257 270)
			(unlocked yes)
			(layer "F.Fab")
			(hide yes)
			(effects
				(font
					(size 0.381 0.254)
					(thickness 0.000001)
				)
			)
		)
		(property "User Part Number" "PARTNUM*"
			(at 0.17018 8.41375 270)
			(unlocked yes)
			(layer "Cmts.User")
			(hide yes)
			(effects
				(font
					(size 0.381 0.254)
					(thickness 0.000001)
				)
			)
		)
		(duplicate_pad_numbers_are_jumpers no)
		(fp_line
			(start -6.8834 6.8834)
			(end -6.8834 -6.8834)
			(stroke
				(width 0.1)
				(type default)
			)
			(layer "F.SilkS")
		)
		(fp_line
			(start 6.8834 6.8834)
			(end -6.8834 6.8834)
			(stroke
				(width 0.1)
				(type default)
			)
			(layer "F.SilkS")
		)
		(fp_line
			(start -6.8834 -6.8834)
			(end 6.8834 -6.8834)
			(stroke
				(width 0.1)
				(type default)
			)
			(layer "F.SilkS")
		)
		(fp_line
			(start 6.8834 -6.8834)
			(end 6.8834 6.8834)
			(stroke
				(width 0.1)
				(type default)
			)
			(layer "F.SilkS")
		)
		(fp_poly
			(pts
				(arc
					(start -7.645908 -4.577588)
					(mid -7.645908 -3.561588)
					(end -7.645908 -4.577588)
				)
			)
			(stroke
				(width 0)
				(type default)
			)
			(fill yes)
			(layer "F.SilkS")
		)
		(fp_rect
			(start -7.1374 7.1374)
			(end 7.1374 -7.1374)
			(stroke
				(width 0)
				(type default)
			)
			(fill no)
			(layer "F.CrtYd")
		)
		(fp_line
			(start -5.0038 5.0038)
			(end 5.0038 5.0038)
			(stroke
				(width 0.1)
				(type default)
			)
			(layer "F.Fab")
		)
		(fp_line
			(start 5.0038 5.0038)
			(end 5.0038 -5.0038)
			(stroke
				(width 0.1)
				(type default)
			)
			(layer "F.Fab")
		)
		(fp_line
			(start -5.0038 -5.0038)
			(end -5.0038 5.0038)
			(stroke
				(width 0.1)
				(type default)
			)
			(layer "F.Fab")
		)
		(fp_line
			(start 5.0038 -5.0038)
			(end -5.0038 -5.0038)
			(stroke
				(width 0.1)
				(type default)
			)
			(layer "F.Fab")
		)
		(fp_poly
			(pts
				(arc
					(start -7.66318 -4.57708)
					(mid -7.66318 -3.56108)
					(end -7.66318 -4.57708)
				)
			)
			(stroke
				(width 0)
				(type default)
			)
			(fill yes)
			(layer "F.Fab")
		)
		(fp_text user "32"
			(at 3.94335 7.4422 0)
			(unlocked yes)
			(layer "F.SilkS")
			(effects
				(font
					(size 0.635 0.4064)
					(thickness 0.1524)
				)
			)
		)
		(fp_text user "17"
			(at -3.7084 7.33425 90)
			(unlocked yes)
			(layer "F.SilkS")
			(effects
				(font
					(size 0.635 0.4064)
					(thickness 0.1524)
				)
			)
		)
		(fp_text user "33"
			(at 7.49935 4.0132 0)
			(unlocked yes)
			(layer "F.SilkS")
			(effects
				(font
					(size 0.635 0.4064)
					(thickness 0.1524)
				)
			)
		)
		(fp_text user "16"
			(at -7.35965 3.7592 0)
			(unlocked yes)
			(layer "F.SilkS")
			(effects
				(font
					(size 0.635 0.4064)
					(thickness 0.1524)
				)
			)
		)
		(fp_text user "48"
			(at 7.62635 -4.1148 0)
			(unlocked yes)
			(layer "F.SilkS")
			(effects
				(font
					(size 0.635 0.4064)
					(thickness 0.1524)
				)
			)
		)
		(fp_text user "49"
			(at 4.5466 -7.32155 90)
			(unlocked yes)
			(layer "F.SilkS")
			(effects
				(font
					(size 0.635 0.4064)
					(thickness 0.1524)
				)
			)
		)
		(fp_text user "64"
			(at -4.48945 -8.0518 0)
			(unlocked yes)
			(layer "F.SilkS")
			(effects
				(font
					(size 0.635 0.4064)
					(thickness 0.1524)
				)
			)
		)
		(fp_text user "17"
			(at -3.975354 7.37743 90)
			(unlocked yes)
			(layer "F.Fab")
			(effects
				(font
					(size 0.7874 0.5842)
					(thickness 0.1524)
				)
			)
		)
		(fp_text user "32"
			(at 3.866134 7.371588 90)
			(unlocked yes)
			(layer "F.Fab")
			(effects
				(font
					(size 0.7874 0.5842)
					(thickness 0.1524)
				)
			)
		)
		(fp_text user "16"
			(at -7.2644 4.35483 90)
			(unlocked yes)
			(layer "F.Fab")
			(effects
				(font
					(size 0.7874 0.5842)
					(thickness 0.1524)
				)
			)
		)
		(fp_text user "33"
			(at 7.478268 3.852672 90)
			(unlocked yes)
			(layer "F.Fab")
			(effects
				(font
					(size 0.7874 0.5842)
					(thickness 0.1524)
				)
			)
		)
		(fp_text user "48"
			(at 7.48411 -3.795776 90)
			(unlocked yes)
			(layer "F.Fab")
			(effects
				(font
					(size 0.7874 0.5842)
					(thickness 0.1524)
				)
			)
		)
		(fp_text user "49"
			(at 3.931666 -7.32917 90)
			(unlocked yes)
			(layer "F.Fab")
			(effects
				(font
					(size 0.7874 0.5842)
					(thickness 0.1524)
				)
			)
		)
		(fp_text user "64"
			(at -3.946906 -7.33933 90)
			(unlocked yes)
			(layer "F.Fab")
			(effects
				(font
					(size 0.7874 0.5842)
					(thickness 0.1524)
				)
			)
		)
		(pad "1" smd rect
			(at -5.8166 -3.750056)
			(size 0.3048 1.6256)
			(layers "F.Cu" "F.Mask" "F.Paste")
			(net "SG")
		)
		(pad "2" smd rect
			(at -5.8166 -3.24993)
			(size 0.3048 1.6256)
			(layers "F.Cu" "F.Mask" "F.Paste")
			(net "UNNAMED_524_CAPACITOR_I7_2")
		)
		(pad "3" smd rect
			(at -5.8166 -2.750058)
			(size 0.3048 1.6256)
			(layers "F.Cu" "F.Mask" "F.Paste")
			(net "UNNAMED_524_CAPACITOR_I10_2")
		)
		(pad "4" smd rect
			(at -5.8166 -2.249932)
			(size 0.3048 1.6256)
			(layers "F.Cu" "F.Mask" "F.Paste")
			(net "XP3R3V_VPHY")
		)
		(pad "5" smd rect
			(at -5.8166 -1.75006)
			(size 0.3048 1.6256)
			(layers "F.Cu" "F.Mask" "F.Paste")
			(net "SG")
		)
		(pad "6" smd rect
			(at -5.8166 -1.249934)
			(size 0.3048 1.6256)
			(layers "F.Cu" "F.Mask" "F.Paste")
			(net "UNNAMED_524_FT4232HLREELQFP64_6")
		)
		(pad "7" smd rect
			(at -5.8166 -0.750062)
			(size 0.3048 1.6256)
			(layers "F.Cu" "F.Mask" "F.Paste")
			(net "R_FT_USB_DM")
		)
		(pad "8" smd rect
			(at -5.8166 -0.249936)
			(size 0.3048 1.6256)
			(layers "F.Cu" "F.Mask" "F.Paste")
			(net "R_FT_USB_DP")
		)
		(pad "9" smd rect
			(at -5.8166 0.249936)
			(size 0.3048 1.6256)
			(layers "F.Cu" "F.Mask" "F.Paste")
			(net "XP3R3V_VPLL")
		)
		(pad "10" smd rect
			(at -5.8166 0.750062)
			(size 0.3048 1.6256)
			(layers "F.Cu" "F.Mask" "F.Paste")
			(net "SG")
		)
		(pad "11" smd rect
			(at -5.8166 1.249934)
			(size 0.3048 1.6256)
			(layers "F.Cu" "F.Mask" "F.Paste")
			(net "SG")
		)
		(pad "12" smd rect
			(at -5.8166 1.75006)
			(size 0.3048 1.6256)
			(layers "F.Cu" "F.Mask" "F.Paste")
			(net "FT4232_VREGOUT")
		)
		(pad "13" smd rect
			(at -5.8166 2.249932)
			(size 0.3048 1.6256)
			(layers "F.Cu" "F.Mask" "F.Paste")
			(net "SG")
		)
		(pad "14" smd rect
			(at -5.8166 2.750058)
			(size 0.3048 1.6256)
			(layers "F.Cu" "F.Mask" "F.Paste")
			(net "UNNAMED_524_FT4232HLREELQFP64_7")
		)
		(pad "15" smd rect
			(at -5.8166 3.24993)
			(size 0.3048 1.6256)
			(layers "F.Cu" "F.Mask" "F.Paste")
			(net "SG")
		)
		(pad "16" smd rect
			(at -5.8166 3.750056)
			(size 0.3048 1.6256)
			(layers "F.Cu" "F.Mask" "F.Paste")
			(net "R_FT4232_TCK")
		)
		(pad "17" smd rect
			(at -3.750056 5.8166 90)
			(size 0.3048 1.6256)
			(layers "F.Cu" "F.Mask" "F.Paste")
			(net "R_FT4232_TDI")
		)
		(pad "18" smd rect
			(at -3.24993 5.8166 90)
			(size 0.3048 1.6256)
			(layers "F.Cu" "F.Mask" "F.Paste")
			(net "R_FT4232_TDO")
		)
		(pad "19" smd rect
			(at -2.750058 5.8166 90)
			(size 0.3048 1.6256)
			(layers "F.Cu" "F.Mask" "F.Paste")
			(net "R_FT4232_TMS")
		)
		(pad "20" smd rect
			(at -2.249932 5.8166 90)
			(size 0.3048 1.6256)
			(layers "F.Cu" "F.Mask" "F.Paste")
			(net "XP3R3V_FT4232")
		)
		(pad "21" smd rect
			(at -1.75006 5.8166 90)
			(size 0.3048 1.6256)
			(layers "F.Cu" "F.Mask" "F.Paste")
			(net "FT4232_MUX1_SEL")
		)
		(pad "22" smd rect
			(at -1.249934 5.8166 90)
			(size 0.3048 1.6256)
			(layers "F.Cu" "F.Mask" "F.Paste")
			(net "FT4232_MUX2_SEL")
		)
		(pad "23" smd rect
			(at -0.750062 5.8166 90)
			(size 0.3048 1.6256)
			(layers "F.Cu" "F.Mask" "F.Paste")
			(net "FT4232_MUX3_SEL")
		)
		(pad "24" smd rect
			(at -0.249936 5.8166 90)
			(size 0.3048 1.6256)
			(layers "F.Cu" "F.Mask" "F.Paste")
			(net "UNNAMED_524_FT4232HLREELQFP64_I")
		)
		(pad "25" smd rect
			(at 0.249936 5.8166 90)
			(size 0.3048 1.6256)
			(layers "F.Cu" "F.Mask" "F.Paste")
			(net "SG")
		)
		(pad "26" smd rect
			(at 0.750062 5.8166 90)
			(size 0.3048 1.6256)
			(layers "F.Cu" "F.Mask" "F.Paste")
			(net "R_FT4232_I2C_SCL")
		)
		(pad "27" smd rect
			(at 1.249934 5.8166 90)
			(size 0.3048 1.6256)
			(layers "F.Cu" "F.Mask" "F.Paste")
			(net "R_FT4232_I2C_SDA_OUT")
		)
		(pad "28" smd rect
			(at 1.75006 5.8166 90)
			(size 0.3048 1.6256)
			(layers "F.Cu" "F.Mask" "F.Paste")
			(net "R_FT4232_I2C_SDA_IN")
		)
		(pad "29" smd rect
			(at 2.249932 5.8166 90)
			(size 0.3048 1.6256)
			(layers "F.Cu" "F.Mask" "F.Paste")
			(net "UNNAMED_524_FT4232HLREELQFP64_1")
		)
		(pad "30" smd rect
			(at 2.750058 5.8166 90)
			(size 0.3048 1.6256)
			(layers "F.Cu" "F.Mask" "F.Paste")
			(net "UNNAMED_524_FT4232HLREELQFP64_2")
		)
		(pad "31" smd rect
			(at 3.24993 5.8166 90)
			(size 0.3048 1.6256)
			(layers "F.Cu" "F.Mask" "F.Paste")
			(net "XP3R3V_FT4232")
		)
		(pad "32" smd rect
			(at 3.750056 5.8166 90)
			(size 0.3048 1.6256)
			(layers "F.Cu" "F.Mask" "F.Paste")
			(net "UNNAMED_524_FT4232HLREELQFP64_3")
		)
		(pad "33" smd rect
			(at 5.8166 3.750056)
			(size 0.3048 1.6256)
			(layers "F.Cu" "F.Mask" "F.Paste")
			(net "UNNAMED_524_FT4232HLREELQFP64_4")
		)
		(pad "34" smd rect
			(at 5.8166 3.24993)
			(size 0.3048 1.6256)
			(layers "F.Cu" "F.Mask" "F.Paste")
			(net "UNNAMED_524_FT4232HLREELQFP64_5")
		)
		(pad "35" smd rect
			(at 5.8166 2.750058)
			(size 0.3048 1.6256)
			(layers "F.Cu" "F.Mask" "F.Paste")
			(net "SG")
		)
		(pad "36" smd rect
			(at 5.8166 2.249932)
			(size 0.3048 1.6256)
			(layers "F.Cu" "F.Mask" "F.Paste")
			(net "Net_789")
		)
		(pad "37" smd rect
			(at 5.8166 1.75006)
			(size 0.3048 1.6256)
			(layers "F.Cu" "F.Mask" "F.Paste")
			(net "FT4232_VREGOUT")
		)
		(pad "38" smd rect
			(at 5.8166 1.249934)
			(size 0.3048 1.6256)
			(layers "F.Cu" "F.Mask" "F.Paste")
			(net "R_FT4232_CHC_TX")
		)
		(pad "39" smd rect
			(at 5.8166 0.750062)
			(size 0.3048 1.6256)
			(layers "F.Cu" "F.Mask" "F.Paste")
			(net "R_FT4232_CHC_RX")
		)
		(pad "40" smd rect
			(at 5.8166 0.249936)
			(size 0.3048 1.6256)
			(layers "F.Cu" "F.Mask" "F.Paste")
			(net "Net_802")
		)
		(pad "41" smd rect
			(at 5.8166 -0.249936)
			(size 0.3048 1.6256)
			(layers "F.Cu" "F.Mask" "F.Paste")
			(net "Net_801")
		)
		(pad "42" smd rect
			(at 5.8166 -0.750062)
			(size 0.3048 1.6256)
			(layers "F.Cu" "F.Mask" "F.Paste")
			(net "XP3R3V_FT4232")
		)
		(pad "43" smd rect
			(at 5.8166 -1.249934)
			(size 0.3048 1.6256)
			(layers "F.Cu" "F.Mask" "F.Paste")
			(net "Net_800")
		)
		(pad "44" smd rect
			(at 5.8166 -1.75006)
			(size 0.3048 1.6256)
			(layers "F.Cu" "F.Mask" "F.Paste")
			(net "Net_799")
		)
		(pad "45" smd rect
			(at 5.8166 -2.249932)
			(size 0.3048 1.6256)
			(layers "F.Cu" "F.Mask" "F.Paste")
			(net "Net_798")
		)
		(pad "46" smd rect
			(at 5.8166 -2.750058)
			(size 0.3048 1.6256)
			(layers "F.Cu" "F.Mask" "F.Paste")
			(net "Net_797")
		)
		(pad "47" smd rect
			(at 5.8166 -3.24993)
			(size 0.3048 1.6256)
			(layers "F.Cu" "F.Mask" "F.Paste")
			(net "SG")
		)
		(pad "48" smd rect
			(at 5.8166 -3.750056)
			(size 0.3048 1.6256)
			(layers "F.Cu" "F.Mask" "F.Paste")
			(net "R_FT4232_CHD_TX")
		)
		(pad "49" smd rect
			(at 3.750056 -5.8166 90)
			(size 0.3048 1.6256)
			(layers "F.Cu" "F.Mask" "F.Paste")
			(net "FT4232_VREGOUT")
		)
		(pad "50" smd rect
			(at 3.24993 -5.8166 90)
			(size 0.3048 1.6256)
			(layers "F.Cu" "F.Mask" "F.Paste")
			(net "XP3R3V_FT4232")
		)
		(pad "51" smd rect
			(at 2.750058 -5.8166 90)
			(size 0.3048 1.6256)
			(layers "F.Cu" "F.Mask" "F.Paste")
			(net "SG")
		)
		(pad "52" smd rect
			(at 2.249932 -5.8166 90)
			(size 0.3048 1.6256)
			(layers "F.Cu" "F.Mask" "F.Paste")
			(net "R_FT4232_CHD_RX")
		)
		(pad "53" smd rect
			(at 1.75006 -5.8166 90)
			(size 0.3048 1.6256)
			(layers "F.Cu" "F.Mask" "F.Paste")
			(net "Net_796")
		)
		(pad "54" smd rect
			(at 1.249934 -5.8166 90)
			(size 0.3048 1.6256)
			(layers "F.Cu" "F.Mask" "F.Paste")
			(net "Net_795")
		)
		(pad "55" smd rect
			(at 0.750062 -5.8166 90)
			(size 0.3048 1.6256)
			(layers "F.Cu" "F.Mask" "F.Paste")
			(net "Net_794")
		)
		(pad "56" smd rect
			(at 0.249936 -5.8166 90)
			(size 0.3048 1.6256)
			(layers "F.Cu" "F.Mask" "F.Paste")
			(net "XP3R3V_FT4232")
		)
		(pad "57" smd rect
			(at -0.249936 -5.8166 90)
			(size 0.3048 1.6256)
			(layers "F.Cu" "F.Mask" "F.Paste")
			(net "Net_793")
		)
		(pad "58" smd rect
			(at -0.750062 -5.8166 90)
			(size 0.3048 1.6256)
			(layers "F.Cu" "F.Mask" "F.Paste")
			(net "Net_792")
		)
		(pad "59" smd rect
			(at -1.249934 -5.8166 90)
			(size 0.3048 1.6256)
			(layers "F.Cu" "F.Mask" "F.Paste")
			(net "Net_791")
		)
		(pad "60" smd rect
			(at -1.75006 -5.8166 90)
			(size 0.3048 1.6256)
			(layers "F.Cu" "F.Mask" "F.Paste")
			(net "Net_790")
		)
		(pad "61" smd rect
			(at -2.249932 -5.8166 90)
			(size 0.3048 1.6256)
			(layers "F.Cu" "F.Mask" "F.Paste")
			(net "FTDI_EE_DAT")
		)
		(pad "62" smd rect
			(at -2.750058 -5.8166 90)
			(size 0.3048 1.6256)
			(layers "F.Cu" "F.Mask" "F.Paste")
			(net "FTDI_EE_CLK")
		)
		(pad "63" smd rect
			(at -3.24993 -5.8166 90)
			(size 0.3048 1.6256)
			(layers "F.Cu" "F.Mask" "F.Paste")
			(net "FTDI_EE_CS")
		)
		(pad "64" smd rect
			(at -3.750056 -5.8166 90)
			(size 0.3048 1.6256)
			(layers "F.Cu" "F.Mask" "F.Paste")
			(net "FT4232_VREGOUT")
		)
	)
	(footprint ""
		(layer "F.Cu")
		(at 72.661018 -67.066922)
		(property "Reference" "MAC_PIN5"
			(at 0.998982 -3.129026 0)
			(unlocked yes)
			(layer "F.SilkS")
			(effects
				(font
					(size 0.7874 0.5842)
					(thickness 0.1524)
				)
			)
		)
		(property "Value" ""
			(at 0 0 0)
			(layer "F.Fab")
			(effects
				(font
					(size 1.27 1.27)
				)
			)
		)
		(property "Device Type" "NUT-A200-00029-FB"
			(at 0 2.632964 0)
			(unlocked yes)
			(layer "F.Fab")
			(hide yes)
			(effects
				(font
					(size 0.7874 0.5842)
					(thickness 0.1524)
				)
			)
		)
		(property "User Part Number" "PARTNUM*"
			(at 0 3.826764 0)
			(unlocked yes)
			(layer "Cmts.User")
			(hide yes)
			(effects
				(font
					(size 0.7874 0.5842)
					(thickness 0.1524)
				)
			)
		)
		(duplicate_pad_numbers_are_jumpers no)
		(fp_circle
			(center 0 0)
			(end 1.524 0)
			(stroke
				(width 0.1)
				(type default)
			)
			(fill no)
			(layer "F.SilkS")
		)
		(fp_poly
			(pts
				(arc
					(start -1.260856 -0.1524)
					(mid -0.898049 -0.898049)
					(end -0.1524 -1.260856)
				)
				(arc
					(start -0.1524 -0.991616)
					(mid -0.709411 -0.709411)
					(end -0.991616 -0.1524)
				)
			)
			(stroke
				(width 0)
				(type default)
			)
			(fill yes)
			(layer "F.Paste")
		)
		(fp_poly
			(pts
				(arc
					(start -0.1524 1.260856)
					(mid -0.898049 0.898049)
					(end -1.260856 0.1524)
				)
				(arc
					(start -0.991616 0.1524)
					(mid -0.709411 0.709411)
					(end -0.1524 0.991616)
				)
			)
			(stroke
				(width 0)
				(type default)
			)
			(fill yes)
			(layer "F.Paste")
		)
		(fp_poly
			(pts
				(arc
					(start 0.1524 -1.260856)
					(mid 0.898049 -0.898049)
					(end 1.260856 -0.1524)
				)
				(arc
					(start 0.991616 -0.1524)
					(mid 0.709411 -0.709411)
					(end 0.1524 -0.991616)
				)
			)
			(stroke
				(width 0)
				(type default)
			)
			(fill yes)
			(layer "F.Paste")
		)
		(fp_poly
			(pts
				(arc
					(start 1.260856 0.1524)
					(mid 0.898049 0.898049)
					(end 0.1524 1.260856)
				)
				(arc
					(start 0.1524 0.991616)
					(mid 0.709411 0.709411)
					(end 0.991616 0.1524)
				)
			)
			(stroke
				(width 0)
				(type default)
			)
			(fill yes)
			(layer "F.Paste")
		)
		(fp_poly
			(pts
				(arc
					(start 6.35 0)
					(mid -6.35 0)
					(end 6.35 0)
				)
			)
			(stroke
				(width 0)
				(type default)
			)
			(fill no)
			(layer "B.CrtYd")
		)
		(fp_poly
			(pts
				(arc
					(start 1.778 0)
					(mid -1.778 0)
					(end 1.778 0)
				)
			)
			(stroke
				(width 0)
				(type default)
			)
			(fill no)
			(layer "F.CrtYd")
		)
		(fp_circle
			(center 0 0)
			(end 1.1684 0)
			(stroke
				(width 0.1)
				(type default)
			)
			(fill no)
			(layer "F.Fab")
		)
		(pad "1" thru_hole circle
			(at 0 0)
			(size 2.54 2.54)
			(drill 2.0066)
			(layers "*.Cu" "*.Mask")
			(remove_unused_layers no)
			(net "XP5R0V_MAC")
			(thermal_gap 0.0254)
			(padstack
				(mode front_inner_back)
				(layer "Inner"
					(shape circle)
					(size 2.54 2.54)
					(clearance 0.0254)
				)
				(layer "B.Cu"
					(shape circle)
					(size 2.54 2.54)
				)
			)
		)
	)
	(footprint ""
		(layer "F.Cu")
		(at 52.07 -125.73)
		(property "Reference" "SP55"
			(at 0 0 0)
			(layer "F.SilkS")
			(hide yes)
			(effects
				(font
					(size 1.27 1.27)
				)
			)
		)
		(property "Value" ""
			(at 0 0 0)
			(layer "F.Fab")
			(effects
				(font
					(size 1.27 1.27)
				)
			)
		)
		(duplicate_pad_numbers_are_jumpers no)
	)
	(footprint ""
		(layer "F.Cu")
		(at 57.785 -130.556)
		(property "Reference" "SP28"
			(at 0 0 0)
			(layer "F.SilkS")
			(hide yes)
			(effects
				(font
					(size 1.27 1.27)
				)
			)
		)
		(property "Value" ""
			(at 0 0 0)
			(layer "F.Fab")
			(effects
				(font
					(size 1.27 1.27)
				)
			)
		)
		(duplicate_pad_numbers_are_jumpers no)
	)
	(footprint ""
		(layer "F.Cu")
		(at 72.661018 -26.426922)
		(property "Reference" "MAC_PIN4"
			(at 2.921762 2.580132 0)
			(unlocked yes)
			(layer "F.SilkS")
			(effects
				(font
					(size 0.7874 0.5842)
					(thickness 0.1524)
				)
			)
		)
		(property "Value" ""
			(at 0 0 0)
			(layer "F.Fab")
			(effects
				(font
					(size 1.27 1.27)
				)
			)
		)
		(property "User Part Number" "PARTNUM*"
			(at 0 3.826764 0)
			(unlocked yes)
			(layer "Cmts.User")
			(hide yes)
			(effects
				(font
					(size 0.7874 0.5842)
					(thickness 0.1524)
				)
			)
		)
		(property "Device Type" "NUT-A200-00029-FB"
			(at 0 2.632964 0)
			(unlocked yes)
			(layer "F.Fab")
			(hide yes)
			(effects
				(font
					(size 0.7874 0.5842)
					(thickness 0.1524)
				)
			)
		)
		(duplicate_pad_numbers_are_jumpers no)
		(fp_circle
			(center 0 0)
			(end 1.524 0)
			(stroke
				(width 0.1)
				(type default)
			)
			(fill no)
			(layer "F.SilkS")
		)
		(fp_poly
			(pts
				(arc
					(start -1.260856 -0.1524)
					(mid -0.898049 -0.898049)
					(end -0.1524 -1.260856)
				)
				(arc
					(start -0.1524 -0.991616)
					(mid -0.709411 -0.709411)
					(end -0.991616 -0.1524)
				)
			)
			(stroke
				(width 0)
				(type default)
			)
			(fill yes)
			(layer "F.Paste")
		)
		(fp_poly
			(pts
				(arc
					(start -0.1524 1.260856)
					(mid -0.898049 0.898049)
					(end -1.260856 0.1524)
				)
				(arc
					(start -0.991616 0.1524)
					(mid -0.709411 0.709411)
					(end -0.1524 0.991616)
				)
			)
			(stroke
				(width 0)
				(type default)
			)
			(fill yes)
			(layer "F.Paste")
		)
		(fp_poly
			(pts
				(arc
					(start 0.1524 -1.260856)
					(mid 0.898049 -0.898049)
					(end 1.260856 -0.1524)
				)
				(arc
					(start 0.991616 -0.1524)
					(mid 0.709411 -0.709411)
					(end 0.1524 -0.991616)
				)
			)
			(stroke
				(width 0)
				(type default)
			)
			(fill yes)
			(layer "F.Paste")
		)
		(fp_poly
			(pts
				(arc
					(start 1.260856 0.1524)
					(mid 0.898049 0.898049)
					(end 0.1524 1.260856)
				)
				(arc
					(start 0.1524 0.991616)
					(mid 0.709411 0.709411)
					(end 0.991616 0.1524)
				)
			)
			(stroke
				(width 0)
				(type default)
			)
			(fill yes)
			(layer "F.Paste")
		)
		(fp_poly
			(pts
				(arc
					(start 6.35 0)
					(mid -6.35 0)
					(end 6.35 0)
				)
			)
			(stroke
				(width 0)
				(type default)
			)
			(fill no)
			(layer "B.CrtYd")
		)
		(fp_poly
			(pts
				(arc
					(start 1.778 0)
					(mid -1.778 0)
					(end 1.778 0)
				)
			)
			(stroke
				(width 0)
				(type default)
			)
			(fill no)
			(layer "F.CrtYd")
		)
		(fp_circle
			(center 0 0)
			(end 1.1684 0)
			(stroke
				(width 0.1)
				(type default)
			)
			(fill no)
			(layer "F.Fab")
		)
		(pad "1" thru_hole circle
			(at 0 0)
			(size 2.54 2.54)
			(drill 2.0066)
			(layers "*.Cu" "*.Mask")
			(remove_unused_layers no)
			(net "SG")
			(thermal_gap 0.0254)
			(padstack
				(mode front_inner_back)
				(layer "Inner"
					(shape circle)
					(size 2.54 2.54)
					(clearance 0.0254)
				)
				(layer "B.Cu"
					(shape circle)
					(size 2.54 2.54)
				)
			)
		)
	)
	(footprint ""
		(layer "F.Cu")
		(at 115.443 -72.263)
		(property "Reference" "R237"
			(at 3.429 0.16637 0)
			(unlocked yes)
			(layer "F.SilkS")
			(effects
				(font
					(size 0.7874 0.5842)
					(thickness 0.1524)
				)
			)
		)
		(property "Value" "VAL*"
			(at 0.02032 2.13233 0)
			(unlocked yes)
			(layer "F.Fab")
			(hide yes)
			(effects
				(font
					(size 0.7874 0.5842)
					(thickness 0.1524)
				)
			)
		)
		(property "Tolerance" "TOL*"
			(at 0.044704 3.05435 0)
			(unlocked yes)
			(layer "Cmts.User")
			(hide yes)
			(effects
				(font
					(size 0.7874 0.5842)
					(thickness 0.1524)
				)
			)
		)
		(property "User Part Number" "PARTNUM*"
			(at 0.02032 4.024884 0)
			(unlocked yes)
			(layer "Cmts.User")
			(hide yes)
			(effects
				(font
					(size 0.7874 0.5842)
					(thickness 0.1524)
				)
			)
		)
		(property "Device Type" "RESISTOR-G155-11002-01,10KOHM,A"
			(at 0.008382 1.210564 0)
			(unlocked yes)
			(layer "F.Fab")
			(hide yes)
			(effects
				(font
					(size 0.7874 0.5842)
					(thickness 0.1524)
				)
			)
		)
		(duplicate_pad_numbers_are_jumpers no)
		(fp_line
			(start -1.143 -0.5588)
			(end -1.143 0.5588)
			(stroke
				(width 0.1)
				(type default)
			)
			(layer "F.SilkS")
		)
		(fp_line
			(start -1.143 0.5588)
			(end 1.143 0.5588)
			(stroke
				(width 0.1)
				(type default)
			)
			(layer "F.SilkS")
		)
		(fp_line
			(start 1.143 -0.5588)
			(end -1.143 -0.5588)
			(stroke
				(width 0.1)
				(type default)
			)
			(layer "F.SilkS")
		)
		(fp_line
			(start 1.143 0.5588)
			(end 1.143 -0.5588)
			(stroke
				(width 0.1)
				(type default)
			)
			(layer "F.SilkS")
		)
		(fp_poly
			(pts
				(xy -1.143 0.5588) (xy 1.143 0.5588) (xy 1.143 -0.5588) (xy -1.143 -0.5588)
			)
			(stroke
				(width 0)
				(type default)
			)
			(fill no)
			(layer "F.CrtYd")
		)
		(fp_line
			(start -0.508 -0.3048)
			(end -0.508 0.3048)
			(stroke
				(width 0.1)
				(type default)
			)
			(layer "F.Fab")
		)
		(fp_line
			(start -0.508 0.3048)
			(end 0.508 0.3048)
			(stroke
				(width 0.1)
				(type default)
			)
			(layer "F.Fab")
		)
		(fp_line
			(start 0.508 -0.3048)
			(end -0.508 -0.3048)
			(stroke
				(width 0.1)
				(type default)
			)
			(layer "F.Fab")
		)
		(fp_line
			(start 0.508 0.3048)
			(end 0.508 -0.3048)
			(stroke
				(width 0.1)
				(type default)
			)
			(layer "F.Fab")
		)
		(pad "1" smd rect
			(at -0.5334 0)
			(size 0.7112 0.6096)
			(layers "F.Cu" "F.Mask" "F.Paste")
			(net "XP3R3V_FPGA_EN_R")
		)
		(pad "2" smd rect
			(at 0.5334 0)
			(size 0.7112 0.6096)
			(layers "F.Cu" "F.Mask" "F.Paste")
			(net "SG")
		)
		(zone
			(layer "F.Cu")
			(hatch none 0.5)
			(connect_pads
				(clearance 0)
			)
			(min_thickness 0.25)
			(keepout
				(tracks not_allowed)
				(vias allowed)
				(pads allowed)
				(copperpour not_allowed)
				(footprints allowed)
			)
			(placement
				(enabled no)
				(sheetname "")
			)
			(fill
				(thermal_gap 0.5)
				(thermal_bridge_width 0.5)
				(island_removal_mode 0)
			)
			(polygon
				(pts
					(xy 115.3668 -71.9582) (xy 115.5192 -71.9582) (xy 115.5192 -72.5678) (xy 115.3668 -72.5678)
				)
			)
		)
		(zone
			(layer "F.Cu")
			(hatch none 0.5)
			(connect_pads
				(clearance 0)
			)
			(min_thickness 0.25)
			(keepout
				(tracks allowed)
				(vias not_allowed)
				(pads allowed)
				(copperpour not_allowed)
				(footprints allowed)
			)
			(placement
				(enabled no)
				(sheetname "")
			)
			(fill
				(thermal_gap 0.5)
				(thermal_bridge_width 0.5)
				(island_removal_mode 0)
			)
			(polygon
				(pts
					(xy 115.3668 -71.9582) (xy 115.5192 -71.9582) (xy 115.5192 -72.5678) (xy 115.3668 -72.5678)
				)
			)
		)
	)
	(footprint ""
		(layer "F.Cu")
		(at 75.565 -14.590014)
		(property "Reference" "R57"
			(at 0.127 1.294384 0)
			(unlocked yes)
			(layer "F.SilkS")
			(effects
				(font
					(size 0.7874 0.5842)
					(thickness 0.1524)
				)
			)
		)
		(property "Value" "VAL*"
			(at 0.02032 2.13233 0)
			(unlocked yes)
			(layer "F.Fab")
			(hide yes)
			(effects
				(font
					(size 0.7874 0.5842)
					(thickness 0.1524)
				)
			)
		)
		(property "Tolerance" "TOL*"
			(at 0.044704 3.05435 0)
			(unlocked yes)
			(layer "Cmts.User")
			(hide yes)
			(effects
				(font
					(size 0.7874 0.5842)
					(thickness 0.1524)
				)
			)
		)
		(property "User Part Number" "PARTNUM*"
			(at 0.02032 4.024884 0)
			(unlocked yes)
			(layer "Cmts.User")
			(hide yes)
			(effects
				(font
					(size 0.7874 0.5842)
					(thickness 0.1524)
				)
			)
		)
		(property "Device Type" "RESISTOR-G155-133R0-01,33OHM,1%"
			(at 0.008382 1.210564 0)
			(unlocked yes)
			(layer "F.Fab")
			(hide yes)
			(effects
				(font
					(size 0.7874 0.5842)
					(thickness 0.1524)
				)
			)
		)
		(duplicate_pad_numbers_are_jumpers no)
		(fp_line
			(start -1.143 -0.5588)
			(end -1.143 0.5588)
			(stroke
				(width 0.1)
				(type default)
			)
			(layer "F.SilkS")
		)
		(fp_line
			(start -1.143 0.5588)
			(end 1.143 0.5588)
			(stroke
				(width 0.1)
				(type default)
			)
			(layer "F.SilkS")
		)
		(fp_line
			(start 1.143 -0.5588)
			(end -1.143 -0.5588)
			(stroke
				(width 0.1)
				(type default)
			)
			(layer "F.SilkS")
		)
		(fp_line
			(start 1.143 0.5588)
			(end 1.143 -0.5588)
			(stroke
				(width 0.1)
				(type default)
			)
			(layer "F.SilkS")
		)
		(fp_rect
			(start -1.143 0.5588)
			(end 1.143 -0.5588)
			(stroke
				(width 0)
				(type default)
			)
			(fill no)
			(layer "F.CrtYd")
		)
		(fp_line
			(start -0.508 -0.3048)
			(end -0.508 0.3048)
			(stroke
				(width 0.1)
				(type default)
			)
			(layer "F.Fab")
		)
		(fp_line
			(start -0.508 0.3048)
			(end 0.508 0.3048)
			(stroke
				(width 0.1)
				(type default)
			)
			(layer "F.Fab")
		)
		(fp_line
			(start 0.508 -0.3048)
			(end -0.508 -0.3048)
			(stroke
				(width 0.1)
				(type default)
			)
			(layer "F.Fab")
		)
		(fp_line
			(start 0.508 0.3048)
			(end 0.508 -0.3048)
			(stroke
				(width 0.1)
				(type default)
			)
			(layer "F.Fab")
		)
		(pad "1" smd rect
			(at -0.5334 0)
			(size 0.7112 0.6096)
			(layers "F.Cu" "F.Mask" "F.Paste")
			(net "BF_PCIE_PERST_N")
		)
		(pad "2" smd rect
			(at 0.5334 0)
			(size 0.7112 0.6096)
			(layers "F.Cu" "F.Mask" "F.Paste")
			(net "PCIE_PERST_N")
		)
		(zone
			(layer "F.Cu")
			(hatch none 0.5)
			(connect_pads
				(clearance 0)
			)
			(min_thickness 0.25)
			(keepout
				(tracks allowed)
				(vias not_allowed)
				(pads allowed)
				(copperpour not_allowed)
				(footprints allowed)
			)
			(placement
				(enabled no)
				(sheetname "")
			)
			(fill
				(thermal_gap 0.5)
				(thermal_bridge_width 0.5)
				(island_removal_mode 0)
			)
			(polygon
				(pts
					(xy 75.4888 -14.285214) (xy 75.6412 -14.285214) (xy 75.6412 -14.894814) (xy 75.4888 -14.894814)
				)
			)
		)
	)
	(footprint ""
		(layer "F.Cu")
		(at 90.7542 -106.6038)
		(property "Reference" "C76"
			(at 0.0508 -1.81483 0)
			(unlocked yes)
			(layer "F.SilkS")
			(effects
				(font
					(size 0.7874 0.5842)
					(thickness 0.1524)
				)
			)
		)
		(property "Value" "VAL*"
			(at 0.0762 2.067306 0)
			(unlocked yes)
			(layer "F.Fab")
			(hide yes)
			(effects
				(font
					(size 0.7874 0.5842)
					(thickness 0.1524)
				)
			)
		)
		(property "Tolerance" "TOL*"
			(at 0.0762 3.032506 0)
			(unlocked yes)
			(layer "Cmts.User")
			(hide yes)
			(effects
				(font
					(size 0.7874 0.5842)
					(thickness 0.1524)
				)
			)
		)
		(property "User Part Number" "PARTNUM*"
			(at 0.1016 4.023106 0)
			(unlocked yes)
			(layer "Cmts.User")
			(hide yes)
			(effects
				(font
					(size 0.7874 0.5842)
					(thickness 0.1524)
				)
			)
		)
		(property "Device Type" "CAPACITOR-G105-0B104-EK,0.1UF,A"
			(at 0.0508 1.127506 0)
			(unlocked yes)
			(layer "F.Fab")
			(hide yes)
			(effects
				(font
					(size 0.7874 0.5842)
					(thickness 0.1524)
				)
			)
		)
		(duplicate_pad_numbers_are_jumpers no)
		(fp_line
			(start -1.143 -0.5588)
			(end -1.143 0.5588)
			(stroke
				(width 0.1)
				(type default)
			)
			(layer "F.SilkS")
		)
		(fp_line
			(start -1.143 0.5588)
			(end 1.143 0.5588)
			(stroke
				(width 0.1)
				(type default)
			)
			(layer "F.SilkS")
		)
		(fp_line
			(start 1.143 -0.5588)
			(end -1.143 -0.5588)
			(stroke
				(width 0.1)
				(type default)
			)
			(layer "F.SilkS")
		)
		(fp_line
			(start 1.143 0.5588)
			(end 1.143 -0.5588)
			(stroke
				(width 0.1)
				(type default)
			)
			(layer "F.SilkS")
		)
		(fp_rect
			(start -1.143 0.5588)
			(end 1.143 -0.5588)
			(stroke
				(width 0)
				(type default)
			)
			(fill no)
			(layer "F.CrtYd")
		)
		(fp_line
			(start -0.508 -0.3048)
			(end -0.508 0.3048)
			(stroke
				(width 0.1)
				(type default)
			)
			(layer "F.Fab")
		)
		(fp_line
			(start -0.508 0.3048)
			(end 0.508 0.3048)
			(stroke
				(width 0.1)
				(type default)
			)
			(layer "F.Fab")
		)
		(fp_line
			(start 0.508 -0.3048)
			(end -0.508 -0.3048)
			(stroke
				(width 0.1)
				(type default)
			)
			(layer "F.Fab")
		)
		(fp_line
			(start 0.508 0.3048)
			(end 0.508 -0.3048)
			(stroke
				(width 0.1)
				(type default)
			)
			(layer "F.Fab")
		)
		(pad "1" smd rect
			(at -0.5334 0)
			(size 0.7112 0.6096)
			(layers "F.Cu" "F.Mask" "F.Paste")
			(net "XP12R0V")
		)
		(pad "2" smd rect
			(at 0.5334 0)
			(size 0.7112 0.6096)
			(layers "F.Cu" "F.Mask" "F.Paste")
			(net "SG")
		)
		(zone
			(layer "F.Cu")
			(hatch none 0.5)
			(connect_pads
				(clearance 0)
			)
			(min_thickness 0.25)
			(keepout
				(tracks allowed)
				(vias not_allowed)
				(pads allowed)
				(copperpour not_allowed)
				(footprints allowed)
			)
			(placement
				(enabled no)
				(sheetname "")
			)
			(fill
				(thermal_gap 0.5)
				(thermal_bridge_width 0.5)
				(island_removal_mode 0)
			)
			(polygon
				(pts
					(xy 90.678 -106.299) (xy 90.8304 -106.299) (xy 90.8304 -106.9086) (xy 90.678 -106.9086)
				)
			)
		)
	)
	(footprint ""
		(layer "F.Cu")
		(at 93.853 -65.278 -90)
		(property "Reference" "U34"
			(at -1.23063 -3.683 0)
			(unlocked yes)
			(layer "F.SilkS")
			(effects
				(font
					(size 0.7874 0.5842)
					(thickness 0.1524)
				)
			)
		)
		(property "Value" ""
			(at 0 0 270)
			(layer "F.Fab")
			(effects
				(font
					(size 1.27 1.27)
				)
			)
		)
		(property "Device Type" "TPS3808G18DBVR_SOT23_6-G222-00A"
			(at 0.1016 2.54127 270)
			(unlocked yes)
			(layer "F.Fab")
			(hide yes)
			(effects
				(font
					(size 0.7874 0.5842)
					(thickness 0.1524)
				)
			)
		)
		(property "User Part Number" "PARTNUM*"
			(at 0.1016 3.45567 270)
			(unlocked yes)
			(layer "Cmts.User")
			(hide yes)
			(effects
				(font
					(size 0.7874 0.5842)
					(thickness 0.1524)
				)
			)
		)
		(duplicate_pad_numbers_are_jumpers no)
		(fp_line
			(start -1.0541 1.704086)
			(end 1.0541 1.704086)
			(stroke
				(width 0.1)
				(type default)
			)
			(layer "F.SilkS")
		)
		(fp_line
			(start 1.0541 1.704086)
			(end 1.0541 1.45796)
			(stroke
				(width 0.1)
				(type default)
			)
			(layer "F.SilkS")
		)
		(fp_line
			(start -2.286 1.45796)
			(end -1.0541 1.45796)
			(stroke
				(width 0.1)
				(type default)
			)
			(layer "F.SilkS")
		)
		(fp_line
			(start -1.0541 1.45796)
			(end -1.0541 1.704086)
			(stroke
				(width 0.1)
				(type default)
			)
			(layer "F.SilkS")
		)
		(fp_line
			(start 1.0541 1.45796)
			(end 2.286 1.45796)
			(stroke
				(width 0.1)
				(type default)
			)
			(layer "F.SilkS")
		)
		(fp_line
			(start 2.286 1.45796)
			(end 2.286 -1.45796)
			(stroke
				(width 0.1)
				(type default)
			)
			(layer "F.SilkS")
		)
		(fp_line
			(start -2.286 -1.45796)
			(end -2.286 1.45796)
			(stroke
				(width 0.1)
				(type default)
			)
			(layer "F.SilkS")
		)
		(fp_line
			(start -1.0541 -1.45796)
			(end -2.286 -1.45796)
			(stroke
				(width 0.1)
				(type default)
			)
			(layer "F.SilkS")
		)
		(fp_line
			(start 1.0541 -1.45796)
			(end 1.0541 -1.704086)
			(stroke
				(width 0.1)
				(type default)
			)
			(layer "F.SilkS")
		)
		(fp_line
			(start 2.286 -1.45796)
			(end 1.0541 -1.45796)
			(stroke
				(width 0.1)
				(type default)
			)
			(layer "F.SilkS")
		)
		(fp_line
			(start -1.0541 -1.704086)
			(end -1.0541 -1.45796)
			(stroke
				(width 0.1)
				(type default)
			)
			(layer "F.SilkS")
		)
		(fp_line
			(start 1.0541 -1.704086)
			(end -1.0541 -1.704086)
			(stroke
				(width 0.1)
				(type default)
			)
			(layer "F.SilkS")
		)
		(fp_poly
			(pts
				(arc
					(start -2.286 -2.286)
					(mid -2.286 -1.524)
					(end -2.286 -2.286)
				)
			)
			(stroke
				(width 0)
				(type default)
			)
			(fill yes)
			(layer "F.SilkS")
		)
		(fp_poly
			(pts
				(xy -2.54 -1.9558) (xy 2.54 -1.9558) (xy 2.54 1.9558) (xy -2.54 1.9558)
			)
			(stroke
				(width 0)
				(type default)
			)
			(fill no)
			(layer "F.CrtYd")
		)
		(fp_line
			(start -0.8001 1.450086)
			(end 0.8001 1.450086)
			(stroke
				(width 0.1)
				(type default)
			)
			(layer "F.Fab")
		)
		(fp_line
			(start -0.8001 1.450086)
			(end -0.599948 1.249934)
			(stroke
				(width 0.1)
				(type default)
			)
			(layer "F.Fab")
		)
		(fp_line
			(start 0.8001 1.450086)
			(end 0.599948 1.249934)
			(stroke
				(width 0.1)
				(type default)
			)
			(layer "F.Fab")
		)
		(fp_line
			(start 0.8001 1.450086)
			(end 0.8001 1.199896)
			(stroke
				(width 0.1)
				(type default)
			)
			(layer "F.Fab")
		)
		(fp_line
			(start -0.599948 1.249934)
			(end -0.599948 -1.249934)
			(stroke
				(width 0.1)
				(type default)
			)
			(layer "F.Fab")
		)
		(fp_line
			(start 0.599948 1.249934)
			(end -0.599948 1.249934)
			(stroke
				(width 0.1)
				(type default)
			)
			(layer "F.Fab")
		)
		(fp_line
			(start -1.500124 1.199896)
			(end -1.500124 0.700024)
			(stroke
				(width 0.1)
				(type default)
			)
			(layer "F.Fab")
		)
		(fp_line
			(start -0.8001 1.199896)
			(end -0.8001 1.450086)
			(stroke
				(width 0.1)
				(type default)
			)
			(layer "F.Fab")
		)
		(fp_line
			(start -0.700024 1.199896)
			(end -1.500124 1.199896)
			(stroke
				(width 0.1)
				(type default)
			)
			(layer "F.Fab")
		)
		(fp_line
			(start 0.700024 1.199896)
			(end 0.700024 0.700024)
			(stroke
				(width 0.1)
				(type default)
			)
			(layer "F.Fab")
		)
		(fp_line
			(start 1.500124 1.199896)
			(end 0.700024 1.199896)
			(stroke
				(width 0.1)
				(type default)
			)
			(layer "F.Fab")
		)
		(fp_line
			(start -1.500124 0.700024)
			(end -0.700024 0.700024)
			(stroke
				(width 0.1)
				(type default)
			)
			(layer "F.Fab")
		)
		(fp_line
			(start -0.700024 0.700024)
			(end -0.700024 1.199896)
			(stroke
				(width 0.1)
				(type default)
			)
			(layer "F.Fab")
		)
		(fp_line
			(start 0.700024 0.700024)
			(end 1.500124 0.700024)
			(stroke
				(width 0.1)
				(type default)
			)
			(layer "F.Fab")
		)
		(fp_line
			(start 1.500124 0.700024)
			(end 1.500124 1.199896)
			(stroke
				(width 0.1)
				(type default)
			)
			(layer "F.Fab")
		)
		(fp_line
			(start -1.500124 0.249936)
			(end -1.500124 -0.249936)
			(stroke
				(width 0.1)
				(type default)
			)
			(layer "F.Fab")
		)
		(fp_line
			(start -0.8001 0.249936)
			(end -0.8001 0.700024)
			(stroke
				(width 0.1)
				(type default)
			)
			(layer "F.Fab")
		)
		(fp_line
			(start -0.700024 0.249936)
			(end -1.500124 0.249936)
			(stroke
				(width 0.1)
				(type default)
			)
			(layer "F.Fab")
		)
		(fp_line
			(start 0.700024 0.249936)
			(end 0.8001 0.249936)
			(stroke
				(width 0.1)
				(type default)
			)
			(layer "F.Fab")
		)
		(fp_line
			(start 0.700024 0.249936)
			(end 0.700024 -0.249936)
			(stroke
				(width 0.1)
				(type default)
			)
			(layer "F.Fab")
		)
		(fp_line
			(start 0.8001 0.249936)
			(end 0.8001 0.700024)
			(stroke
				(width 0.1)
				(type default)
			)
			(layer "F.Fab")
		)
		(fp_line
			(start 1.500124 0.249936)
			(end 0.700024 0.249936)
			(stroke
				(width 0.1)
				(type default)
			)
			(layer "F.Fab")
		)
		(fp_line
			(start -1.500124 -0.249936)
			(end -0.700024 -0.249936)
			(stroke
				(width 0.1)
				(type default)
			)
			(layer "F.Fab")
		)
		(fp_line
			(start -0.700024 -0.249936)
			(end -0.700024 0.249936)
			(stroke
				(width 0.1)
				(type default)
			)
			(layer "F.Fab")
		)
		(fp_line
			(start 0.700024 -0.249936)
			(end 0.700024 0.249936)
			(stroke
				(width 0.1)
				(type default)
			)
			(layer "F.Fab")
		)
		(fp_line
			(start 0.700024 -0.249936)
			(end 1.500124 -0.249936)
			(stroke
				(width 0.1)
				(type default)
			)
			(layer "F.Fab")
		)
		(fp_line
			(start 0.8001 -0.249936)
			(end 0.700024 -0.249936)
			(stroke
				(width 0.1)
				(type default)
			)
			(layer "F.Fab")
		)
		(fp_line
			(start 1.500124 -0.249936)
			(end 1.500124 0.249936)
			(stroke
				(width 0.1)
				(type default)
			)
			(layer "F.Fab")
		)
		(fp_line
			(start -1.500124 -0.700024)
			(end -1.500124 -1.199896)
			(stroke
				(width 0.1)
				(type default)
			)
			(layer "F.Fab")
		)
		(fp_line
			(start -0.8001 -0.700024)
			(end -0.8001 -0.249936)
			(stroke
				(width 0.1)
				(type default)
			)
			(layer "F.Fab")
		)
		(fp_line
			(start -0.700024 -0.700024)
			(end -1.500124 -0.700024)
			(stroke
				(width 0.1)
				(type default)
			)
			(layer "F.Fab")
		)
		(fp_line
			(start 0.700024 -0.700024)
			(end 0.700024 -1.199896)
			(stroke
				(width 0.1)
				(type default)
			)
			(layer "F.Fab")
		)
		(fp_line
			(start 0.8001 -0.700024)
			(end 0.8001 -0.249936)
			(stroke
				(width 0.1)
				(type default)
			)
			(layer "F.Fab")
		)
		(fp_line
			(start 1.500124 -0.700024)
			(end 0.700024 -0.700024)
			(stroke
				(width 0.1)
				(type default)
			)
			(layer "F.Fab")
		)
		(fp_line
			(start -1.500124 -1.199896)
			(end -0.700024 -1.199896)
			(stroke
				(width 0.1)
				(type default)
			)
			(layer "F.Fab")
		)
		(fp_line
			(start -0.8001 -1.199896)
			(end -0.8001 -1.450086)
			(stroke
				(width 0.1)
				(type default)
			)
			(layer "F.Fab")
		)
		(fp_line
			(start -0.700024 -1.199896)
			(end -0.700024 -0.700024)
			(stroke
				(width 0.1)
				(type default)
			)
			(layer "F.Fab")
		)
		(fp_line
			(start 0.700024 -1.199896)
			(end 1.500124 -1.199896)
			(stroke
				(width 0.1)
				(type default)
			)
			(layer "F.Fab")
		)
		(fp_line
			(start 1.500124 -1.199896)
			(end 1.500124 -0.700024)
			(stroke
				(width 0.1)
				(type default)
			)
			(layer "F.Fab")
		)
		(fp_line
			(start -0.599948 -1.249934)
			(end 0.599948 -1.249934)
			(stroke
				(width 0.1)
				(type default)
			)
			(layer "F.Fab")
		)
		(fp_line
			(start -0.599948 -1.249934)
			(end -0.8001 -1.450086)
			(stroke
				(width 0.1)
				(type default)
			)
			(layer "F.Fab")
		)
		(fp_line
			(start 0.599948 -1.249934)
			(end 0.599948 1.249934)
			(stroke
				(width 0.1)
				(type default)
			)
			(layer "F.Fab")
		)
		(fp_line
			(start 0.599948 -1.249934)
			(end 0.8001 -1.450086)
			(stroke
				(width 0.1)
				(type default)
			)
			(layer "F.Fab")
		)
		(fp_line
			(start -0.8001 -1.450086)
			(end 0.8001 -1.450086)
			(stroke
				(width 0.1)
				(type default)
			)
			(layer "F.Fab")
		)
		(fp_line
			(start 0.8001 -1.450086)
			(end 0.8001 -1.199896)
			(stroke
				(width 0.1)
				(type default)
			)
			(layer "F.Fab")
		)
		(fp_poly
			(pts
				(arc
					(start -0.350012 -1.100074)
					(mid -0.350012 -0.799846)
					(end -0.350012 -1.100074)
				)
			)
			(stroke
				(width 0)
				(type default)
			)
			(fill yes)
			(layer "F.Fab")
		)
		(fp_text user "3"
			(at -2.25425 2.032 0)
			(unlocked yes)
			(layer "F.SilkS")
			(effects
				(font
					(size 0.635 0.4064)
					(thickness 0.1524)
				)
			)
		)
		(fp_text user "4"
			(at 3.02895 1.524 0)
			(unlocked yes)
			(layer "F.SilkS")
			(effects
				(font
					(size 0.635 0.4064)
					(thickness 0.1524)
				)
			)
		)
		(fp_text user "6"
			(at 2.69875 -1.905 0)
			(unlocked yes)
			(layer "F.SilkS")
			(effects
				(font
					(size 0.635 0.4064)
					(thickness 0.1524)
				)
			)
		)
		(fp_text user "4"
			(at 2.07137 1.778 0)
			(unlocked yes)
			(layer "F.Fab")
			(effects
				(font
					(size 0.7874 0.5842)
					(thickness 0.1524)
				)
			)
		)
		(fp_text user "3"
			(at -2.37363 1.524 0)
			(unlocked yes)
			(layer "F.Fab")
			(effects
				(font
					(size 0.7874 0.5842)
					(thickness 0.1524)
				)
			)
		)
		(fp_text user "6"
			(at 2.19837 -1.651 0)
			(unlocked yes)
			(layer "F.Fab")
			(effects
				(font
					(size 0.7874 0.5842)
					(thickness 0.1524)
				)
			)
		)
		(pad "1" smd rect
			(at -1.4351 -0.94996)
			(size 0.508 1.1938)
			(layers "F.Cu" "F.Mask" "F.Paste")
			(net "FPGA_IN_RST_DLY_N")
		)
		(pad "2" smd rect
			(at -1.4351 0)
			(size 0.508 1.1938)
			(layers "F.Cu" "F.Mask" "F.Paste")
			(net "SG")
		)
		(pad "3" smd rect
			(at -1.4351 0.94996)
			(size 0.508 1.1938)
			(layers "F.Cu" "F.Mask" "F.Paste")
			(net "PCIE_PERST_N")
		)
		(pad "4" smd rect
			(at 1.4351 0.94996)
			(size 0.508 1.1938)
			(layers "F.Cu" "F.Mask" "F.Paste")
			(net "UNNAMED_3_RESISTOR_I151_2")
		)
		(pad "5" smd rect
			(at 1.4351 0)
			(size 0.508 1.1938)
			(layers "F.Cu" "F.Mask" "F.Paste")
			(net "XP3R3V_FPGA")
		)
		(pad "6" smd rect
			(at 1.4351 -0.94996)
			(size 0.508 1.1938)
			(layers "F.Cu" "F.Mask" "F.Paste")
			(net "XP3R3V_FPGA")
		)
	)
	(footprint ""
		(layer "F.Cu")
		(at 100.2538 -69.215)
		(property "Reference" "R181"
			(at 2.8702 -0.08763 0)
			(unlocked yes)
			(layer "F.SilkS")
			(effects
				(font
					(size 0.7874 0.5842)
					(thickness 0.1524)
				)
			)
		)
		(property "Value" "VAL*"
			(at 0.02032 2.13233 0)
			(unlocked yes)
			(layer "F.Fab")
			(hide yes)
			(effects
				(font
					(size 0.7874 0.5842)
					(thickness 0.1524)
				)
			)
		)
		(property "Tolerance" "TOL*"
			(at 0.044704 3.05435 0)
			(unlocked yes)
			(layer "Cmts.User")
			(hide yes)
			(effects
				(font
					(size 0.7874 0.5842)
					(thickness 0.1524)
				)
			)
		)
		(property "User Part Number" "PARTNUM*"
			(at 0.02032 4.024884 0)
			(unlocked yes)
			(layer "Cmts.User")
			(hide yes)
			(effects
				(font
					(size 0.7874 0.5842)
					(thickness 0.1524)
				)
			)
		)
		(property "Device Type" "RESISTOR-G155-100R0-J0,0OHM,-"
			(at 0.008382 1.210564 0)
			(unlocked yes)
			(layer "F.Fab")
			(hide yes)
			(effects
				(font
					(size 0.7874 0.5842)
					(thickness 0.1524)
				)
			)
		)
		(duplicate_pad_numbers_are_jumpers no)
		(fp_line
			(start -1.143 -0.5588)
			(end -1.143 0.5588)
			(stroke
				(width 0.1)
				(type default)
			)
			(layer "F.SilkS")
		)
		(fp_line
			(start -1.143 0.5588)
			(end 1.143 0.5588)
			(stroke
				(width 0.1)
				(type default)
			)
			(layer "F.SilkS")
		)
		(fp_line
			(start 1.143 -0.5588)
			(end -1.143 -0.5588)
			(stroke
				(width 0.1)
				(type default)
			)
			(layer "F.SilkS")
		)
		(fp_line
			(start 1.143 0.5588)
			(end 1.143 -0.5588)
			(stroke
				(width 0.1)
				(type default)
			)
			(layer "F.SilkS")
		)
		(fp_rect
			(start -1.143 -0.5588)
			(end 1.143 0.5588)
			(stroke
				(width 0)
				(type default)
			)
			(fill no)
			(layer "F.CrtYd")
		)
		(fp_line
			(start -0.508 -0.3048)
			(end -0.508 0.3048)
			(stroke
				(width 0.1)
				(type default)
			)
			(layer "F.Fab")
		)
		(fp_line
			(start -0.508 0.3048)
			(end 0.508 0.3048)
			(stroke
				(width 0.1)
				(type default)
			)
			(layer "F.Fab")
		)
		(fp_line
			(start 0.508 -0.3048)
			(end -0.508 -0.3048)
			(stroke
				(width 0.1)
				(type default)
			)
			(layer "F.Fab")
		)
		(fp_line
			(start 0.508 0.3048)
			(end 0.508 -0.3048)
			(stroke
				(width 0.1)
				(type default)
			)
			(layer "F.Fab")
		)
		(pad "1" smd rect
			(at -0.5334 0)
			(size 0.7112 0.6096)
			(layers "F.Cu" "F.Mask" "F.Paste")
			(net "XP1R2V_PG_R")
		)
		(pad "2" smd rect
			(at 0.5334 0)
			(size 0.7112 0.6096)
			(layers "F.Cu" "F.Mask" "F.Paste")
			(net "XP1R2V_FPGA_PG")
		)
		(zone
			(layer "F.Cu")
			(hatch none 0.5)
			(connect_pads
				(clearance 0)
			)
			(min_thickness 0.25)
			(keepout
				(tracks allowed)
				(vias not_allowed)
				(pads allowed)
				(copperpour not_allowed)
				(footprints allowed)
			)
			(placement
				(enabled no)
				(sheetname "")
			)
			(fill
				(thermal_gap 0.5)
				(thermal_bridge_width 0.5)
				(island_removal_mode 0)
			)
			(polygon
				(pts
					(xy 100.1776 -69.5198) (xy 100.1776 -68.9102) (xy 100.33 -68.9102) (xy 100.33 -69.5198)
				)
			)
		)
	)
	(footprint ""
		(layer "F.Cu")
		(at 85.1662 -101.9048 -90)
		(property "Reference" "U6"
			(at -0.3302 -2.88417 90)
			(unlocked yes)
			(layer "F.SilkS")
			(effects
				(font
					(size 0.7874 0.5842)
					(thickness 0.1524)
				)
			)
		)
		(property "Value" ""
			(at 0 0 270)
			(layer "F.Fab")
			(effects
				(font
					(size 1.27 1.27)
				)
			)
		)
		(property "Device Type" "TPS54824RNVR_VQFN18-G220-10657A"
			(at 0.33782 4.521454 270)
			(unlocked yes)
			(layer "F.Fab")
			(hide yes)
			(effects
				(font
					(size 0.7874 0.5842)
					(thickness 0.1524)
				)
			)
		)
		(property "User Part Number" "PARTNUM*"
			(at 0.33782 5.715254 270)
			(unlocked yes)
			(layer "Cmts.User")
			(hide yes)
			(effects
				(font
					(size 0.7874 0.5842)
					(thickness 0.1524)
				)
			)
		)
		(duplicate_pad_numbers_are_jumpers no)
		(fp_line
			(start -2.208784 2.200148)
			(end -2.208784 -2.208784)
			(stroke
				(width 0.1)
				(type default)
			)
			(layer "F.SilkS")
		)
		(fp_line
			(start 2.208784 2.200148)
			(end -2.208784 2.200148)
			(stroke
				(width 0.1)
				(type default)
			)
			(layer "F.SilkS")
		)
		(fp_line
			(start -2.208784 -2.208784)
			(end 2.208784 -2.208784)
			(stroke
				(width 0.1)
				(type default)
			)
			(layer "F.SilkS")
		)
		(fp_line
			(start 2.208784 -2.208784)
			(end 2.208784 2.200148)
			(stroke
				(width 0.1)
				(type default)
			)
			(layer "F.SilkS")
		)
		(fp_poly
			(pts
				(arc
					(start -3.084068 -1.50114)
					(mid -3.084068 -0.48514)
					(end -3.084068 -1.50114)
				)
			)
			(stroke
				(width 0)
				(type default)
			)
			(fill yes)
			(layer "F.SilkS")
		)
		(fp_rect
			(start 2.462784 2.454148)
			(end -2.462784 -2.462784)
			(stroke
				(width 0)
				(type default)
			)
			(fill no)
			(layer "F.CrtYd")
		)
		(fp_line
			(start -1.800098 1.800098)
			(end -1.800098 -1.800098)
			(stroke
				(width 0.1)
				(type default)
			)
			(layer "F.Fab")
		)
		(fp_line
			(start 1.800098 1.800098)
			(end -1.800098 1.800098)
			(stroke
				(width 0.1)
				(type default)
			)
			(layer "F.Fab")
		)
		(fp_line
			(start -1.800098 -1.800098)
			(end 1.800098 -1.800098)
			(stroke
				(width 0.1)
				(type default)
			)
			(layer "F.Fab")
		)
		(fp_line
			(start 1.800098 -1.800098)
			(end 1.800098 1.800098)
			(stroke
				(width 0.1)
				(type default)
			)
			(layer "F.Fab")
		)
		(fp_circle
			(center -2.468626 -1.148334)
			(end -2.468626 -1.656334)
			(stroke
				(width 0.1)
				(type default)
			)
			(fill no)
			(layer "F.Fab")
		)
		(fp_text user "8"
			(at 1.98755 2.9972 0)
			(unlocked yes)
			(layer "F.SilkS")
			(effects
				(font
					(size 0.635 0.4064)
					(thickness 0.1524)
				)
			)
		)
		(fp_text user "7"
			(at 0.71755 2.7432 0)
			(unlocked yes)
			(layer "F.SilkS")
			(effects
				(font
					(size 0.635 0.4064)
					(thickness 0.1524)
				)
			)
		)
		(fp_text user "5"
			(at -1.49225 2.6162 0)
			(unlocked yes)
			(layer "F.SilkS")
			(effects
				(font
					(size 0.635 0.4064)
					(thickness 0.1524)
				)
			)
		)
		(fp_text user "6"
			(at -0.34925 2.6162 0)
			(unlocked yes)
			(layer "F.SilkS")
			(effects
				(font
					(size 0.635 0.4064)
					(thickness 0.1524)
				)
			)
		)
		(fp_text user "12"
			(at 2.87655 -1.9558 0)
			(unlocked yes)
			(layer "F.SilkS")
			(effects
				(font
					(size 0.635 0.4064)
					(thickness 0.1524)
				)
			)
		)
		(fp_text user "18"
			(at -2.3622 -2.87655 90)
			(unlocked yes)
			(layer "F.SilkS")
			(effects
				(font
					(size 0.635 0.4064)
					(thickness 0.1524)
				)
			)
		)
		(fp_text user "13"
			(at 1.5748 -2.87655 90)
			(unlocked yes)
			(layer "F.SilkS")
			(effects
				(font
					(size 0.635 0.4064)
					(thickness 0.1524)
				)
			)
		)
		(fp_text user "6"
			(at -1.06553 2.3622 0)
			(unlocked yes)
			(layer "F.Fab")
			(effects
				(font
					(size 0.7874 0.5842)
					(thickness 0.1524)
				)
			)
		)
		(fp_text user "7"
			(at 1.09347 2.3622 0)
			(unlocked yes)
			(layer "F.Fab")
			(effects
				(font
					(size 0.7874 0.5842)
					(thickness 0.1524)
				)
			)
		)
		(fp_text user "5"
			(at -2.08153 2.1082 0)
			(unlocked yes)
			(layer "F.Fab")
			(effects
				(font
					(size 0.7874 0.5842)
					(thickness 0.1524)
				)
			)
		)
		(fp_text user "8"
			(at 2.36347 1.8542 0)
			(unlocked yes)
			(layer "F.Fab")
			(effects
				(font
					(size 0.7874 0.5842)
					(thickness 0.1524)
				)
			)
		)
		(fp_text user "12"
			(at 2.36347 -1.1938 0)
			(unlocked yes)
			(layer "F.Fab")
			(effects
				(font
					(size 0.7874 0.5842)
					(thickness 0.1524)
				)
			)
		)
		(fp_text user "18"
			(at -1.604264 -2.61747 0)
			(unlocked yes)
			(layer "F.Fab")
			(effects
				(font
					(size 0.7874 0.5842)
					(thickness 0.1524)
				)
			)
		)
		(fp_text user "13"
			(at 1.356868 -2.61747 0)
			(unlocked yes)
			(layer "F.Fab")
			(effects
				(font
					(size 0.7874 0.5842)
					(thickness 0.1524)
				)
			)
		)
		(pad "1" smd rect
			(at -1.649984 -0.94996 270)
			(size 0.6096 0.3048)
			(layers "F.Cu" "F.Mask" "F.Paste")
			(net "XP3R3V_BT")
		)
		(pad "2" smd rect
			(at -1.374902 -0.350012 270)
			(size 1.143 0.4064)
			(layers "F.Cu" "F.Mask" "F.Paste")
			(net "VIN_XP3R3")
		)
		(pad "3" smd rect
			(at -1.374902 0.299974 270)
			(size 1.143 0.3048)
			(layers "F.Cu" "F.Mask" "F.Paste")
			(net "SG")
		)
		(pad "4" smd rect
			(at -1.374902 0.849884 270)
			(size 1.143 0.3048)
			(layers "F.Cu" "F.Mask" "F.Paste")
			(net "SG")
		)
		(pad "5" smd rect
			(at -1.374902 1.400048 270)
			(size 1.143 0.3048)
			(layers "F.Cu" "F.Mask" "F.Paste")
			(net "SG")
		)
		(pad "6" smd rect
			(at -0.32512 0.599948 270)
			(size 0.2032 2.6924)
			(layers "F.Cu" "F.Mask" "F.Paste")
			(net "XP3R3V_SW")
		)
		(pad "7" smd rect
			(at 0.32512 0.599948 270)
			(size 0.2032 2.6924)
			(layers "F.Cu" "F.Mask" "F.Paste")
			(net "XP3R3V_SW")
		)
		(pad "8" smd rect
			(at 1.374902 1.400048 270)
			(size 1.143 0.3048)
			(layers "F.Cu" "F.Mask" "F.Paste")
			(net "SG")
		)
		(pad "9" smd rect
			(at 1.374902 0.849884 270)
			(size 1.143 0.3048)
			(layers "F.Cu" "F.Mask" "F.Paste")
			(net "SG")
		)
		(pad "10" smd rect
			(at 1.374902 0.299974 270)
			(size 1.143 0.3048)
			(layers "F.Cu" "F.Mask" "F.Paste")
			(net "SG")
		)
		(pad "11" smd rect
			(at 1.374902 -0.350012 270)
			(size 1.143 0.4064)
			(layers "F.Cu" "F.Mask" "F.Paste")
			(net "VIN_XP3R3")
		)
		(pad "12" smd rect
			(at 1.649984 -0.94996 270)
			(size 0.6096 0.3048)
			(layers "F.Cu" "F.Mask" "F.Paste")
			(net "XP3R3V_AGND")
		)
		(pad "13" smd rect
			(at 1.374902 -1.649984 270)
			(size 0.508 0.6096)
			(layers "F.Cu" "F.Mask" "F.Paste")
			(net "XP3R3V_RT")
		)
		(pad "14" smd rect
			(at 0.750062 -1.649984 270)
			(size 0.254 0.6096)
			(layers "F.Cu" "F.Mask" "F.Paste")
			(net "XP3R3V_FB_R_TO_AGND")
		)
		(pad "15" smd rect
			(at 0.249936 -1.649984 270)
			(size 0.254 0.6096)
			(layers "F.Cu" "F.Mask" "F.Paste")
			(net "XP3R3V_COMP")
		)
		(pad "16" smd rect
			(at -0.249936 -1.649984 270)
			(size 0.254 0.6096)
			(layers "F.Cu" "F.Mask" "F.Paste")
			(net "XP3R3V_SS")
		)
		(pad "17" smd rect
			(at -0.750062 -1.649984 270)
			(size 0.254 0.6096)
			(layers "F.Cu" "F.Mask" "F.Paste")
			(net "XP3R3V_EN")
		)
		(pad "18" smd rect
			(at -1.374902 -1.649984 270)
			(size 0.508 0.6096)
			(layers "F.Cu" "F.Mask" "F.Paste")
			(net "R_XP3R3V_PG")
		)
	)
	(footprint ""
		(layer "F.Cu")
		(at 105.8164 -70.9168 180)
		(property "Reference" "C237"
			(at -0.381 -3.59537 0)
			(unlocked yes)
			(layer "F.SilkS")
			(effects
				(font
					(size 0.7874 0.5842)
					(thickness 0.1524)
				)
			)
		)
		(property "Value" "VAL*"
			(at 0.0762 2.067306 180)
			(unlocked yes)
			(layer "F.Fab")
			(hide yes)
			(effects
				(font
					(size 0.7874 0.5842)
					(thickness 0.1524)
				)
			)
		)
		(property "Device Type" "CAPACITOR-G105-0B104-CK,0.1UF,A"
			(at 0.0508 1.127506 180)
			(unlocked yes)
			(layer "F.Fab")
			(hide yes)
			(effects
				(font
					(size 0.7874 0.5842)
					(thickness 0.1524)
				)
			)
		)
		(property "User Part Number" "PARTNUM*"
			(at 0.1016 4.023106 180)
			(unlocked yes)
			(layer "Cmts.User")
			(hide yes)
			(effects
				(font
					(size 0.7874 0.5842)
					(thickness 0.1524)
				)
			)
		)
		(property "Tolerance" "TOL*"
			(at 0.0762 3.032506 180)
			(unlocked yes)
			(layer "Cmts.User")
			(hide yes)
			(effects
				(font
					(size 0.7874 0.5842)
					(thickness 0.1524)
				)
			)
		)
		(duplicate_pad_numbers_are_jumpers no)
		(fp_line
			(start 1.143 0.5588)
			(end 1.143 -0.5588)
			(stroke
				(width 0.1)
				(type default)
			)
			(layer "F.SilkS")
		)
		(fp_line
			(start 1.143 -0.5588)
			(end -1.143 -0.5588)
			(stroke
				(width 0.1)
				(type default)
			)
			(layer "F.SilkS")
		)
		(fp_line
			(start -1.143 0.5588)
			(end 1.143 0.5588)
			(stroke
				(width 0.1)
				(type default)
			)
			(layer "F.SilkS")
		)
		(fp_line
			(start -1.143 -0.5588)
			(end -1.143 0.5588)
			(stroke
				(width 0.1)
				(type default)
			)
			(layer "F.SilkS")
		)
		(fp_rect
			(start -1.143 0.5588)
			(end 1.143 -0.5588)
			(stroke
				(width 0)
				(type default)
			)
			(fill no)
			(layer "F.CrtYd")
		)
		(fp_line
			(start 0.508 0.3048)
			(end 0.508 -0.3048)
			(stroke
				(width 0.1)
				(type default)
			)
			(layer "F.Fab")
		)
		(fp_line
			(start 0.508 -0.3048)
			(end -0.508 -0.3048)
			(stroke
				(width 0.1)
				(type default)
			)
			(layer "F.Fab")
		)
		(fp_line
			(start -0.508 0.3048)
			(end 0.508 0.3048)
			(stroke
				(width 0.1)
				(type default)
			)
			(layer "F.Fab")
		)
		(fp_line
			(start -0.508 -0.3048)
			(end -0.508 0.3048)
			(stroke
				(width 0.1)
				(type default)
			)
			(layer "F.Fab")
		)
		(pad "1" smd rect
			(at -0.5334 0 180)
			(size 0.7112 0.6096)
			(layers "F.Cu" "F.Mask" "F.Paste")
			(net "XP3R3V_FPGA")
		)
		(pad "2" smd rect
			(at 0.5334 0 180)
			(size 0.7112 0.6096)
			(layers "F.Cu" "F.Mask" "F.Paste")
			(net "SG")
		)
		(zone
			(layer "F.Cu")
			(hatch none 0.5)
			(connect_pads
				(clearance 0)
			)
			(min_thickness 0.25)
			(keepout
				(tracks allowed)
				(vias not_allowed)
				(pads allowed)
				(copperpour not_allowed)
				(footprints allowed)
			)
			(placement
				(enabled no)
				(sheetname "")
			)
			(fill
				(thermal_gap 0.5)
				(thermal_bridge_width 0.5)
				(island_removal_mode 0)
			)
			(polygon
				(pts
					(xy 105.8926 -71.2216) (xy 105.7402 -71.2216) (xy 105.7402 -70.612) (xy 105.8926 -70.612)
				)
			)
		)
	)
	(footprint ""
		(layer "F.Cu")
		(at 94.107 -61.087 -90)
		(property "Reference" "C250"
			(at 2.794 0.08763 90)
			(unlocked yes)
			(layer "F.SilkS")
			(effects
				(font
					(size 0.7874 0.5842)
					(thickness 0.1524)
				)
			)
		)
		(property "Value" "VAL*"
			(at 0.0762 2.067306 270)
			(unlocked yes)
			(layer "F.Fab")
			(hide yes)
			(effects
				(font
					(size 0.7874 0.5842)
					(thickness 0.1524)
				)
			)
		)
		(property "Tolerance" "TOL*"
			(at 0.0762 3.032506 270)
			(unlocked yes)
			(layer "Cmts.User")
			(hide yes)
			(effects
				(font
					(size 0.7874 0.5842)
					(thickness 0.1524)
				)
			)
		)
		(property "User Part Number" "PARTNUM*"
			(at 0.1016 4.023106 270)
			(unlocked yes)
			(layer "Cmts.User")
			(hide yes)
			(effects
				(font
					(size 0.7874 0.5842)
					(thickness 0.1524)
				)
			)
		)
		(property "Device Type" "CAPACITOR-G105-0B104-EK,0.1UF,A"
			(at 0.0508 1.127506 270)
			(unlocked yes)
			(layer "F.Fab")
			(hide yes)
			(effects
				(font
					(size 0.7874 0.5842)
					(thickness 0.1524)
				)
			)
		)
		(duplicate_pad_numbers_are_jumpers no)
		(fp_line
			(start -1.143 0.5588)
			(end 1.143 0.5588)
			(stroke
				(width 0.1)
				(type default)
			)
			(layer "F.SilkS")
		)
		(fp_line
			(start 1.143 0.5588)
			(end 1.143 -0.5588)
			(stroke
				(width 0.1)
				(type default)
			)
			(layer "F.SilkS")
		)
		(fp_line
			(start -1.143 -0.5588)
			(end -1.143 0.5588)
			(stroke
				(width 0.1)
				(type default)
			)
			(layer "F.SilkS")
		)
		(fp_line
			(start 1.143 -0.5588)
			(end -1.143 -0.5588)
			(stroke
				(width 0.1)
				(type default)
			)
			(layer "F.SilkS")
		)
		(fp_poly
			(pts
				(xy -1.143 0.5588) (xy 1.143 0.5588) (xy 1.143 -0.5588) (xy -1.143 -0.5588)
			)
			(stroke
				(width 0)
				(type default)
			)
			(fill no)
			(layer "F.CrtYd")
		)
		(fp_line
			(start -0.508 0.3048)
			(end 0.508 0.3048)
			(stroke
				(width 0.1)
				(type default)
			)
			(layer "F.Fab")
		)
		(fp_line
			(start 0.508 0.3048)
			(end 0.508 -0.3048)
			(stroke
				(width 0.1)
				(type default)
			)
			(layer "F.Fab")
		)
		(fp_line
			(start -0.508 -0.3048)
			(end -0.508 0.3048)
			(stroke
				(width 0.1)
				(type default)
			)
			(layer "F.Fab")
		)
		(fp_line
			(start 0.508 -0.3048)
			(end -0.508 -0.3048)
			(stroke
				(width 0.1)
				(type default)
			)
			(layer "F.Fab")
		)
		(pad "1" smd rect
			(at -0.5334 0 270)
			(size 0.7112 0.6096)
			(layers "F.Cu" "F.Mask" "F.Paste")
			(net "UNNAMED_3_RESISTOR_I151_2")
		)
		(pad "2" smd rect
			(at 0.5334 0 270)
			(size 0.7112 0.6096)
			(layers "F.Cu" "F.Mask" "F.Paste")
			(net "SG")
		)
		(zone
			(layer "F.Cu")
			(hatch none 0.5)
			(connect_pads
				(clearance 0)
			)
			(min_thickness 0.25)
			(keepout
				(tracks not_allowed)
				(vias allowed)
				(pads allowed)
				(copperpour not_allowed)
				(footprints allowed)
			)
			(placement
				(enabled no)
				(sheetname "")
			)
			(fill
				(thermal_gap 0.5)
				(thermal_bridge_width 0.5)
				(island_removal_mode 0)
			)
			(polygon
				(pts
					(xy 93.8022 -61.1632) (xy 93.8022 -61.0108) (xy 94.4118 -61.0108) (xy 94.4118 -61.1632)
				)
			)
		)
		(zone
			(layer "F.Cu")
			(hatch none 0.5)
			(connect_pads
				(clearance 0)
			)
			(min_thickness 0.25)
			(keepout
				(tracks allowed)
				(vias not_allowed)
				(pads allowed)
				(copperpour not_allowed)
				(footprints allowed)
			)
			(placement
				(enabled no)
				(sheetname "")
			)
			(fill
				(thermal_gap 0.5)
				(thermal_bridge_width 0.5)
				(island_removal_mode 0)
			)
			(polygon
				(pts
					(xy 93.8022 -61.1632) (xy 93.8022 -61.0108) (xy 94.4118 -61.0108) (xy 94.4118 -61.1632)
				)
			)
		)
	)
	(footprint ""
		(layer "F.Cu")
		(at 57.4294 -103.4034 90)
		(property "Reference" "C15"
			(at -0.0254 3.18897 90)
			(unlocked yes)
			(layer "F.SilkS")
			(effects
				(font
					(size 0.7874 0.5842)
					(thickness 0.1524)
				)
			)
		)
		(property "Value" "VAL*"
			(at 0.0762 3.134106 90)
			(unlocked yes)
			(layer "F.Fab")
			(hide yes)
			(effects
				(font
					(size 0.7874 0.5842)
					(thickness 0.1524)
				)
			)
		)
		(property "Device Type" "CAPACITOR-G107-0F226-CM,22UF,2A"
			(at 0.0508 2.194306 90)
			(unlocked yes)
			(layer "F.Fab")
			(hide yes)
			(effects
				(font
					(size 0.7874 0.5842)
					(thickness 0.1524)
				)
			)
		)
		(property "User Part Number" "PARTNUM*"
			(at 0.1016 5.013706 90)
			(unlocked yes)
			(layer "Cmts.User")
			(hide yes)
			(effects
				(font
					(size 0.7874 0.5842)
					(thickness 0.1524)
				)
			)
		)
		(property "Tolerance" "TOL*"
			(at 0.0762 4.048506 90)
			(unlocked yes)
			(layer "Cmts.User")
			(hide yes)
			(effects
				(font
					(size 0.7874 0.5842)
					(thickness 0.1524)
				)
			)
		)
		(duplicate_pad_numbers_are_jumpers no)
		(fp_line
			(start 1.5748 -0.9398)
			(end -1.5748 -0.9398)
			(stroke
				(width 0.1)
				(type default)
			)
			(layer "F.SilkS")
		)
		(fp_line
			(start -1.5748 -0.9398)
			(end -1.5748 0.9398)
			(stroke
				(width 0.1)
				(type default)
			)
			(layer "F.SilkS")
		)
		(fp_line
			(start 1.5748 0.9398)
			(end 1.5748 -0.9398)
			(stroke
				(width 0.1)
				(type default)
			)
			(layer "F.SilkS")
		)
		(fp_line
			(start -1.5748 0.9398)
			(end 1.5748 0.9398)
			(stroke
				(width 0.1)
				(type default)
			)
			(layer "F.SilkS")
		)
		(fp_rect
			(start 1.5748 0.9398)
			(end -1.5748 -0.9398)
			(stroke
				(width 0)
				(type default)
			)
			(fill no)
			(layer "F.CrtYd")
		)
		(fp_line
			(start 1.016 -0.635)
			(end -1.016 -0.635)
			(stroke
				(width 0.1)
				(type default)
			)
			(layer "F.Fab")
		)
		(fp_line
			(start -1.016 -0.635)
			(end -1.016 0.635)
			(stroke
				(width 0.1)
				(type default)
			)
			(layer "F.Fab")
		)
		(fp_line
			(start 1.016 0.635)
			(end 1.016 -0.635)
			(stroke
				(width 0.1)
				(type default)
			)
			(layer "F.Fab")
		)
		(fp_line
			(start -1.016 0.635)
			(end 1.016 0.635)
			(stroke
				(width 0.1)
				(type default)
			)
			(layer "F.Fab")
		)
		(pad "1" smd rect
			(at -0.8382 0 90)
			(size 0.9652 1.3716)
			(layers "F.Cu" "F.Mask" "F.Paste")
			(net "XP5R0V")
		)
		(pad "2" smd rect
			(at 0.8382 0 90)
			(size 0.9652 1.3716)
			(layers "F.Cu" "F.Mask" "F.Paste")
			(net "SG")
		)
		(zone
			(layer "F.Cu")
			(hatch none 0.5)
			(connect_pads
				(clearance 0)
			)
			(min_thickness 0.25)
			(keepout
				(tracks allowed)
				(vias not_allowed)
				(pads allowed)
				(copperpour not_allowed)
				(footprints allowed)
			)
			(placement
				(enabled no)
				(sheetname "")
			)
			(fill
				(thermal_gap 0.5)
				(thermal_bridge_width 0.5)
				(island_removal_mode 0)
			)
			(polygon
				(pts
					(xy 58.0644 -103.632) (xy 56.7944 -103.632) (xy 56.7944 -103.1748) (xy 58.0644 -103.1748)
				)
			)
		)
	)
	(footprint ""
		(layer "F.Cu")
		(at 144.653 -59.563 -90)
		(property "Reference" "C267"
			(at -3.048 2.11963 90)
			(unlocked yes)
			(layer "F.SilkS")
			(effects
				(font
					(size 0.7874 0.5842)
					(thickness 0.1524)
				)
			)
		)
		(property "Value" "VAL*"
			(at 0.193548 2.13614 270)
			(unlocked yes)
			(layer "F.Fab")
			(hide yes)
			(effects
				(font
					(size 0.7874 0.5842)
					(thickness 0.1524)
				)
			)
		)
		(property "Tolerance" "TOL*"
			(at 0.216154 3.1496 270)
			(unlocked yes)
			(layer "Cmts.User")
			(hide yes)
			(effects
				(font
					(size 0.7874 0.5842)
					(thickness 0.1524)
				)
			)
		)
		(property "Device Type" "CAPACITOR-G104-0B101-FK,100PF,A"
			(at 0.184404 1.180592 270)
			(unlocked yes)
			(layer "F.Fab")
			(hide yes)
			(effects
				(font
					(size 0.7874 0.5842)
					(thickness 0.1524)
				)
			)
		)
		(property "User Part Number" "PARTNUM*"
			(at 0.216154 4.185666 270)
			(unlocked yes)
			(layer "Cmts.User")
			(hide yes)
			(effects
				(font
					(size 0.7874 0.5842)
					(thickness 0.1524)
				)
			)
		)
		(duplicate_pad_numbers_are_jumpers no)
		(fp_line
			(start -0.671322 0.4445)
			(end -0.671322 -0.4445)
			(stroke
				(width 0.1)
				(type default)
			)
			(layer "F.SilkS")
		)
		(fp_line
			(start 0.671322 0.4445)
			(end -0.671322 0.4445)
			(stroke
				(width 0.1)
				(type default)
			)
			(layer "F.SilkS")
		)
		(fp_line
			(start -0.671322 -0.4445)
			(end 0.671322 -0.4445)
			(stroke
				(width 0.1)
				(type default)
			)
			(layer "F.SilkS")
		)
		(fp_line
			(start 0.671322 -0.4445)
			(end 0.671322 0.4445)
			(stroke
				(width 0.1)
				(type default)
			)
			(layer "F.SilkS")
		)
		(fp_rect
			(start 0.671322 0.4445)
			(end -0.671322 -0.4445)
			(stroke
				(width 0)
				(type default)
			)
			(fill no)
			(layer "F.CrtYd")
		)
		(fp_line
			(start -0.31496 0.1651)
			(end 0.31496 0.1651)
			(stroke
				(width 0.1)
				(type default)
			)
			(layer "F.Fab")
		)
		(fp_line
			(start 0.31496 0.1651)
			(end 0.31496 -0.1651)
			(stroke
				(width 0.1)
				(type default)
			)
			(layer "F.Fab")
		)
		(fp_line
			(start -0.31496 -0.1651)
			(end -0.31496 0.1651)
			(stroke
				(width 0.1)
				(type default)
			)
			(layer "F.Fab")
		)
		(fp_line
			(start 0.31496 -0.1651)
			(end -0.31496 -0.1651)
			(stroke
				(width 0.1)
				(type default)
			)
			(layer "F.Fab")
		)
		(pad "1" smd rect
			(at -0.264922 0 270)
			(size 0.3048 0.381)
			(layers "F.Cu" "F.Mask" "F.Paste")
			(net "UNNAMED_523_CAPACITOR_I28_1")
		)
		(pad "2" smd rect
			(at 0.264922 0 270)
			(size 0.3048 0.381)
			(layers "F.Cu" "F.Mask" "F.Paste")
			(net "XP1R0V_FB_R_TO_AGND")
		)
		(zone
			(layer "F.Cu")
			(hatch none 0.5)
			(connect_pads
				(clearance 0)
			)
			(min_thickness 0.25)
			(keepout
				(tracks allowed)
				(vias not_allowed)
				(pads allowed)
				(copperpour not_allowed)
				(footprints allowed)
			)
			(placement
				(enabled no)
				(sheetname "")
			)
			(fill
				(thermal_gap 0.5)
				(thermal_bridge_width 0.5)
				(island_removal_mode 0)
			)
			(polygon
				(pts
					(xy 144.4625 -59.450478) (xy 144.8435 -59.450478) (xy 144.8435 -59.675522) (xy 144.4625 -59.675522)
				)
			)
		)
	)
	(footprint ""
		(layer "F.Cu")
		(at 54.737 -125.349)
		(property "Reference" "SP56"
			(at 0 0 0)
			(layer "F.SilkS")
			(hide yes)
			(effects
				(font
					(size 1.27 1.27)
				)
			)
		)
		(property "Value" ""
			(at 0 0 0)
			(layer "F.Fab")
			(effects
				(font
					(size 1.27 1.27)
				)
			)
		)
		(duplicate_pad_numbers_are_jumpers no)
	)
	(footprint ""
		(layer "F.Cu")
		(at 53.594 -131.699)
		(property "Reference" "SP60"
			(at 0 0 0)
			(layer "F.SilkS")
			(hide yes)
			(effects
				(font
					(size 1.27 1.27)
				)
			)
		)
		(property "Value" ""
			(at 0 0 0)
			(layer "F.Fab")
			(effects
				(font
					(size 1.27 1.27)
				)
			)
		)
		(duplicate_pad_numbers_are_jumpers no)
	)
	(footprint ""
		(layer "F.Cu")
		(at 144.018 -20.1168 180)
		(property "Reference" "C230"
			(at -3.048 1.43383 0)
			(unlocked yes)
			(layer "F.SilkS")
			(effects
				(font
					(size 0.7874 0.5842)
					(thickness 0.1524)
				)
			)
		)
		(property "Value" "VAL*"
			(at 0.0762 2.067306 180)
			(unlocked yes)
			(layer "F.Fab")
			(hide yes)
			(effects
				(font
					(size 0.7874 0.5842)
					(thickness 0.1524)
				)
			)
		)
		(property "Tolerance" "TOL*"
			(at 0.0762 3.032506 180)
			(unlocked yes)
			(layer "Cmts.User")
			(hide yes)
			(effects
				(font
					(size 0.7874 0.5842)
					(thickness 0.1524)
				)
			)
		)
		(property "User Part Number" "PARTNUM*"
			(at 0.1016 4.023106 180)
			(unlocked yes)
			(layer "Cmts.User")
			(hide yes)
			(effects
				(font
					(size 0.7874 0.5842)
					(thickness 0.1524)
				)
			)
		)
		(property "Device Type" "CAPACITOR-G105-0B104-EK,0.1UF,A"
			(at 0.0508 1.127506 180)
			(unlocked yes)
			(layer "F.Fab")
			(hide yes)
			(effects
				(font
					(size 0.7874 0.5842)
					(thickness 0.1524)
				)
			)
		)
		(duplicate_pad_numbers_are_jumpers no)
		(fp_line
			(start 1.143 0.5588)
			(end 1.143 -0.5588)
			(stroke
				(width 0.1)
				(type default)
			)
			(layer "F.SilkS")
		)
		(fp_line
			(start 1.143 -0.5588)
			(end -1.143 -0.5588)
			(stroke
				(width 0.1)
				(type default)
			)
			(layer "F.SilkS")
		)
		(fp_line
			(start -1.143 0.5588)
			(end 1.143 0.5588)
			(stroke
				(width 0.1)
				(type default)
			)
			(layer "F.SilkS")
		)
		(fp_line
			(start -1.143 -0.5588)
			(end -1.143 0.5588)
			(stroke
				(width 0.1)
				(type default)
			)
			(layer "F.SilkS")
		)
		(fp_rect
			(start -1.143 0.5588)
			(end 1.143 -0.5588)
			(stroke
				(width 0)
				(type default)
			)
			(fill no)
			(layer "F.CrtYd")
		)
		(fp_line
			(start 0.508 0.3048)
			(end 0.508 -0.3048)
			(stroke
				(width 0.1)
				(type default)
			)
			(layer "F.Fab")
		)
		(fp_line
			(start 0.508 -0.3048)
			(end -0.508 -0.3048)
			(stroke
				(width 0.1)
				(type default)
			)
			(layer "F.Fab")
		)
		(fp_line
			(start -0.508 0.3048)
			(end 0.508 0.3048)
			(stroke
				(width 0.1)
				(type default)
			)
			(layer "F.Fab")
		)
		(fp_line
			(start -0.508 -0.3048)
			(end -0.508 0.3048)
			(stroke
				(width 0.1)
				(type default)
			)
			(layer "F.Fab")
		)
		(pad "1" smd rect
			(at -0.5334 0 180)
			(size 0.7112 0.6096)
			(layers "F.Cu" "F.Mask" "F.Paste")
			(net "UNNAMED_515_CAPACITOR_I130_1")
		)
		(pad "2" smd rect
			(at 0.5334 0 180)
			(size 0.7112 0.6096)
			(layers "F.Cu" "F.Mask" "F.Paste")
			(net "SG")
		)
		(zone
			(layer "F.Cu")
			(hatch none 0.5)
			(connect_pads
				(clearance 0)
			)
			(min_thickness 0.25)
			(keepout
				(tracks allowed)
				(vias not_allowed)
				(pads allowed)
				(copperpour not_allowed)
				(footprints allowed)
			)
			(placement
				(enabled no)
				(sheetname "")
			)
			(fill
				(thermal_gap 0.5)
				(thermal_bridge_width 0.5)
				(island_removal_mode 0)
			)
			(polygon
				(pts
					(xy 144.0942 -20.4216) (xy 143.9418 -20.4216) (xy 143.9418 -19.812) (xy 144.0942 -19.812)
				)
			)
		)
	)
	(footprint ""
		(layer "F.Cu")
		(at 18.669 -70.866 180)
		(property "Reference" "R73"
			(at -0.635 2.24663 0)
			(unlocked yes)
			(layer "F.SilkS")
			(effects
				(font
					(size 0.7874 0.5842)
					(thickness 0.1524)
				)
			)
		)
		(property "Value" "VAL*"
			(at 0.02032 2.13233 180)
			(unlocked yes)
			(layer "F.Fab")
			(hide yes)
			(effects
				(font
					(size 0.7874 0.5842)
					(thickness 0.1524)
				)
			)
		)
		(property "Tolerance" "TOL*"
			(at 0.044704 3.05435 180)
			(unlocked yes)
			(layer "Cmts.User")
			(hide yes)
			(effects
				(font
					(size 0.7874 0.5842)
					(thickness 0.1524)
				)
			)
		)
		(property "User Part Number" "PARTNUM*"
			(at 0.02032 4.024884 180)
			(unlocked yes)
			(layer "Cmts.User")
			(hide yes)
			(effects
				(font
					(size 0.7874 0.5842)
					(thickness 0.1524)
				)
			)
		)
		(property "Device Type" "RESISTOR-G155-133R0-01,33OHM,1%"
			(at 0.008382 1.210564 180)
			(unlocked yes)
			(layer "F.Fab")
			(hide yes)
			(effects
				(font
					(size 0.7874 0.5842)
					(thickness 0.1524)
				)
			)
		)
		(duplicate_pad_numbers_are_jumpers no)
		(fp_line
			(start 1.143 0.5588)
			(end 1.143 -0.5588)
			(stroke
				(width 0.1)
				(type default)
			)
			(layer "F.SilkS")
		)
		(fp_line
			(start 1.143 -0.5588)
			(end -1.143 -0.5588)
			(stroke
				(width 0.1)
				(type default)
			)
			(layer "F.SilkS")
		)
		(fp_line
			(start -1.143 0.5588)
			(end 1.143 0.5588)
			(stroke
				(width 0.1)
				(type default)
			)
			(layer "F.SilkS")
		)
		(fp_line
			(start -1.143 -0.5588)
			(end -1.143 0.5588)
			(stroke
				(width 0.1)
				(type default)
			)
			(layer "F.SilkS")
		)
		(fp_rect
			(start -1.143 0.5588)
			(end 1.143 -0.5588)
			(stroke
				(width 0)
				(type default)
			)
			(fill no)
			(layer "F.CrtYd")
		)
		(fp_line
			(start 0.508 0.3048)
			(end 0.508 -0.3048)
			(stroke
				(width 0.1)
				(type default)
			)
			(layer "F.Fab")
		)
		(fp_line
			(start 0.508 -0.3048)
			(end -0.508 -0.3048)
			(stroke
				(width 0.1)
				(type default)
			)
			(layer "F.Fab")
		)
		(fp_line
			(start -0.508 0.3048)
			(end 0.508 0.3048)
			(stroke
				(width 0.1)
				(type default)
			)
			(layer "F.Fab")
		)
		(fp_line
			(start -0.508 -0.3048)
			(end -0.508 0.3048)
			(stroke
				(width 0.1)
				(type default)
			)
			(layer "F.Fab")
		)
		(pad "1" smd rect
			(at -0.5334 0 180)
			(size 0.7112 0.6096)
			(layers "F.Cu" "F.Mask" "F.Paste")
			(net "BF_ICP10100_I2C_SCL")
		)
		(pad "2" smd rect
			(at 0.5334 0 180)
			(size 0.7112 0.6096)
			(layers "F.Cu" "F.Mask" "F.Paste")
			(net "R_ICP10100_I2C_SCL")
		)
		(zone
			(layer "F.Cu")
			(hatch none 0.5)
			(connect_pads
				(clearance 0)
			)
			(min_thickness 0.25)
			(keepout
				(tracks allowed)
				(vias not_allowed)
				(pads allowed)
				(copperpour not_allowed)
				(footprints allowed)
			)
			(placement
				(enabled no)
				(sheetname "")
			)
			(fill
				(thermal_gap 0.5)
				(thermal_bridge_width 0.5)
				(island_removal_mode 0)
			)
			(polygon
				(pts
					(xy 18.7452 -71.1708) (xy 18.5928 -71.1708) (xy 18.5928 -70.5612) (xy 18.7452 -70.5612)
				)
			)
		)
	)
	(footprint ""
		(layer "F.Cu")
		(at 46.228 -131.064)
		(property "Reference" "SP63"
			(at 0 0 0)
			(layer "F.SilkS")
			(hide yes)
			(effects
				(font
					(size 1.27 1.27)
				)
			)
		)
		(property "Value" ""
			(at 0 0 0)
			(layer "F.Fab")
			(effects
				(font
					(size 1.27 1.27)
				)
			)
		)
		(duplicate_pad_numbers_are_jumpers no)
	)
	(footprint ""
		(layer "F.Cu")
		(at 137.414 -46.101 90)
		(property "Reference" "C268"
			(at 3.302 -0.08763 90)
			(unlocked yes)
			(layer "F.SilkS")
			(effects
				(font
					(size 0.7874 0.5842)
					(thickness 0.1524)
				)
			)
		)
		(property "Value" "VAL*"
			(at 0.0762 2.067306 90)
			(unlocked yes)
			(layer "F.Fab")
			(hide yes)
			(effects
				(font
					(size 0.7874 0.5842)
					(thickness 0.1524)
				)
			)
		)
		(property "Device Type" "CAPACITOR-G105-0B104-CK,0.1UF,A"
			(at 0.0508 1.127506 90)
			(unlocked yes)
			(layer "F.Fab")
			(hide yes)
			(effects
				(font
					(size 0.7874 0.5842)
					(thickness 0.1524)
				)
			)
		)
		(property "User Part Number" "PARTNUM*"
			(at 0.1016 4.023106 90)
			(unlocked yes)
			(layer "Cmts.User")
			(hide yes)
			(effects
				(font
					(size 0.7874 0.5842)
					(thickness 0.1524)
				)
			)
		)
		(property "Tolerance" "TOL*"
			(at 0.0762 3.032506 90)
			(unlocked yes)
			(layer "Cmts.User")
			(hide yes)
			(effects
				(font
					(size 0.7874 0.5842)
					(thickness 0.1524)
				)
			)
		)
		(duplicate_pad_numbers_are_jumpers no)
		(fp_line
			(start 1.143 -0.5588)
			(end -1.143 -0.5588)
			(stroke
				(width 0.1)
				(type default)
			)
			(layer "F.SilkS")
		)
		(fp_line
			(start -1.143 -0.5588)
			(end -1.143 0.5588)
			(stroke
				(width 0.1)
				(type default)
			)
			(layer "F.SilkS")
		)
		(fp_line
			(start 1.143 0.5588)
			(end 1.143 -0.5588)
			(stroke
				(width 0.1)
				(type default)
			)
			(layer "F.SilkS")
		)
		(fp_line
			(start -1.143 0.5588)
			(end 1.143 0.5588)
			(stroke
				(width 0.1)
				(type default)
			)
			(layer "F.SilkS")
		)
		(fp_rect
			(start -1.143 -0.5588)
			(end 1.143 0.5588)
			(stroke
				(width 0)
				(type default)
			)
			(fill no)
			(layer "F.CrtYd")
		)
		(fp_line
			(start 0.508 -0.3048)
			(end -0.508 -0.3048)
			(stroke
				(width 0.1)
				(type default)
			)
			(layer "F.Fab")
		)
		(fp_line
			(start -0.508 -0.3048)
			(end -0.508 0.3048)
			(stroke
				(width 0.1)
				(type default)
			)
			(layer "F.Fab")
		)
		(fp_line
			(start 0.508 0.3048)
			(end 0.508 -0.3048)
			(stroke
				(width 0.1)
				(type default)
			)
			(layer "F.Fab")
		)
		(fp_line
			(start -0.508 0.3048)
			(end 0.508 0.3048)
			(stroke
				(width 0.1)
				(type default)
			)
			(layer "F.Fab")
		)
		(pad "1" smd rect
			(at -0.5334 0 90)
			(size 0.7112 0.6096)
			(layers "F.Cu" "F.Mask" "F.Paste")
			(net "XP1R0V_FPGA")
		)
		(pad "2" smd rect
			(at 0.5334 0 90)
			(size 0.7112 0.6096)
			(layers "F.Cu" "F.Mask" "F.Paste")
			(net "SG")
		)
		(zone
			(layer "F.Cu")
			(hatch none 0.5)
			(connect_pads
				(clearance 0)
			)
			(min_thickness 0.25)
			(keepout
				(tracks allowed)
				(vias not_allowed)
				(pads allowed)
				(copperpour not_allowed)
				(footprints allowed)
			)
			(placement
				(enabled no)
				(sheetname "")
			)
			(fill
				(thermal_gap 0.5)
				(thermal_bridge_width 0.5)
				(island_removal_mode 0)
			)
			(polygon
				(pts
					(xy 137.1092 -46.0248) (xy 137.7188 -46.0248) (xy 137.7188 -46.1772) (xy 137.1092 -46.1772)
				)
			)
		)
	)
	(footprint ""
		(layer "F.Cu")
		(at 67.555618 -23.734522)
		(property "Reference" "MAC_PIN7"
			(at -0.634238 2.580132 0)
			(unlocked yes)
			(layer "F.SilkS")
			(effects
				(font
					(size 0.7874 0.5842)
					(thickness 0.1524)
				)
			)
		)
		(property "Value" ""
			(at 0 0 0)
			(layer "F.Fab")
			(effects
				(font
					(size 1.27 1.27)
				)
			)
		)
		(property "Device Type" "NUT-A200-00029-FB"
			(at 0 2.632964 0)
			(unlocked yes)
			(layer "F.Fab")
			(hide yes)
			(effects
				(font
					(size 0.7874 0.5842)
					(thickness 0.1524)
				)
			)
		)
		(property "User Part Number" "PARTNUM*"
			(at 0 3.826764 0)
			(unlocked yes)
			(layer "Cmts.User")
			(hide yes)
			(effects
				(font
					(size 0.7874 0.5842)
					(thickness 0.1524)
				)
			)
		)
		(duplicate_pad_numbers_are_jumpers no)
		(fp_circle
			(center 0 0)
			(end 1.524 0)
			(stroke
				(width 0.1)
				(type default)
			)
			(fill no)
			(layer "F.SilkS")
		)
		(fp_poly
			(pts
				(arc
					(start -1.260856 -0.1524)
					(mid -0.898049 -0.898049)
					(end -0.1524 -1.260856)
				)
				(arc
					(start -0.1524 -0.991616)
					(mid -0.709411 -0.709411)
					(end -0.991616 -0.1524)
				)
			)
			(stroke
				(width 0)
				(type default)
			)
			(fill yes)
			(layer "F.Paste")
		)
		(fp_poly
			(pts
				(arc
					(start -0.1524 1.260856)
					(mid -0.898049 0.898049)
					(end -1.260856 0.1524)
				)
				(arc
					(start -0.991616 0.1524)
					(mid -0.709411 0.709411)
					(end -0.1524 0.991616)
				)
			)
			(stroke
				(width 0)
				(type default)
			)
			(fill yes)
			(layer "F.Paste")
		)
		(fp_poly
			(pts
				(arc
					(start 0.1524 -1.260856)
					(mid 0.898049 -0.898049)
					(end 1.260856 -0.1524)
				)
				(arc
					(start 0.991616 -0.1524)
					(mid 0.709411 -0.709411)
					(end 0.1524 -0.991616)
				)
			)
			(stroke
				(width 0)
				(type default)
			)
			(fill yes)
			(layer "F.Paste")
		)
		(fp_poly
			(pts
				(arc
					(start 1.260856 0.1524)
					(mid 0.898049 0.898049)
					(end 0.1524 1.260856)
				)
				(arc
					(start 0.1524 0.991616)
					(mid 0.709411 0.709411)
					(end 0.991616 0.1524)
				)
			)
			(stroke
				(width 0)
				(type default)
			)
			(fill yes)
			(layer "F.Paste")
		)
		(fp_poly
			(pts
				(arc
					(start 6.35 0)
					(mid -6.35 0)
					(end 6.35 0)
				)
			)
			(stroke
				(width 0)
				(type default)
			)
			(fill no)
			(layer "B.CrtYd")
		)
		(fp_poly
			(pts
				(arc
					(start 1.778 0)
					(mid -1.778 0)
					(end 1.778 0)
				)
			)
			(stroke
				(width 0)
				(type default)
			)
			(fill no)
			(layer "F.CrtYd")
		)
		(fp_circle
			(center 0 0)
			(end 1.1684 0)
			(stroke
				(width 0.1)
				(type default)
			)
			(fill no)
			(layer "F.Fab")
		)
		(pad "1" thru_hole circle
			(at 0 0)
			(size 2.54 2.54)
			(drill 2.0066)
			(layers "*.Cu" "*.Mask")
			(remove_unused_layers no)
			(net "R_MAC_UART_TX_FPGA_RX")
			(thermal_gap 0.0254)
			(padstack
				(mode front_inner_back)
				(layer "Inner"
					(shape circle)
					(size 2.54 2.54)
					(clearance 0.0254)
				)
				(layer "B.Cu"
					(shape circle)
					(size 2.54 2.54)
				)
			)
		)
	)
	(footprint ""
		(layer "F.Cu")
		(at 118.618 -90.297)
		(property "Reference" "TP15"
			(at -1.9812 1.30937 0)
			(unlocked yes)
			(layer "F.SilkS")
			(effects
				(font
					(size 0.7874 0.5842)
					(thickness 0.1524)
				)
				(justify left)
			)
		)
		(property "Value" ""
			(at 0 0 0)
			(layer "F.Fab")
			(effects
				(font
					(size 1.27 1.27)
				)
			)
		)
		(property "Device Type" "TP_PIONT-TP010CT020B030_PTH-TPA"
			(at -1.341882 0.996696 0)
			(unlocked yes)
			(layer "F.Fab")
			(hide yes)
			(effects
				(font
					(size 0.7874 0.5842)
					(thickness 0.000001)
				)
				(justify left)
			)
		)
		(duplicate_pad_numbers_are_jumpers no)
		(fp_poly
			(pts
				(arc
					(start 0.889 0)
					(mid -0.889 0)
					(end 0.889 0)
				)
			)
			(stroke
				(width 0)
				(type default)
			)
			(fill no)
			(layer "B.CrtYd")
		)
		(fp_poly
			(pts
				(arc
					(start 0.889 0)
					(mid -0.889 0)
					(end 0.889 0)
				)
			)
			(stroke
				(width 0)
				(type default)
			)
			(fill no)
			(layer "F.CrtYd")
		)
		(pad "1" thru_hole circle
			(at 0 0)
			(size 0.508 0.508)
			(drill 0.254)
			(layers "*.Cu" "*.Mask")
			(remove_unused_layers no)
			(net "GPS_RST_N")
			(clearance 0.1016)
			(padstack
				(mode front_inner_back)
				(layer "Inner"
					(shape circle)
					(size 0.508 0.508)
					(clearance 0.1016)
				)
				(layer "B.Cu"
					(shape circle)
					(size 0.762 0.762)
					(clearance -0.0254)
				)
			)
		)
	)
	(footprint ""
		(layer "F.Cu")
		(at 118.346982 -41.32326)
		(property "Reference" "TP141"
			(at 0 0 0)
			(layer "F.SilkS")
			(hide yes)
			(effects
				(font
					(size 1.27 1.27)
				)
			)
		)
		(property "Value" ""
			(at 0 0 0)
			(layer "F.Fab")
			(effects
				(font
					(size 1.27 1.27)
				)
			)
		)
		(property "Device Type" "TP_PIONT-TP010CT020B030_PTH-TPA"
			(at -1.341882 0.996696 0)
			(unlocked yes)
			(layer "F.Fab")
			(hide yes)
			(effects
				(font
					(size 0.7874 0.5842)
					(thickness 0.1524)
				)
				(justify left)
			)
		)
		(duplicate_pad_numbers_are_jumpers no)
		(fp_poly
			(pts
				(arc
					(start 0.889 0)
					(mid -0.889 0)
					(end 0.889 0)
				)
			)
			(stroke
				(width 0)
				(type default)
			)
			(fill no)
			(layer "B.CrtYd")
		)
		(fp_poly
			(pts
				(arc
					(start 0.889 0)
					(mid -0.889 0)
					(end 0.889 0)
				)
			)
			(stroke
				(width 0)
				(type default)
			)
			(fill no)
			(layer "F.CrtYd")
		)
		(pad "1" thru_hole circle
			(at 0 0)
			(size 0.508 0.508)
			(drill 0.254)
			(layers "*.Cu" "*.Mask")
			(remove_unused_layers no)
			(net "IO_L24N_34")
			(clearance 0.1016)
			(padstack
				(mode front_inner_back)
				(layer "Inner"
					(shape circle)
					(size 0.508 0.508)
					(clearance 0.1016)
				)
				(layer "B.Cu"
					(shape circle)
					(size 0.762 0.762)
					(clearance -0.0254)
				)
			)
		)
	)
	(footprint ""
		(layer "F.Cu")
		(at 52.9082 -74.9808 90)
		(property "Reference" "R408"
			(at -0.5588 4.53517 90)
			(unlocked yes)
			(layer "F.SilkS")
			(effects
				(font
					(size 0.7874 0.5842)
					(thickness 0.1524)
				)
			)
		)
		(property "Value" "VAL*"
			(at 0.02032 2.13233 90)
			(unlocked yes)
			(layer "F.Fab")
			(hide yes)
			(effects
				(font
					(size 0.7874 0.5842)
					(thickness 0.1524)
				)
			)
		)
		(property "Device Type" "RESISTOR-G155-14701-01,4.7KOHMA"
			(at 0.008382 1.210564 90)
			(unlocked yes)
			(layer "F.Fab")
			(hide yes)
			(effects
				(font
					(size 0.7874 0.5842)
					(thickness 0.1524)
				)
			)
		)
		(property "User Part Number" "PARTNUM*"
			(at 0.02032 4.024884 90)
			(unlocked yes)
			(layer "Cmts.User")
			(hide yes)
			(effects
				(font
					(size 0.7874 0.5842)
					(thickness 0.1524)
				)
			)
		)
		(property "Tolerance" "TOL*"
			(at 0.044704 3.05435 90)
			(unlocked yes)
			(layer "Cmts.User")
			(hide yes)
			(effects
				(font
					(size 0.7874 0.5842)
					(thickness 0.1524)
				)
			)
		)
		(duplicate_pad_numbers_are_jumpers no)
		(fp_line
			(start 1.143 -0.5588)
			(end -1.143 -0.5588)
			(stroke
				(width 0.1)
				(type default)
			)
			(layer "F.SilkS")
		)
		(fp_line
			(start -1.143 -0.5588)
			(end -1.143 0.5588)
			(stroke
				(width 0.1)
				(type default)
			)
			(layer "F.SilkS")
		)
		(fp_line
			(start 1.143 0.5588)
			(end 1.143 -0.5588)
			(stroke
				(width 0.1)
				(type default)
			)
			(layer "F.SilkS")
		)
		(fp_line
			(start -1.143 0.5588)
			(end 1.143 0.5588)
			(stroke
				(width 0.1)
				(type default)
			)
			(layer "F.SilkS")
		)
		(fp_rect
			(start -1.143 0.5588)
			(end 1.143 -0.5588)
			(stroke
				(width 0)
				(type default)
			)
			(fill no)
			(layer "F.CrtYd")
		)
		(fp_line
			(start 0.508 -0.3048)
			(end -0.508 -0.3048)
			(stroke
				(width 0.1)
				(type default)
			)
			(layer "F.Fab")
		)
		(fp_line
			(start -0.508 -0.3048)
			(end -0.508 0.3048)
			(stroke
				(width 0.1)
				(type default)
			)
			(layer "F.Fab")
		)
		(fp_line
			(start 0.508 0.3048)
			(end 0.508 -0.3048)
			(stroke
				(width 0.1)
				(type default)
			)
			(layer "F.Fab")
		)
		(fp_line
			(start -0.508 0.3048)
			(end 0.508 0.3048)
			(stroke
				(width 0.1)
				(type default)
			)
			(layer "F.Fab")
		)
		(pad "1" smd rect
			(at -0.5334 0 90)
			(size 0.7112 0.6096)
			(layers "F.Cu" "F.Mask" "F.Paste")
			(net "XP3R3V_FPGA")
		)
		(pad "2" smd rect
			(at 0.5334 0 90)
			(size 0.7112 0.6096)
			(layers "F.Cu" "F.Mask" "F.Paste")
			(net "UNNAMED_6_LM75BDPTSSOP8_I59_A2")
		)
		(zone
			(layer "F.Cu")
			(hatch none 0.5)
			(connect_pads
				(clearance 0)
			)
			(min_thickness 0.25)
			(keepout
				(tracks allowed)
				(vias not_allowed)
				(pads allowed)
				(copperpour not_allowed)
				(footprints allowed)
			)
			(placement
				(enabled no)
				(sheetname "")
			)
			(fill
				(thermal_gap 0.5)
				(thermal_bridge_width 0.5)
				(island_removal_mode 0)
			)
			(polygon
				(pts
					(xy 53.213 -74.9046) (xy 53.213 -75.057) (xy 52.6034 -75.057) (xy 52.6034 -74.9046)
				)
			)
		)
		(zone
			(layer "F.Cu")
			(hatch none 0.5)
			(connect_pads
				(clearance 0)
			)
			(min_thickness 0.25)
			(keepout
				(tracks not_allowed)
				(vias allowed)
				(pads allowed)
				(copperpour not_allowed)
				(footprints allowed)
			)
			(placement
				(enabled no)
				(sheetname "")
			)
			(fill
				(thermal_gap 0.5)
				(thermal_bridge_width 0.5)
				(island_removal_mode 0)
			)
			(polygon
				(pts
					(xy 53.213 -74.9046) (xy 53.213 -75.057) (xy 52.6034 -75.057) (xy 52.6034 -74.9046)
				)
			)
		)
	)
	(footprint ""
		(layer "F.Cu")
		(at 126.365 -37.719)
		(property "Reference" "TP135"
			(at 2.95275 2.2098 90)
			(unlocked yes)
			(layer "F.SilkS")
			(effects
				(font
					(size 0.635 0.4064)
					(thickness 0.1524)
				)
				(justify left)
			)
		)
		(property "Value" ""
			(at 0 0 0)
			(layer "F.Fab")
			(effects
				(font
					(size 1.27 1.27)
				)
			)
		)
		(property "Device Type" "TP_PIONT-TP010CT020B030_PTH-TPA"
			(at -1.341882 0.996696 0)
			(unlocked yes)
			(layer "F.Fab")
			(hide yes)
			(effects
				(font
					(size 0.7874 0.5842)
					(thickness 0.1524)
				)
				(justify left)
			)
		)
		(duplicate_pad_numbers_are_jumpers no)
		(fp_poly
			(pts
				(arc
					(start 0.889 0)
					(mid -0.889 0)
					(end 0.889 0)
				)
			)
			(stroke
				(width 0)
				(type default)
			)
			(fill no)
			(layer "B.CrtYd")
		)
		(fp_poly
			(pts
				(arc
					(start 0.889 0)
					(mid -0.889 0)
					(end 0.889 0)
				)
			)
			(stroke
				(width 0)
				(type default)
			)
			(fill no)
			(layer "F.CrtYd")
		)
		(pad "1" thru_hole circle
			(at 0 0)
			(size 0.508 0.508)
			(drill 0.254)
			(layers "*.Cu" "*.Mask")
			(remove_unused_layers no)
			(net "IO_L21N_34")
			(clearance 0.1016)
			(padstack
				(mode front_inner_back)
				(layer "Inner"
					(shape circle)
					(size 0.508 0.508)
					(clearance 0.1016)
				)
				(layer "B.Cu"
					(shape circle)
					(size 0.762 0.762)
					(clearance -0.0254)
				)
			)
		)
	)
	(footprint ""
		(layer "F.Cu")
		(at 66.4464 -16.637 180)
		(property "Reference" "R55"
			(at -0.9906 1.23063 0)
			(unlocked yes)
			(layer "F.SilkS")
			(effects
				(font
					(size 0.7874 0.5842)
					(thickness 0.1524)
				)
			)
		)
		(property "Value" "VAL*"
			(at 0.02032 2.13233 180)
			(unlocked yes)
			(layer "F.Fab")
			(hide yes)
			(effects
				(font
					(size 0.7874 0.5842)
					(thickness 0.1524)
				)
			)
		)
		(property "Tolerance" "TOL*"
			(at 0.044704 3.05435 180)
			(unlocked yes)
			(layer "Cmts.User")
			(hide yes)
			(effects
				(font
					(size 0.7874 0.5842)
					(thickness 0.1524)
				)
			)
		)
		(property "User Part Number" "PARTNUM*"
			(at 0.02032 4.024884 180)
			(unlocked yes)
			(layer "Cmts.User")
			(hide yes)
			(effects
				(font
					(size 0.7874 0.5842)
					(thickness 0.1524)
				)
			)
		)
		(property "Device Type" "RESISTOR-G155-14701-01,4.7KOHMA"
			(at 0.008382 1.210564 180)
			(unlocked yes)
			(layer "F.Fab")
			(hide yes)
			(effects
				(font
					(size 0.7874 0.5842)
					(thickness 0.1524)
				)
			)
		)
		(duplicate_pad_numbers_are_jumpers no)
		(fp_line
			(start 1.143 0.5588)
			(end 1.143 -0.5588)
			(stroke
				(width 0.1)
				(type default)
			)
			(layer "F.SilkS")
		)
		(fp_line
			(start 1.143 -0.5588)
			(end -1.143 -0.5588)
			(stroke
				(width 0.1)
				(type default)
			)
			(layer "F.SilkS")
		)
		(fp_line
			(start -1.143 0.5588)
			(end 1.143 0.5588)
			(stroke
				(width 0.1)
				(type default)
			)
			(layer "F.SilkS")
		)
		(fp_line
			(start -1.143 -0.5588)
			(end -1.143 0.5588)
			(stroke
				(width 0.1)
				(type default)
			)
			(layer "F.SilkS")
		)
		(fp_rect
			(start 1.143 -0.5588)
			(end -1.143 0.5588)
			(stroke
				(width 0)
				(type default)
			)
			(fill no)
			(layer "F.CrtYd")
		)
		(fp_line
			(start 0.508 0.3048)
			(end 0.508 -0.3048)
			(stroke
				(width 0.1)
				(type default)
			)
			(layer "F.Fab")
		)
		(fp_line
			(start 0.508 -0.3048)
			(end -0.508 -0.3048)
			(stroke
				(width 0.1)
				(type default)
			)
			(layer "F.Fab")
		)
		(fp_line
			(start -0.508 0.3048)
			(end 0.508 0.3048)
			(stroke
				(width 0.1)
				(type default)
			)
			(layer "F.Fab")
		)
		(fp_line
			(start -0.508 -0.3048)
			(end -0.508 0.3048)
			(stroke
				(width 0.1)
				(type default)
			)
			(layer "F.Fab")
		)
		(pad "1" smd rect
			(at -0.5334 0 180)
			(size 0.7112 0.6096)
			(layers "F.Cu" "F.Mask" "F.Paste")
			(net "PCIE_CONN_PERST_N")
		)
		(pad "2" smd rect
			(at 0.5334 0 180)
			(size 0.7112 0.6096)
			(layers "F.Cu" "F.Mask" "F.Paste")
			(net "SG")
		)
		(zone
			(layer "F.Cu")
			(hatch none 0.5)
			(connect_pads
				(clearance 0)
			)
			(min_thickness 0.25)
			(keepout
				(tracks allowed)
				(vias not_allowed)
				(pads allowed)
				(copperpour not_allowed)
				(footprints allowed)
			)
			(placement
				(enabled no)
				(sheetname "")
			)
			(fill
				(thermal_gap 0.5)
				(thermal_bridge_width 0.5)
				(island_removal_mode 0)
			)
			(polygon
				(pts
					(xy 66.3702 -16.3322) (xy 66.5226 -16.3322) (xy 66.5226 -16.9418) (xy 66.3702 -16.9418)
				)
			)
		)
	)
	(footprint ""
		(layer "F.Cu")
		(at 111.125 -98.171 180)
		(property "Reference" "R320"
			(at -3.302 3.38963 0)
			(unlocked yes)
			(layer "F.SilkS")
			(effects
				(font
					(size 0.7874 0.5842)
					(thickness 0.1524)
				)
			)
		)
		(property "Value" "VAL*"
			(at 0.02032 2.13233 180)
			(unlocked yes)
			(layer "F.Fab")
			(hide yes)
			(effects
				(font
					(size 0.7874 0.5842)
					(thickness 0.1524)
				)
			)
		)
		(property "Tolerance" "TOL*"
			(at 0.044704 3.05435 180)
			(unlocked yes)
			(layer "Cmts.User")
			(hide yes)
			(effects
				(font
					(size 0.7874 0.5842)
					(thickness 0.1524)
				)
			)
		)
		(property "User Part Number" "PARTNUM*"
			(at 0.02032 4.024884 180)
			(unlocked yes)
			(layer "Cmts.User")
			(hide yes)
			(effects
				(font
					(size 0.7874 0.5842)
					(thickness 0.1524)
				)
			)
		)
		(property "Device Type" "RESISTOR-G155-14701-01,4.7KOHMA"
			(at 0.008382 1.210564 180)
			(unlocked yes)
			(layer "F.Fab")
			(hide yes)
			(effects
				(font
					(size 0.7874 0.5842)
					(thickness 0.1524)
				)
			)
		)
		(duplicate_pad_numbers_are_jumpers no)
		(fp_line
			(start 1.143 0.5588)
			(end 1.143 -0.5588)
			(stroke
				(width 0.1)
				(type default)
			)
			(layer "F.SilkS")
		)
		(fp_line
			(start 1.143 -0.5588)
			(end -1.143 -0.5588)
			(stroke
				(width 0.1)
				(type default)
			)
			(layer "F.SilkS")
		)
		(fp_line
			(start -1.143 0.5588)
			(end 1.143 0.5588)
			(stroke
				(width 0.1)
				(type default)
			)
			(layer "F.SilkS")
		)
		(fp_line
			(start -1.143 -0.5588)
			(end -1.143 0.5588)
			(stroke
				(width 0.1)
				(type default)
			)
			(layer "F.SilkS")
		)
		(fp_poly
			(pts
				(xy -1.143 0.5588) (xy 1.143 0.5588) (xy 1.143 -0.5588) (xy -1.143 -0.5588)
			)
			(stroke
				(width 0)
				(type default)
			)
			(fill no)
			(layer "F.CrtYd")
		)
		(fp_line
			(start 0.508 0.3048)
			(end 0.508 -0.3048)
			(stroke
				(width 0.1)
				(type default)
			)
			(layer "F.Fab")
		)
		(fp_line
			(start 0.508 -0.3048)
			(end -0.508 -0.3048)
			(stroke
				(width 0.1)
				(type default)
			)
			(layer "F.Fab")
		)
		(fp_line
			(start -0.508 0.3048)
			(end 0.508 0.3048)
			(stroke
				(width 0.1)
				(type default)
			)
			(layer "F.Fab")
		)
		(fp_line
			(start -0.508 -0.3048)
			(end -0.508 0.3048)
			(stroke
				(width 0.1)
				(type default)
			)
			(layer "F.Fab")
		)
		(pad "1" smd rect
			(at -0.5334 0 180)
			(size 0.7112 0.6096)
			(layers "F.Cu" "F.Mask" "F.Paste")
			(net "XP3R3V_FPGA")
		)
		(pad "2" smd rect
			(at 0.5334 0 180)
			(size 0.7112 0.6096)
			(layers "F.Cu" "F.Mask" "F.Paste")
			(net "RGB_LED_SHUTDOWN_N")
		)
		(zone
			(layer "F.Cu")
			(hatch none 0.5)
			(connect_pads
				(clearance 0)
			)
			(min_thickness 0.25)
			(keepout
				(tracks allowed)
				(vias not_allowed)
				(pads allowed)
				(copperpour not_allowed)
				(footprints allowed)
			)
			(placement
				(enabled no)
				(sheetname "")
			)
			(fill
				(thermal_gap 0.5)
				(thermal_bridge_width 0.5)
				(island_removal_mode 0)
			)
			(polygon
				(pts
					(xy 111.2012 -98.4758) (xy 111.0488 -98.4758) (xy 111.0488 -97.8662) (xy 111.2012 -97.8662)
				)
			)
		)
		(zone
			(layer "F.Cu")
			(hatch none 0.5)
			(connect_pads
				(clearance 0)
			)
			(min_thickness 0.25)
			(keepout
				(tracks not_allowed)
				(vias allowed)
				(pads allowed)
				(copperpour not_allowed)
				(footprints allowed)
			)
			(placement
				(enabled no)
				(sheetname "")
			)
			(fill
				(thermal_gap 0.5)
				(thermal_bridge_width 0.5)
				(island_removal_mode 0)
			)
			(polygon
				(pts
					(xy 111.2012 -98.4758) (xy 111.0488 -98.4758) (xy 111.0488 -97.8662) (xy 111.2012 -97.8662)
				)
			)
		)
	)
	(footprint ""
		(layer "F.Cu")
		(at 150.749 -27.432)
		(property "Reference" "R407"
			(at -0.762 -2.11963 0)
			(unlocked yes)
			(layer "F.SilkS")
			(effects
				(font
					(size 0.7874 0.5842)
					(thickness 0.1524)
				)
			)
		)
		(property "Value" "VAL*"
			(at 0.02032 2.13233 0)
			(unlocked yes)
			(layer "F.Fab")
			(hide yes)
			(effects
				(font
					(size 0.7874 0.5842)
					(thickness 0.1524)
				)
			)
		)
		(property "Tolerance" "TOL*"
			(at 0.044704 3.05435 0)
			(unlocked yes)
			(layer "Cmts.User")
			(hide yes)
			(effects
				(font
					(size 0.7874 0.5842)
					(thickness 0.1524)
				)
			)
		)
		(property "User Part Number" "PARTNUM*"
			(at 0.02032 4.024884 0)
			(unlocked yes)
			(layer "Cmts.User")
			(hide yes)
			(effects
				(font
					(size 0.7874 0.5842)
					(thickness 0.1524)
				)
			)
		)
		(property "Device Type" "RESISTOR-G155-133R0-01,33OHM,1%"
			(at 0.008382 1.210564 0)
			(unlocked yes)
			(layer "F.Fab")
			(hide yes)
			(effects
				(font
					(size 0.7874 0.5842)
					(thickness 0.1524)
				)
			)
		)
		(duplicate_pad_numbers_are_jumpers no)
		(fp_line
			(start -1.143 -0.5588)
			(end -1.143 0.5588)
			(stroke
				(width 0.1)
				(type default)
			)
			(layer "F.SilkS")
		)
		(fp_line
			(start -1.143 0.5588)
			(end 1.143 0.5588)
			(stroke
				(width 0.1)
				(type default)
			)
			(layer "F.SilkS")
		)
		(fp_line
			(start 1.143 -0.5588)
			(end -1.143 -0.5588)
			(stroke
				(width 0.1)
				(type default)
			)
			(layer "F.SilkS")
		)
		(fp_line
			(start 1.143 0.5588)
			(end 1.143 -0.5588)
			(stroke
				(width 0.1)
				(type default)
			)
			(layer "F.SilkS")
		)
		(fp_rect
			(start -1.143 0.5588)
			(end 1.143 -0.5588)
			(stroke
				(width 0)
				(type default)
			)
			(fill no)
			(layer "F.CrtYd")
		)
		(fp_line
			(start -0.508 -0.3048)
			(end -0.508 0.3048)
			(stroke
				(width 0.1)
				(type default)
			)
			(layer "F.Fab")
		)
		(fp_line
			(start -0.508 0.3048)
			(end 0.508 0.3048)
			(stroke
				(width 0.1)
				(type default)
			)
			(layer "F.Fab")
		)
		(fp_line
			(start 0.508 -0.3048)
			(end -0.508 -0.3048)
			(stroke
				(width 0.1)
				(type default)
			)
			(layer "F.Fab")
		)
		(fp_line
			(start 0.508 0.3048)
			(end 0.508 -0.3048)
			(stroke
				(width 0.1)
				(type default)
			)
			(layer "F.Fab")
		)
		(pad "1" smd rect
			(at -0.5334 0)
			(size 0.7112 0.6096)
			(layers "F.Cu" "F.Mask" "F.Paste")
			(net "LM75B_I2C_SDA")
		)
		(pad "2" smd rect
			(at 0.5334 0)
			(size 0.7112 0.6096)
			(layers "F.Cu" "F.Mask" "F.Paste")
			(net "R_LM75B_3_I2C_SDA")
		)
		(zone
			(layer "F.Cu")
			(hatch none 0.5)
			(connect_pads
				(clearance 0)
			)
			(min_thickness 0.25)
			(keepout
				(tracks not_allowed)
				(vias allowed)
				(pads allowed)
				(copperpour not_allowed)
				(footprints allowed)
			)
			(placement
				(enabled no)
				(sheetname "")
			)
			(fill
				(thermal_gap 0.5)
				(thermal_bridge_width 0.5)
				(island_removal_mode 0)
			)
			(polygon
				(pts
					(xy 150.6728 -27.1272) (xy 150.8252 -27.1272) (xy 150.8252 -27.7368) (xy 150.6728 -27.7368)
				)
			)
		)
		(zone
			(layer "F.Cu")
			(hatch none 0.5)
			(connect_pads
				(clearance 0)
			)
			(min_thickness 0.25)
			(keepout
				(tracks allowed)
				(vias not_allowed)
				(pads allowed)
				(copperpour not_allowed)
				(footprints allowed)
			)
			(placement
				(enabled no)
				(sheetname "")
			)
			(fill
				(thermal_gap 0.5)
				(thermal_bridge_width 0.5)
				(island_removal_mode 0)
			)
			(polygon
				(pts
					(xy 150.6728 -27.1272) (xy 150.8252 -27.1272) (xy 150.8252 -27.7368) (xy 150.6728 -27.7368)
				)
			)
		)
	)
	(footprint ""
		(layer "F.Cu")
		(at 74.0918 -84.6328)
		(property "Reference" "R311"
			(at -0.1778 -3.33883 0)
			(unlocked yes)
			(layer "F.SilkS")
			(effects
				(font
					(size 0.7874 0.5842)
					(thickness 0.1524)
				)
			)
		)
		(property "Value" "VAL*"
			(at 0.02032 2.13233 0)
			(unlocked yes)
			(layer "F.Fab")
			(hide yes)
			(effects
				(font
					(size 0.7874 0.5842)
					(thickness 0.1524)
				)
			)
		)
		(property "Tolerance" "TOL*"
			(at 0.044704 3.05435 0)
			(unlocked yes)
			(layer "Cmts.User")
			(hide yes)
			(effects
				(font
					(size 0.7874 0.5842)
					(thickness 0.1524)
				)
			)
		)
		(property "User Part Number" "PARTNUM*"
			(at 0.02032 4.024884 0)
			(unlocked yes)
			(layer "Cmts.User")
			(hide yes)
			(effects
				(font
					(size 0.7874 0.5842)
					(thickness 0.1524)
				)
			)
		)
		(property "Device Type" "RESISTOR-G155-100R0-J0,0OHM,-"
			(at 0.008382 1.210564 0)
			(unlocked yes)
			(layer "F.Fab")
			(hide yes)
			(effects
				(font
					(size 0.7874 0.5842)
					(thickness 0.1524)
				)
			)
		)
		(duplicate_pad_numbers_are_jumpers no)
		(fp_line
			(start -1.143 -0.5588)
			(end -1.143 0.5588)
			(stroke
				(width 0.1)
				(type default)
			)
			(layer "F.SilkS")
		)
		(fp_line
			(start -1.143 0.5588)
			(end 1.143 0.5588)
			(stroke
				(width 0.1)
				(type default)
			)
			(layer "F.SilkS")
		)
		(fp_line
			(start 1.143 -0.5588)
			(end -1.143 -0.5588)
			(stroke
				(width 0.1)
				(type default)
			)
			(layer "F.SilkS")
		)
		(fp_line
			(start 1.143 0.5588)
			(end 1.143 -0.5588)
			(stroke
				(width 0.1)
				(type default)
			)
			(layer "F.SilkS")
		)
		(fp_poly
			(pts
				(xy -1.143 0.5588) (xy 1.143 0.5588) (xy 1.143 -0.5588) (xy -1.143 -0.5588)
			)
			(stroke
				(width 0)
				(type default)
			)
			(fill no)
			(layer "F.CrtYd")
		)
		(fp_line
			(start -0.508 -0.3048)
			(end -0.508 0.3048)
			(stroke
				(width 0.1)
				(type default)
			)
			(layer "F.Fab")
		)
		(fp_line
			(start -0.508 0.3048)
			(end 0.508 0.3048)
			(stroke
				(width 0.1)
				(type default)
			)
			(layer "F.Fab")
		)
		(fp_line
			(start 0.508 -0.3048)
			(end -0.508 -0.3048)
			(stroke
				(width 0.1)
				(type default)
			)
			(layer "F.Fab")
		)
		(fp_line
			(start 0.508 0.3048)
			(end 0.508 -0.3048)
			(stroke
				(width 0.1)
				(type default)
			)
			(layer "F.Fab")
		)
		(pad "1" smd rect
			(at -0.5334 0)
			(size 0.7112 0.6096)
			(layers "F.Cu" "F.Mask" "F.Paste")
			(net "RGB_LED_I2C_SCL")
		)
		(pad "2" smd rect
			(at 0.5334 0)
			(size 0.7112 0.6096)
			(layers "F.Cu" "F.Mask" "F.Paste")
			(net "R_PCA9546_I2C_SCL")
		)
		(zone
			(layer "F.Cu")
			(hatch none 0.5)
			(connect_pads
				(clearance 0)
			)
			(min_thickness 0.25)
			(keepout
				(tracks not_allowed)
				(vias allowed)
				(pads allowed)
				(copperpour not_allowed)
				(footprints allowed)
			)
			(placement
				(enabled no)
				(sheetname "")
			)
			(fill
				(thermal_gap 0.5)
				(thermal_bridge_width 0.5)
				(island_removal_mode 0)
			)
			(polygon
				(pts
					(xy 74.0156 -84.328) (xy 74.168 -84.328) (xy 74.168 -84.9376) (xy 74.0156 -84.9376)
				)
			)
		)
		(zone
			(layer "F.Cu")
			(hatch none 0.5)
			(connect_pads
				(clearance 0)
			)
			(min_thickness 0.25)
			(keepout
				(tracks allowed)
				(vias not_allowed)
				(pads allowed)
				(copperpour not_allowed)
				(footprints allowed)
			)
			(placement
				(enabled no)
				(sheetname "")
			)
			(fill
				(thermal_gap 0.5)
				(thermal_bridge_width 0.5)
				(island_removal_mode 0)
			)
			(polygon
				(pts
					(xy 74.0156 -84.328) (xy 74.168 -84.328) (xy 74.168 -84.9376) (xy 74.0156 -84.9376)
				)
			)
		)
	)
	(footprint ""
		(layer "F.Cu")
		(at 121.793 -23.495)
		(property "Reference" "TP12"
			(at -0.2032 -1.67005 0)
			(unlocked yes)
			(layer "F.SilkS")
			(effects
				(font
					(size 0.635 0.4064)
					(thickness 0.1524)
				)
				(justify left)
			)
		)
		(property "Value" ""
			(at 0 0 0)
			(layer "F.Fab")
			(effects
				(font
					(size 1.27 1.27)
				)
			)
		)
		(property "Device Type" "TP_PIONT-TP010CT020B030_PTH-TPA"
			(at -1.341882 0.996696 0)
			(unlocked yes)
			(layer "F.Fab")
			(hide yes)
			(effects
				(font
					(size 0.7874 0.5842)
					(thickness 0.000001)
				)
				(justify left)
			)
		)
		(duplicate_pad_numbers_are_jumpers no)
		(fp_poly
			(pts
				(arc
					(start 0.889 0)
					(mid -0.889 0)
					(end 0.889 0)
				)
			)
			(stroke
				(width 0)
				(type default)
			)
			(fill no)
			(layer "B.CrtYd")
		)
		(fp_poly
			(pts
				(arc
					(start 0.889 0)
					(mid -0.889 0)
					(end 0.889 0)
				)
			)
			(stroke
				(width 0)
				(type default)
			)
			(fill no)
			(layer "F.CrtYd")
		)
		(pad "1" thru_hole circle
			(at 0 0)
			(size 0.508 0.508)
			(drill 0.254)
			(layers "*.Cu" "*.Mask")
			(remove_unused_layers no)
			(net "MUX3_SEL")
			(clearance 0.1016)
			(padstack
				(mode front_inner_back)
				(layer "Inner"
					(shape circle)
					(size 0.508 0.508)
					(clearance 0.1016)
				)
				(layer "B.Cu"
					(shape circle)
					(size 0.762 0.762)
					(clearance -0.0254)
				)
			)
		)
	)
	(footprint ""
		(layer "F.Cu")
		(at 74.0664 -81.4324 180)
		(property "Reference" "C38"
			(at 0.5334 4.50723 0)
			(unlocked yes)
			(layer "F.SilkS")
			(effects
				(font
					(size 0.7874 0.5842)
					(thickness 0.1524)
				)
			)
		)
		(property "Value" "VAL*"
			(at 0.0762 2.067306 180)
			(unlocked yes)
			(layer "F.Fab")
			(hide yes)
			(effects
				(font
					(size 0.7874 0.5842)
					(thickness 0.1524)
				)
			)
		)
		(property "Tolerance" "TOL*"
			(at 0.0762 3.032506 180)
			(unlocked yes)
			(layer "Cmts.User")
			(hide yes)
			(effects
				(font
					(size 0.7874 0.5842)
					(thickness 0.1524)
				)
			)
		)
		(property "User Part Number" "PARTNUM*"
			(at 0.1016 4.023106 180)
			(unlocked yes)
			(layer "Cmts.User")
			(hide yes)
			(effects
				(font
					(size 0.7874 0.5842)
					(thickness 0.1524)
				)
			)
		)
		(property "Device Type" "CAPACITOR-G105-0B104-CK,0.1UF,A"
			(at 0.0508 1.127506 180)
			(unlocked yes)
			(layer "F.Fab")
			(hide yes)
			(effects
				(font
					(size 0.7874 0.5842)
					(thickness 0.1524)
				)
			)
		)
		(duplicate_pad_numbers_are_jumpers no)
		(fp_line
			(start 1.143 0.5588)
			(end 1.143 -0.5588)
			(stroke
				(width 0.1)
				(type default)
			)
			(layer "F.SilkS")
		)
		(fp_line
			(start 1.143 -0.5588)
			(end -1.143 -0.5588)
			(stroke
				(width 0.1)
				(type default)
			)
			(layer "F.SilkS")
		)
		(fp_line
			(start -1.143 0.5588)
			(end 1.143 0.5588)
			(stroke
				(width 0.1)
				(type default)
			)
			(layer "F.SilkS")
		)
		(fp_line
			(start -1.143 -0.5588)
			(end -1.143 0.5588)
			(stroke
				(width 0.1)
				(type default)
			)
			(layer "F.SilkS")
		)
		(fp_rect
			(start 1.143 0.5588)
			(end -1.143 -0.5588)
			(stroke
				(width 0)
				(type default)
			)
			(fill no)
			(layer "F.CrtYd")
		)
		(fp_line
			(start 0.508 0.3048)
			(end 0.508 -0.3048)
			(stroke
				(width 0.1)
				(type default)
			)
			(layer "F.Fab")
		)
		(fp_line
			(start 0.508 -0.3048)
			(end -0.508 -0.3048)
			(stroke
				(width 0.1)
				(type default)
			)
			(layer "F.Fab")
		)
		(fp_line
			(start -0.508 0.3048)
			(end 0.508 0.3048)
			(stroke
				(width 0.1)
				(type default)
			)
			(layer "F.Fab")
		)
		(fp_line
			(start -0.508 -0.3048)
			(end -0.508 0.3048)
			(stroke
				(width 0.1)
				(type default)
			)
			(layer "F.Fab")
		)
		(pad "1" smd rect
			(at -0.5334 0 180)
			(size 0.7112 0.6096)
			(layers "F.Cu" "F.Mask" "F.Paste")
			(net "VDD_PCA9546A")
		)
		(pad "2" smd rect
			(at 0.5334 0 180)
			(size 0.7112 0.6096)
			(layers "F.Cu" "F.Mask" "F.Paste")
			(net "SG")
		)
		(zone
			(layer "F.Cu")
			(hatch none 0.5)
			(connect_pads
				(clearance 0)
			)
			(min_thickness 0.25)
			(keepout
				(tracks allowed)
				(vias not_allowed)
				(pads allowed)
				(copperpour not_allowed)
				(footprints allowed)
			)
			(placement
				(enabled no)
				(sheetname "")
			)
			(fill
				(thermal_gap 0.5)
				(thermal_bridge_width 0.5)
				(island_removal_mode 0)
			)
			(polygon
				(pts
					(xy 73.9902 -81.7372) (xy 73.9902 -81.1276) (xy 74.1426 -81.1276) (xy 74.1426 -81.7372)
				)
			)
		)
	)
	(footprint ""
		(layer "F.Cu")
		(at 55.2704 -98.1964 -90)
		(property "Reference" "C12"
			(at -0.127 -3.59537 90)
			(unlocked yes)
			(layer "F.SilkS")
			(effects
				(font
					(size 0.7874 0.5842)
					(thickness 0.1524)
				)
			)
		)
		(property "Value" "VAL*"
			(at 0.0762 2.067306 270)
			(unlocked yes)
			(layer "F.Fab")
			(hide yes)
			(effects
				(font
					(size 0.7874 0.5842)
					(thickness 0.1524)
				)
			)
		)
		(property "Device Type" "CAPACITOR-G105-0B104-CK,0.1UF,A"
			(at 0.0508 1.127506 270)
			(unlocked yes)
			(layer "F.Fab")
			(hide yes)
			(effects
				(font
					(size 0.7874 0.5842)
					(thickness 0.1524)
				)
			)
		)
		(property "User Part Number" "PARTNUM*"
			(at 0.1016 4.023106 270)
			(unlocked yes)
			(layer "Cmts.User")
			(hide yes)
			(effects
				(font
					(size 0.7874 0.5842)
					(thickness 0.1524)
				)
			)
		)
		(property "Tolerance" "TOL*"
			(at 0.0762 3.032506 270)
			(unlocked yes)
			(layer "Cmts.User")
			(hide yes)
			(effects
				(font
					(size 0.7874 0.5842)
					(thickness 0.1524)
				)
			)
		)
		(duplicate_pad_numbers_are_jumpers no)
		(fp_line
			(start -1.143 0.5588)
			(end 1.143 0.5588)
			(stroke
				(width 0.1)
				(type default)
			)
			(layer "F.SilkS")
		)
		(fp_line
			(start 1.143 0.5588)
			(end 1.143 -0.5588)
			(stroke
				(width 0.1)
				(type default)
			)
			(layer "F.SilkS")
		)
		(fp_line
			(start -1.143 -0.5588)
			(end -1.143 0.5588)
			(stroke
				(width 0.1)
				(type default)
			)
			(layer "F.SilkS")
		)
		(fp_line
			(start 1.143 -0.5588)
			(end -1.143 -0.5588)
			(stroke
				(width 0.1)
				(type default)
			)
			(layer "F.SilkS")
		)
		(fp_rect
			(start -1.143 -0.5588)
			(end 1.143 0.5588)
			(stroke
				(width 0)
				(type default)
			)
			(fill no)
			(layer "F.CrtYd")
		)
		(fp_line
			(start -0.508 0.3048)
			(end 0.508 0.3048)
			(stroke
				(width 0.1)
				(type default)
			)
			(layer "F.Fab")
		)
		(fp_line
			(start 0.508 0.3048)
			(end 0.508 -0.3048)
			(stroke
				(width 0.1)
				(type default)
			)
			(layer "F.Fab")
		)
		(fp_line
			(start -0.508 -0.3048)
			(end -0.508 0.3048)
			(stroke
				(width 0.1)
				(type default)
			)
			(layer "F.Fab")
		)
		(fp_line
			(start 0.508 -0.3048)
			(end -0.508 -0.3048)
			(stroke
				(width 0.1)
				(type default)
			)
			(layer "F.Fab")
		)
		(pad "1" smd rect
			(at -0.5334 0 270)
			(size 0.7112 0.6096)
			(layers "F.Cu" "F.Mask" "F.Paste")
			(net "XP5R0V")
		)
		(pad "2" smd rect
			(at 0.5334 0 270)
			(size 0.7112 0.6096)
			(layers "F.Cu" "F.Mask" "F.Paste")
			(net "SG")
		)
		(zone
			(layer "F.Cu")
			(hatch none 0.5)
			(connect_pads
				(clearance 0)
			)
			(min_thickness 0.25)
			(keepout
				(tracks allowed)
				(vias not_allowed)
				(pads allowed)
				(copperpour not_allowed)
				(footprints allowed)
			)
			(placement
				(enabled no)
				(sheetname "")
			)
			(fill
				(thermal_gap 0.5)
				(thermal_bridge_width 0.5)
				(island_removal_mode 0)
			)
			(polygon
				(pts
					(xy 55.5752 -98.2726) (xy 54.9656 -98.2726) (xy 54.9656 -98.1202) (xy 55.5752 -98.1202)
				)
			)
		)
	)
	(footprint ""
		(layer "F.Cu")
		(at 124.841 -37.719)
		(property "Reference" "TP139"
			(at -2.00025 2.2098 90)
			(unlocked yes)
			(layer "F.SilkS")
			(effects
				(font
					(size 0.635 0.4064)
					(thickness 0.1524)
				)
				(justify left)
			)
		)
		(property "Value" ""
			(at 0 0 0)
			(layer "F.Fab")
			(effects
				(font
					(size 1.27 1.27)
				)
			)
		)
		(property "Device Type" "TP_PIONT-TP010CT020B030_PTH-TPA"
			(at -1.341882 0.996696 0)
			(unlocked yes)
			(layer "F.Fab")
			(hide yes)
			(effects
				(font
					(size 0.7874 0.5842)
					(thickness 0.1524)
				)
				(justify left)
			)
		)
		(duplicate_pad_numbers_are_jumpers no)
		(fp_poly
			(pts
				(arc
					(start 0.889 0)
					(mid -0.889 0)
					(end 0.889 0)
				)
			)
			(stroke
				(width 0)
				(type default)
			)
			(fill no)
			(layer "B.CrtYd")
		)
		(fp_poly
			(pts
				(arc
					(start 0.889 0)
					(mid -0.889 0)
					(end 0.889 0)
				)
			)
			(stroke
				(width 0)
				(type default)
			)
			(fill no)
			(layer "F.CrtYd")
		)
		(pad "1" thru_hole circle
			(at 0 0)
			(size 0.508 0.508)
			(drill 0.254)
			(layers "*.Cu" "*.Mask")
			(remove_unused_layers no)
			(net "IO_L23N_34")
			(clearance 0.1016)
			(padstack
				(mode front_inner_back)
				(layer "Inner"
					(shape circle)
					(size 0.508 0.508)
					(clearance 0.1016)
				)
				(layer "B.Cu"
					(shape circle)
					(size 0.762 0.762)
					(clearance -0.0254)
				)
			)
		)
	)
	(footprint ""
		(layer "F.Cu")
		(at 48.006 -131.445)
		(property "Reference" "SP62"
			(at 0 0 0)
			(layer "F.SilkS")
			(hide yes)
			(effects
				(font
					(size 1.27 1.27)
				)
			)
		)
		(property "Value" ""
			(at 0 0 0)
			(layer "F.Fab")
			(effects
				(font
					(size 1.27 1.27)
				)
			)
		)
		(duplicate_pad_numbers_are_jumpers no)
	)
	(footprint ""
		(layer "F.Cu")
		(at 74.0664 -82.7786)
		(property "Reference" "R310"
			(at -0.1524 -4.17703 0)
			(unlocked yes)
			(layer "F.SilkS")
			(effects
				(font
					(size 0.7874 0.5842)
					(thickness 0.1524)
				)
			)
		)
		(property "Value" "VAL*"
			(at 0.02032 2.13233 0)
			(unlocked yes)
			(layer "F.Fab")
			(hide yes)
			(effects
				(font
					(size 0.7874 0.5842)
					(thickness 0.1524)
				)
			)
		)
		(property "Tolerance" "TOL*"
			(at 0.044704 3.05435 0)
			(unlocked yes)
			(layer "Cmts.User")
			(hide yes)
			(effects
				(font
					(size 0.7874 0.5842)
					(thickness 0.1524)
				)
			)
		)
		(property "User Part Number" "PARTNUM*"
			(at 0.02032 4.024884 0)
			(unlocked yes)
			(layer "Cmts.User")
			(hide yes)
			(effects
				(font
					(size 0.7874 0.5842)
					(thickness 0.1524)
				)
			)
		)
		(property "Device Type" "RESISTOR-G155-100R0-J0,0OHM,-"
			(at 0.008382 1.210564 0)
			(unlocked yes)
			(layer "F.Fab")
			(hide yes)
			(effects
				(font
					(size 0.7874 0.5842)
					(thickness 0.1524)
				)
			)
		)
		(duplicate_pad_numbers_are_jumpers no)
		(fp_line
			(start -1.143 -0.5588)
			(end -1.143 0.5588)
			(stroke
				(width 0.1)
				(type default)
			)
			(layer "F.SilkS")
		)
		(fp_line
			(start -1.143 0.5588)
			(end 1.143 0.5588)
			(stroke
				(width 0.1)
				(type default)
			)
			(layer "F.SilkS")
		)
		(fp_line
			(start 1.143 -0.5588)
			(end -1.143 -0.5588)
			(stroke
				(width 0.1)
				(type default)
			)
			(layer "F.SilkS")
		)
		(fp_line
			(start 1.143 0.5588)
			(end 1.143 -0.5588)
			(stroke
				(width 0.1)
				(type default)
			)
			(layer "F.SilkS")
		)
		(fp_poly
			(pts
				(xy -1.143 0.5588) (xy 1.143 0.5588) (xy 1.143 -0.5588) (xy -1.143 -0.5588)
			)
			(stroke
				(width 0)
				(type default)
			)
			(fill no)
			(layer "F.CrtYd")
		)
		(fp_line
			(start -0.508 -0.3048)
			(end -0.508 0.3048)
			(stroke
				(width 0.1)
				(type default)
			)
			(layer "F.Fab")
		)
		(fp_line
			(start -0.508 0.3048)
			(end 0.508 0.3048)
			(stroke
				(width 0.1)
				(type default)
			)
			(layer "F.Fab")
		)
		(fp_line
			(start 0.508 -0.3048)
			(end -0.508 -0.3048)
			(stroke
				(width 0.1)
				(type default)
			)
			(layer "F.Fab")
		)
		(fp_line
			(start 0.508 0.3048)
			(end 0.508 -0.3048)
			(stroke
				(width 0.1)
				(type default)
			)
			(layer "F.Fab")
		)
		(pad "1" smd rect
			(at -0.5334 0)
			(size 0.7112 0.6096)
			(layers "F.Cu" "F.Mask" "F.Paste")
			(net "RGB_LED_I2C_SDA")
		)
		(pad "2" smd rect
			(at 0.5334 0)
			(size 0.7112 0.6096)
			(layers "F.Cu" "F.Mask" "F.Paste")
			(net "R_PCA9546_I2C_SDA")
		)
		(zone
			(layer "F.Cu")
			(hatch none 0.5)
			(connect_pads
				(clearance 0)
			)
			(min_thickness 0.25)
			(keepout
				(tracks not_allowed)
				(vias allowed)
				(pads allowed)
				(copperpour not_allowed)
				(footprints allowed)
			)
			(placement
				(enabled no)
				(sheetname "")
			)
			(fill
				(thermal_gap 0.5)
				(thermal_bridge_width 0.5)
				(island_removal_mode 0)
			)
			(polygon
				(pts
					(xy 73.9902 -82.4738) (xy 74.1426 -82.4738) (xy 74.1426 -83.0834) (xy 73.9902 -83.0834)
				)
			)
		)
		(zone
			(layer "F.Cu")
			(hatch none 0.5)
			(connect_pads
				(clearance 0)
			)
			(min_thickness 0.25)
			(keepout
				(tracks allowed)
				(vias not_allowed)
				(pads allowed)
				(copperpour not_allowed)
				(footprints allowed)
			)
			(placement
				(enabled no)
				(sheetname "")
			)
			(fill
				(thermal_gap 0.5)
				(thermal_bridge_width 0.5)
				(island_removal_mode 0)
			)
			(polygon
				(pts
					(xy 73.9902 -82.4738) (xy 74.1426 -82.4738) (xy 74.1426 -83.0834) (xy 73.9902 -83.0834)
				)
			)
		)
	)
	(footprint ""
		(layer "F.Cu")
		(at 145.8214 -89.3318)
		(property "Reference" "R5"
			(at -0.2794 7.96417 0)
			(unlocked yes)
			(layer "F.SilkS")
			(effects
				(font
					(size 0.7874 0.5842)
					(thickness 0.1524)
				)
			)
		)
		(property "Value" "VAL*"
			(at 0.02032 2.13233 0)
			(unlocked yes)
			(layer "F.Fab")
			(hide yes)
			(effects
				(font
					(size 0.7874 0.5842)
					(thickness 0.1524)
				)
			)
		)
		(property "Device Type" "RESISTOR-G155-11002-01,10KOHM,A"
			(at 0.008382 1.210564 0)
			(unlocked yes)
			(layer "F.Fab")
			(hide yes)
			(effects
				(font
					(size 0.7874 0.5842)
					(thickness 0.1524)
				)
			)
		)
		(property "User Part Number" "PARTNUM*"
			(at 0.02032 4.024884 0)
			(unlocked yes)
			(layer "Cmts.User")
			(hide yes)
			(effects
				(font
					(size 0.7874 0.5842)
					(thickness 0.1524)
				)
			)
		)
		(property "Tolerance" "TOL*"
			(at 0.044704 3.05435 0)
			(unlocked yes)
			(layer "Cmts.User")
			(hide yes)
			(effects
				(font
					(size 0.7874 0.5842)
					(thickness 0.1524)
				)
			)
		)
		(duplicate_pad_numbers_are_jumpers no)
		(fp_line
			(start -1.143 -0.5588)
			(end -1.143 0.5588)
			(stroke
				(width 0.1)
				(type default)
			)
			(layer "F.SilkS")
		)
		(fp_line
			(start -1.143 0.5588)
			(end 1.143 0.5588)
			(stroke
				(width 0.1)
				(type default)
			)
			(layer "F.SilkS")
		)
		(fp_line
			(start 1.143 -0.5588)
			(end -1.143 -0.5588)
			(stroke
				(width 0.1)
				(type default)
			)
			(layer "F.SilkS")
		)
		(fp_line
			(start 1.143 0.5588)
			(end 1.143 -0.5588)
			(stroke
				(width 0.1)
				(type default)
			)
			(layer "F.SilkS")
		)
		(fp_rect
			(start -1.143 -0.5588)
			(end 1.143 0.5588)
			(stroke
				(width 0)
				(type default)
			)
			(fill no)
			(layer "F.CrtYd")
		)
		(fp_line
			(start -0.508 -0.3048)
			(end -0.508 0.3048)
			(stroke
				(width 0.1)
				(type default)
			)
			(layer "F.Fab")
		)
		(fp_line
			(start -0.508 0.3048)
			(end 0.508 0.3048)
			(stroke
				(width 0.1)
				(type default)
			)
			(layer "F.Fab")
		)
		(fp_line
			(start 0.508 -0.3048)
			(end -0.508 -0.3048)
			(stroke
				(width 0.1)
				(type default)
			)
			(layer "F.Fab")
		)
		(fp_line
			(start 0.508 0.3048)
			(end 0.508 -0.3048)
			(stroke
				(width 0.1)
				(type default)
			)
			(layer "F.Fab")
		)
		(pad "1" smd rect
			(at -0.5334 0)
			(size 0.7112 0.6096)
			(layers "F.Cu" "F.Mask" "F.Paste")
			(net "XP12R0V_A_EN")
		)
		(pad "2" smd rect
			(at 0.5334 0)
			(size 0.7112 0.6096)
			(layers "F.Cu" "F.Mask" "F.Paste")
			(net "SG")
		)
		(zone
			(layer "F.Cu")
			(hatch none 0.5)
			(connect_pads
				(clearance 0)
			)
			(min_thickness 0.25)
			(keepout
				(tracks allowed)
				(vias not_allowed)
				(pads allowed)
				(copperpour not_allowed)
				(footprints allowed)
			)
			(placement
				(enabled no)
				(sheetname "")
			)
			(fill
				(thermal_gap 0.5)
				(thermal_bridge_width 0.5)
				(island_removal_mode 0)
			)
			(polygon
				(pts
					(xy 145.7452 -89.6366) (xy 145.7452 -89.027) (xy 145.8976 -89.027) (xy 145.8976 -89.6366)
				)
			)
		)
	)
	(footprint ""
		(layer "F.Cu")
		(at 125.984 -66.421 90)
		(property "Reference" "R166"
			(at 5.42163 0.127 0)
			(unlocked yes)
			(layer "F.SilkS")
			(effects
				(font
					(size 0.7874 0.5842)
					(thickness 0.1524)
				)
			)
		)
		(property "Value" "VAL*"
			(at 0.0508 2.245106 90)
			(unlocked yes)
			(layer "F.Fab")
			(hide yes)
			(effects
				(font
					(size 0.7874 0.5842)
					(thickness 0.1524)
				)
			)
		)
		(property "Tolerance" "TOL*"
			(at 0.0508 3.261106 90)
			(unlocked yes)
			(layer "Cmts.User")
			(hide yes)
			(effects
				(font
					(size 0.7874 0.5842)
					(thickness 0.1524)
				)
			)
		)
		(property "Device Type" "RESISTOR-G152-00055-01,1.13KOHA"
			(at 0.0762 1.254506 90)
			(unlocked yes)
			(layer "F.Fab")
			(hide yes)
			(effects
				(font
					(size 0.7874 0.5842)
					(thickness 0.1524)
				)
			)
		)
		(property "User Part Number" "PARTNUM*"
			(at 0.0762 4.302506 90)
			(unlocked yes)
			(layer "Cmts.User")
			(hide yes)
			(effects
				(font
					(size 0.7874 0.5842)
					(thickness 0.1524)
				)
			)
		)
		(duplicate_pad_numbers_are_jumpers no)
		(fp_line
			(start 1.143 -0.5588)
			(end -1.143 -0.5588)
			(stroke
				(width 0.1)
				(type default)
			)
			(layer "F.SilkS")
		)
		(fp_line
			(start -1.143 -0.5588)
			(end -1.143 0.5588)
			(stroke
				(width 0.1)
				(type default)
			)
			(layer "F.SilkS")
		)
		(fp_line
			(start 1.143 0.5588)
			(end 1.143 -0.5588)
			(stroke
				(width 0.1)
				(type default)
			)
			(layer "F.SilkS")
		)
		(fp_line
			(start -1.143 0.5588)
			(end 1.143 0.5588)
			(stroke
				(width 0.1)
				(type default)
			)
			(layer "F.SilkS")
		)
		(fp_rect
			(start 1.143 -0.5588)
			(end -1.143 0.5588)
			(stroke
				(width 0)
				(type default)
			)
			(fill no)
			(layer "F.CrtYd")
		)
		(fp_line
			(start 0.508 -0.3048)
			(end -0.508 -0.3048)
			(stroke
				(width 0.1)
				(type default)
			)
			(layer "F.Fab")
		)
		(fp_line
			(start -0.508 -0.3048)
			(end -0.508 0.3048)
			(stroke
				(width 0.1)
				(type default)
			)
			(layer "F.Fab")
		)
		(fp_line
			(start 0.508 0.3048)
			(end 0.508 -0.3048)
			(stroke
				(width 0.1)
				(type default)
			)
			(layer "F.Fab")
		)
		(fp_line
			(start -0.508 0.3048)
			(end 0.508 0.3048)
			(stroke
				(width 0.1)
				(type default)
			)
			(layer "F.Fab")
		)
		(pad "1" smd rect
			(at -0.5334 0 90)
			(size 0.7112 0.6096)
			(layers "F.Cu" "F.Mask" "F.Paste")
			(net "XP1R8V_VIN")
		)
		(pad "2" smd rect
			(at 0.5334 0 90)
			(size 0.7112 0.6096)
			(layers "F.Cu" "F.Mask" "F.Paste")
			(net "XP1R8V_EN_R")
		)
		(zone
			(layer "F.Cu")
			(hatch none 0.5)
			(connect_pads
				(clearance 0)
			)
			(min_thickness 0.25)
			(keepout
				(tracks allowed)
				(vias not_allowed)
				(pads allowed)
				(copperpour not_allowed)
				(footprints allowed)
			)
			(placement
				(enabled no)
				(sheetname "")
			)
			(fill
				(thermal_gap 0.5)
				(thermal_bridge_width 0.5)
				(island_removal_mode 0)
			)
			(polygon
				(pts
					(xy 125.6792 -66.4972) (xy 125.6792 -66.3448) (xy 126.2888 -66.3448) (xy 126.2888 -66.4972)
				)
			)
		)
	)
	(footprint ""
		(layer "F.Cu")
		(at 117.475 -98.044 180)
		(property "Reference" "L16"
			(at 1.0795 -1.43637 0)
			(unlocked yes)
			(layer "F.SilkS")
			(effects
				(font
					(size 0.7874 0.5842)
					(thickness 0.1524)
				)
				(justify left)
			)
		)
		(property "Value" "VAL*"
			(at -0.9398 3.70967 180)
			(unlocked yes)
			(layer "F.Fab")
			(hide yes)
			(effects
				(font
					(size 0.7874 0.5842)
					(thickness 0.1524)
				)
				(justify left)
			)
		)
		(property "Tolerance" "TOL*"
			(at -0.9906 5.00507 180)
			(unlocked yes)
			(layer "Cmts.User")
			(hide yes)
			(effects
				(font
					(size 0.7874 0.5842)
					(thickness 0.1524)
				)
				(justify left)
			)
		)
		(property "User Part Number" "PARTNUM*"
			(at -2.54 2.46507 180)
			(unlocked yes)
			(layer "Cmts.User")
			(hide yes)
			(effects
				(font
					(size 0.7874 0.5842)
					(thickness 0.1524)
				)
				(justify left)
			)
		)
		(property "Device Type" "FERRITEBEAD-G191-10100-01,120OA"
			(at -0.9906 1.22047 180)
			(unlocked yes)
			(layer "F.Fab")
			(hide yes)
			(effects
				(font
					(size 0.7874 0.5842)
					(thickness 0.1524)
				)
				(justify left)
			)
		)
		(duplicate_pad_numbers_are_jumpers no)
		(fp_line
			(start 1.3208 0.7112)
			(end -1.3208 0.7112)
			(stroke
				(width 0.1)
				(type default)
			)
			(layer "F.SilkS")
		)
		(fp_line
			(start 1.3208 -0.7112)
			(end 1.3208 0.7112)
			(stroke
				(width 0.1)
				(type default)
			)
			(layer "F.SilkS")
		)
		(fp_line
			(start -1.3208 0.7112)
			(end -1.3208 -0.7112)
			(stroke
				(width 0.1)
				(type default)
			)
			(layer "F.SilkS")
		)
		(fp_line
			(start -1.3208 -0.7112)
			(end 1.3208 -0.7112)
			(stroke
				(width 0.1)
				(type default)
			)
			(layer "F.SilkS")
		)
		(fp_rect
			(start -1.3208 0.7112)
			(end 1.3208 -0.7112)
			(stroke
				(width 0)
				(type default)
			)
			(fill no)
			(layer "F.CrtYd")
		)
		(fp_line
			(start 0.8128 0.4572)
			(end -0.8128 0.4572)
			(stroke
				(width 0.1)
				(type default)
			)
			(layer "F.Fab")
		)
		(fp_line
			(start 0.8128 -0.4572)
			(end 0.8128 0.4572)
			(stroke
				(width 0.1)
				(type default)
			)
			(layer "F.Fab")
		)
		(fp_line
			(start -0.8128 0.4572)
			(end -0.8128 -0.4572)
			(stroke
				(width 0.1)
				(type default)
			)
			(layer "F.Fab")
		)
		(fp_line
			(start -0.8128 -0.4572)
			(end 0.8128 -0.4572)
			(stroke
				(width 0.1)
				(type default)
			)
			(layer "F.Fab")
		)
		(pad "1" smd rect
			(at -0.6858 0 180)
			(size 0.762 0.8636)
			(layers "F.Cu" "F.Mask" "F.Paste")
			(net "XP3R3V_GPS")
		)
		(pad "2" smd rect
			(at 0.6858 0 180)
			(size 0.762 0.8636)
			(layers "F.Cu" "F.Mask" "F.Paste")
			(net "XP3R3V_FPGA")
		)
		(zone
			(layer "F.Cu")
			(hatch none 0.5)
			(connect_pads
				(clearance 0)
			)
			(min_thickness 0.25)
			(keepout
				(tracks allowed)
				(vias not_allowed)
				(pads allowed)
				(copperpour not_allowed)
				(footprints allowed)
			)
			(placement
				(enabled no)
				(sheetname "")
			)
			(fill
				(thermal_gap 0.5)
				(thermal_bridge_width 0.5)
				(island_removal_mode 0)
			)
			(polygon
				(pts
					(xy 117.6274 -98.5012) (xy 117.3226 -98.5012) (xy 117.3226 -97.5868) (xy 117.6274 -97.5868)
				)
			)
		)
		(zone
			(layer "F.Cu")
			(hatch none 0.5)
			(connect_pads
				(clearance 0)
			)
			(min_thickness 0.25)
			(keepout
				(tracks not_allowed)
				(vias allowed)
				(pads allowed)
				(copperpour not_allowed)
				(footprints allowed)
			)
			(placement
				(enabled no)
				(sheetname "")
			)
			(fill
				(thermal_gap 0.5)
				(thermal_bridge_width 0.5)
				(island_removal_mode 0)
			)
			(polygon
				(pts
					(xy 117.6274 -98.5012) (xy 117.3226 -98.5012) (xy 117.3226 -97.5868) (xy 117.6274 -97.5868)
				)
			)
		)
	)
	(footprint ""
		(layer "F.Cu")
		(at 111.633 -61.976 -90)
		(property "Reference" "R213"
			(at -3.302 -0.42037 90)
			(unlocked yes)
			(layer "F.SilkS")
			(effects
				(font
					(size 0.7874 0.5842)
					(thickness 0.1524)
				)
			)
		)
		(property "Value" "VAL*"
			(at 0.02032 2.13233 270)
			(unlocked yes)
			(layer "F.Fab")
			(hide yes)
			(effects
				(font
					(size 0.7874 0.5842)
					(thickness 0.1524)
				)
			)
		)
		(property "Device Type" "RESISTOR-G155-11002-01,10KOHM,A"
			(at 0.008382 1.210564 270)
			(unlocked yes)
			(layer "F.Fab")
			(hide yes)
			(effects
				(font
					(size 0.7874 0.5842)
					(thickness 0.1524)
				)
			)
		)
		(property "User Part Number" "PARTNUM*"
			(at 0.02032 4.024884 270)
			(unlocked yes)
			(layer "Cmts.User")
			(hide yes)
			(effects
				(font
					(size 0.7874 0.5842)
					(thickness 0.1524)
				)
			)
		)
		(property "Tolerance" "TOL*"
			(at 0.044704 3.05435 270)
			(unlocked yes)
			(layer "Cmts.User")
			(hide yes)
			(effects
				(font
					(size 0.7874 0.5842)
					(thickness 0.1524)
				)
			)
		)
		(duplicate_pad_numbers_are_jumpers no)
		(fp_line
			(start -1.143 0.5588)
			(end 1.143 0.5588)
			(stroke
				(width 0.1)
				(type default)
			)
			(layer "F.SilkS")
		)
		(fp_line
			(start 1.143 0.5588)
			(end 1.143 -0.5588)
			(stroke
				(width 0.1)
				(type default)
			)
			(layer "F.SilkS")
		)
		(fp_line
			(start -1.143 -0.5588)
			(end -1.143 0.5588)
			(stroke
				(width 0.1)
				(type default)
			)
			(layer "F.SilkS")
		)
		(fp_line
			(start 1.143 -0.5588)
			(end -1.143 -0.5588)
			(stroke
				(width 0.1)
				(type default)
			)
			(layer "F.SilkS")
		)
		(fp_rect
			(start 1.143 0.5588)
			(end -1.143 -0.5588)
			(stroke
				(width 0)
				(type default)
			)
			(fill no)
			(layer "F.CrtYd")
		)
		(fp_line
			(start -0.508 0.3048)
			(end 0.508 0.3048)
			(stroke
				(width 0.1)
				(type default)
			)
			(layer "F.Fab")
		)
		(fp_line
			(start 0.508 0.3048)
			(end 0.508 -0.3048)
			(stroke
				(width 0.1)
				(type default)
			)
			(layer "F.Fab")
		)
		(fp_line
			(start -0.508 -0.3048)
			(end -0.508 0.3048)
			(stroke
				(width 0.1)
				(type default)
			)
			(layer "F.Fab")
		)
		(fp_line
			(start 0.508 -0.3048)
			(end -0.508 -0.3048)
			(stroke
				(width 0.1)
				(type default)
			)
			(layer "F.Fab")
		)
		(pad "1" smd rect
			(at -0.5334 0 270)
			(size 0.7112 0.6096)
			(layers "F.Cu" "F.Mask" "F.Paste")
			(net "XP3R3V_FPGA")
		)
		(pad "2" smd rect
			(at 0.5334 0 270)
			(size 0.7112 0.6096)
			(layers "F.Cu" "F.Mask" "F.Paste")
			(net "FPGA_BRD_REV2")
		)
		(zone
			(layer "F.Cu")
			(hatch none 0.5)
			(connect_pads
				(clearance 0)
			)
			(min_thickness 0.25)
			(keepout
				(tracks allowed)
				(vias not_allowed)
				(pads allowed)
				(copperpour not_allowed)
				(footprints allowed)
			)
			(placement
				(enabled no)
				(sheetname "")
			)
			(fill
				(thermal_gap 0.5)
				(thermal_bridge_width 0.5)
				(island_removal_mode 0)
			)
			(polygon
				(pts
					(xy 111.3282 -61.8998) (xy 111.9378 -61.8998) (xy 111.9378 -62.0522) (xy 111.3282 -62.0522)
				)
			)
		)
	)
	(footprint ""
		(layer "F.Cu")
		(at 24.13 -74.041 90)
		(property "Reference" "TP10"
			(at 0 0 90)
			(layer "F.SilkS")
			(hide yes)
			(effects
				(font
					(size 1.27 1.27)
				)
			)
		)
		(property "Value" ""
			(at 0 0 90)
			(layer "F.Fab")
			(effects
				(font
					(size 1.27 1.27)
				)
			)
		)
		(property "Device Type" "TP_PIONT-TP010CT020B030_PTH-TPA"
			(at -1.341882 0.996696 90)
			(unlocked yes)
			(layer "F.Fab")
			(hide yes)
			(effects
				(font
					(size 0.7874 0.5842)
					(thickness 0.1524)
				)
				(justify left)
			)
		)
		(duplicate_pad_numbers_are_jumpers no)
		(fp_poly
			(pts
				(arc
					(start 0 0.889)
					(mid 0 -0.889)
					(end 0 0.889)
				)
			)
			(stroke
				(width 0)
				(type default)
			)
			(fill no)
			(layer "B.CrtYd")
		)
		(fp_poly
			(pts
				(arc
					(start 0 0.889)
					(mid 0 -0.889)
					(end 0 0.889)
				)
			)
			(stroke
				(width 0)
				(type default)
			)
			(fill no)
			(layer "F.CrtYd")
		)
		(pad "1" thru_hole circle
			(at 0 0 90)
			(size 0.508 0.508)
			(drill 0.254)
			(layers "*.Cu" "*.Mask")
			(remove_unused_layers no)
			(net "UNNAMED_524_FT4232HLREELQFP64_5")
			(clearance 0.1016)
			(padstack
				(mode front_inner_back)
				(layer "Inner"
					(shape circle)
					(size 0.508 0.508)
					(clearance 0.1016)
				)
				(layer "B.Cu"
					(shape circle)
					(size 0.762 0.762)
					(clearance -0.0254)
				)
			)
		)
	)
	(footprint ""
		(layer "F.Cu")
		(at 105.8418 -74.5744 180)
		(property "Reference" "C238"
			(at -0.3302 -5.00507 0)
			(unlocked yes)
			(layer "F.SilkS")
			(effects
				(font
					(size 0.7874 0.5842)
					(thickness 0.1524)
				)
			)
		)
		(property "Value" "VAL*"
			(at 0.0762 3.134106 180)
			(unlocked yes)
			(layer "F.Fab")
			(hide yes)
			(effects
				(font
					(size 0.7874 0.5842)
					(thickness 0.1524)
				)
			)
		)
		(property "Device Type" "CAPACITOR-G107-0F226-CM,22UF,2A"
			(at 0.0508 2.194306 180)
			(unlocked yes)
			(layer "F.Fab")
			(hide yes)
			(effects
				(font
					(size 0.7874 0.5842)
					(thickness 0.1524)
				)
			)
		)
		(property "User Part Number" "PARTNUM*"
			(at 0.1016 5.013706 180)
			(unlocked yes)
			(layer "Cmts.User")
			(hide yes)
			(effects
				(font
					(size 0.7874 0.5842)
					(thickness 0.1524)
				)
			)
		)
		(property "Tolerance" "TOL*"
			(at 0.0762 4.048506 180)
			(unlocked yes)
			(layer "Cmts.User")
			(hide yes)
			(effects
				(font
					(size 0.7874 0.5842)
					(thickness 0.1524)
				)
			)
		)
		(duplicate_pad_numbers_are_jumpers no)
		(fp_line
			(start 1.5748 0.9398)
			(end 1.5748 -0.9398)
			(stroke
				(width 0.1)
				(type default)
			)
			(layer "F.SilkS")
		)
		(fp_line
			(start 1.5748 -0.9398)
			(end -1.5748 -0.9398)
			(stroke
				(width 0.1)
				(type default)
			)
			(layer "F.SilkS")
		)
		(fp_line
			(start -1.5748 0.9398)
			(end 1.5748 0.9398)
			(stroke
				(width 0.1)
				(type default)
			)
			(layer "F.SilkS")
		)
		(fp_line
			(start -1.5748 -0.9398)
			(end -1.5748 0.9398)
			(stroke
				(width 0.1)
				(type default)
			)
			(layer "F.SilkS")
		)
		(fp_rect
			(start -1.5748 0.9398)
			(end 1.5748 -0.9398)
			(stroke
				(width 0)
				(type default)
			)
			(fill no)
			(layer "F.CrtYd")
		)
		(fp_line
			(start 1.016 0.635)
			(end 1.016 -0.635)
			(stroke
				(width 0.1)
				(type default)
			)
			(layer "F.Fab")
		)
		(fp_line
			(start 1.016 -0.635)
			(end -1.016 -0.635)
			(stroke
				(width 0.1)
				(type default)
			)
			(layer "F.Fab")
		)
		(fp_line
			(start -1.016 0.635)
			(end 1.016 0.635)
			(stroke
				(width 0.1)
				(type default)
			)
			(layer "F.Fab")
		)
		(fp_line
			(start -1.016 -0.635)
			(end -1.016 0.635)
			(stroke
				(width 0.1)
				(type default)
			)
			(layer "F.Fab")
		)
		(pad "1" smd rect
			(at -0.8382 0 180)
			(size 0.9652 1.3716)
			(layers "F.Cu" "F.Mask" "F.Paste")
			(net "XP3R3V_FPGA")
		)
		(pad "2" smd rect
			(at 0.8382 0 180)
			(size 0.9652 1.3716)
			(layers "F.Cu" "F.Mask" "F.Paste")
			(net "SG")
		)
		(zone
			(layer "F.Cu")
			(hatch none 0.5)
			(connect_pads
				(clearance 0)
			)
			(min_thickness 0.25)
			(keepout
				(tracks allowed)
				(vias not_allowed)
				(pads allowed)
				(copperpour not_allowed)
				(footprints allowed)
			)
			(placement
				(enabled no)
				(sheetname "")
			)
			(fill
				(thermal_gap 0.5)
				(thermal_bridge_width 0.5)
				(island_removal_mode 0)
			)
			(polygon
				(pts
					(xy 106.0704 -75.2094) (xy 105.6132 -75.2094) (xy 105.6132 -73.9394) (xy 106.0704 -73.9394)
				)
			)
		)
	)
	(footprint ""
		(layer "F.Cu")
		(at 154.153108 -49.01311 90)
		(property "Reference" "R67"
			(at 0.00889 2.604262 90)
			(unlocked yes)
			(layer "F.SilkS")
			(effects
				(font
					(size 0.7874 0.5842)
					(thickness 0.1524)
				)
			)
		)
		(property "Value" "VAL*"
			(at 0.02032 2.13233 90)
			(unlocked yes)
			(layer "F.Fab")
			(hide yes)
			(effects
				(font
					(size 0.7874 0.5842)
					(thickness 0.1524)
				)
			)
		)
		(property "Device Type" "RESISTOR-G155-133R0-01,33OHM,1%"
			(at 0.008382 1.210564 90)
			(unlocked yes)
			(layer "F.Fab")
			(hide yes)
			(effects
				(font
					(size 0.7874 0.5842)
					(thickness 0.1524)
				)
			)
		)
		(property "User Part Number" "PARTNUM*"
			(at 0.02032 4.024884 90)
			(unlocked yes)
			(layer "Cmts.User")
			(hide yes)
			(effects
				(font
					(size 0.7874 0.5842)
					(thickness 0.1524)
				)
			)
		)
		(property "Tolerance" "TOL*"
			(at 0.044704 3.05435 90)
			(unlocked yes)
			(layer "Cmts.User")
			(hide yes)
			(effects
				(font
					(size 0.7874 0.5842)
					(thickness 0.1524)
				)
			)
		)
		(duplicate_pad_numbers_are_jumpers no)
		(fp_line
			(start 1.143 -0.5588)
			(end -1.143 -0.5588)
			(stroke
				(width 0.1)
				(type default)
			)
			(layer "F.SilkS")
		)
		(fp_line
			(start -1.143 -0.5588)
			(end -1.143 0.5588)
			(stroke
				(width 0.1)
				(type default)
			)
			(layer "F.SilkS")
		)
		(fp_line
			(start 1.143 0.5588)
			(end 1.143 -0.5588)
			(stroke
				(width 0.1)
				(type default)
			)
			(layer "F.SilkS")
		)
		(fp_line
			(start -1.143 0.5588)
			(end 1.143 0.5588)
			(stroke
				(width 0.1)
				(type default)
			)
			(layer "F.SilkS")
		)
		(fp_rect
			(start 1.143 0.5588)
			(end -1.143 -0.5588)
			(stroke
				(width 0)
				(type default)
			)
			(fill no)
			(layer "F.CrtYd")
		)
		(fp_line
			(start 0.508 -0.3048)
			(end -0.508 -0.3048)
			(stroke
				(width 0.1)
				(type default)
			)
			(layer "F.Fab")
		)
		(fp_line
			(start -0.508 -0.3048)
			(end -0.508 0.3048)
			(stroke
				(width 0.1)
				(type default)
			)
			(layer "F.Fab")
		)
		(fp_line
			(start 0.508 0.3048)
			(end 0.508 -0.3048)
			(stroke
				(width 0.1)
				(type default)
			)
			(layer "F.Fab")
		)
		(fp_line
			(start -0.508 0.3048)
			(end 0.508 0.3048)
			(stroke
				(width 0.1)
				(type default)
			)
			(layer "F.Fab")
		)
		(pad "1" smd rect
			(at -0.5334 0 90)
			(size 0.7112 0.6096)
			(layers "F.Cu" "F.Mask" "F.Paste")
			(net "SHT3X_I2C_SCL")
		)
		(pad "2" smd rect
			(at 0.5334 0 90)
			(size 0.7112 0.6096)
			(layers "F.Cu" "F.Mask" "F.Paste")
			(net "R_SHT3X_I2C_SCL")
		)
		(zone
			(layer "F.Cu")
			(hatch none 0.5)
			(connect_pads
				(clearance 0)
			)
			(min_thickness 0.25)
			(keepout
				(tracks allowed)
				(vias not_allowed)
				(pads allowed)
				(copperpour not_allowed)
				(footprints allowed)
			)
			(placement
				(enabled no)
				(sheetname "")
			)
			(fill
				(thermal_gap 0.5)
				(thermal_bridge_width 0.5)
				(island_removal_mode 0)
			)
			(polygon
				(pts
					(xy 154.457908 -49.08931) (xy 153.848308 -49.08931) (xy 153.848308 -48.93691) (xy 154.457908 -48.93691)
				)
			)
		)
	)
	(footprint ""
		(layer "F.Cu")
		(at 72.136 -128.27)
		(property "Reference" "SP31"
			(at 0 0 0)
			(layer "F.SilkS")
			(hide yes)
			(effects
				(font
					(size 1.27 1.27)
				)
			)
		)
		(property "Value" ""
			(at 0 0 0)
			(layer "F.Fab")
			(effects
				(font
					(size 1.27 1.27)
				)
			)
		)
		(duplicate_pad_numbers_are_jumpers no)
	)
	(footprint ""
		(layer "F.Cu")
		(at 83.439 -64.3128 90)
		(property "Reference" "R303"
			(at 13.4112 -9.73963 90)
			(unlocked yes)
			(layer "F.SilkS")
			(effects
				(font
					(size 0.7874 0.5842)
					(thickness 0.1524)
				)
			)
		)
		(property "Value" "VAL*"
			(at 0.02032 2.13233 90)
			(unlocked yes)
			(layer "F.Fab")
			(hide yes)
			(effects
				(font
					(size 0.7874 0.5842)
					(thickness 0.1524)
				)
			)
		)
		(property "Device Type" "RESISTOR-G155-11001-01,1KOHM,1%"
			(at 0.008382 1.210564 90)
			(unlocked yes)
			(layer "F.Fab")
			(hide yes)
			(effects
				(font
					(size 0.7874 0.5842)
					(thickness 0.1524)
				)
			)
		)
		(property "User Part Number" "PARTNUM*"
			(at 0.02032 4.024884 90)
			(unlocked yes)
			(layer "Cmts.User")
			(hide yes)
			(effects
				(font
					(size 0.7874 0.5842)
					(thickness 0.1524)
				)
			)
		)
		(property "Tolerance" "TOL*"
			(at 0.044704 3.05435 90)
			(unlocked yes)
			(layer "Cmts.User")
			(hide yes)
			(effects
				(font
					(size 0.7874 0.5842)
					(thickness 0.1524)
				)
			)
		)
		(duplicate_pad_numbers_are_jumpers no)
		(fp_line
			(start 1.143 -0.5588)
			(end -1.143 -0.5588)
			(stroke
				(width 0.1)
				(type default)
			)
			(layer "F.SilkS")
		)
		(fp_line
			(start -1.143 -0.5588)
			(end -1.143 0.5588)
			(stroke
				(width 0.1)
				(type default)
			)
			(layer "F.SilkS")
		)
		(fp_line
			(start 1.143 0.5588)
			(end 1.143 -0.5588)
			(stroke
				(width 0.1)
				(type default)
			)
			(layer "F.SilkS")
		)
		(fp_line
			(start -1.143 0.5588)
			(end 1.143 0.5588)
			(stroke
				(width 0.1)
				(type default)
			)
			(layer "F.SilkS")
		)
		(fp_rect
			(start -1.143 -0.5588)
			(end 1.143 0.5588)
			(stroke
				(width 0)
				(type default)
			)
			(fill no)
			(layer "F.CrtYd")
		)
		(fp_line
			(start 0.508 -0.3048)
			(end -0.508 -0.3048)
			(stroke
				(width 0.1)
				(type default)
			)
			(layer "F.Fab")
		)
		(fp_line
			(start -0.508 -0.3048)
			(end -0.508 0.3048)
			(stroke
				(width 0.1)
				(type default)
			)
			(layer "F.Fab")
		)
		(fp_line
			(start 0.508 0.3048)
			(end 0.508 -0.3048)
			(stroke
				(width 0.1)
				(type default)
			)
			(layer "F.Fab")
		)
		(fp_line
			(start -0.508 0.3048)
			(end 0.508 0.3048)
			(stroke
				(width 0.1)
				(type default)
			)
			(layer "F.Fab")
		)
		(pad "1" smd rect
			(at -0.5334 0 90)
			(size 0.7112 0.6096)
			(layers "F.Cu" "F.Mask" "F.Paste")
			(net "UNNAMED_9_BNO080LGA28_I29_PS1")
		)
		(pad "2" smd rect
			(at 0.5334 0 90)
			(size 0.7112 0.6096)
			(layers "F.Cu" "F.Mask" "F.Paste")
			(net "SG")
		)
		(zone
			(layer "F.Cu")
			(hatch none 0.5)
			(connect_pads
				(clearance 0)
			)
			(min_thickness 0.25)
			(keepout
				(tracks allowed)
				(vias not_allowed)
				(pads allowed)
				(copperpour not_allowed)
				(footprints allowed)
			)
			(placement
				(enabled no)
				(sheetname "")
			)
			(fill
				(thermal_gap 0.5)
				(thermal_bridge_width 0.5)
				(island_removal_mode 0)
			)
			(polygon
				(pts
					(xy 83.1342 -64.2366) (xy 83.7438 -64.2366) (xy 83.7438 -64.389) (xy 83.1342 -64.389)
				)
			)
		)
	)
	(footprint ""
		(layer "F.Cu")
		(at 28.067 -94.234 -90)
		(property "Reference" "R129"
			(at -4.953 0.59563 90)
			(unlocked yes)
			(layer "F.SilkS")
			(effects
				(font
					(size 0.7874 0.5842)
					(thickness 0.1524)
				)
			)
		)
		(property "Value" "VAL*"
			(at 0.02032 2.13233 270)
			(unlocked yes)
			(layer "F.Fab")
			(hide yes)
			(effects
				(font
					(size 0.7874 0.5842)
					(thickness 0.1524)
				)
			)
		)
		(property "Tolerance" "TOL*"
			(at 0.044704 3.05435 270)
			(unlocked yes)
			(layer "Cmts.User")
			(hide yes)
			(effects
				(font
					(size 0.7874 0.5842)
					(thickness 0.1524)
				)
			)
		)
		(property "User Part Number" "PARTNUM*"
			(at 0.02032 4.024884 270)
			(unlocked yes)
			(layer "Cmts.User")
			(hide yes)
			(effects
				(font
					(size 0.7874 0.5842)
					(thickness 0.1524)
				)
			)
		)
		(property "Device Type" "RESISTOR-G155-100R0-J0,0OHM,-"
			(at 0.008382 1.210564 270)
			(unlocked yes)
			(layer "F.Fab")
			(hide yes)
			(effects
				(font
					(size 0.7874 0.5842)
					(thickness 0.1524)
				)
			)
		)
		(duplicate_pad_numbers_are_jumpers no)
		(fp_line
			(start -1.143 0.5588)
			(end 1.143 0.5588)
			(stroke
				(width 0.1)
				(type default)
			)
			(layer "F.SilkS")
		)
		(fp_line
			(start 1.143 0.5588)
			(end 1.143 -0.5588)
			(stroke
				(width 0.1)
				(type default)
			)
			(layer "F.SilkS")
		)
		(fp_line
			(start -1.143 -0.5588)
			(end -1.143 0.5588)
			(stroke
				(width 0.1)
				(type default)
			)
			(layer "F.SilkS")
		)
		(fp_line
			(start 1.143 -0.5588)
			(end -1.143 -0.5588)
			(stroke
				(width 0.1)
				(type default)
			)
			(layer "F.SilkS")
		)
		(fp_poly
			(pts
				(xy -1.143 0.5588) (xy 1.143 0.5588) (xy 1.143 -0.5588) (xy -1.143 -0.5588)
			)
			(stroke
				(width 0)
				(type default)
			)
			(fill no)
			(layer "F.CrtYd")
		)
		(fp_line
			(start -0.508 0.3048)
			(end 0.508 0.3048)
			(stroke
				(width 0.1)
				(type default)
			)
			(layer "F.Fab")
		)
		(fp_line
			(start 0.508 0.3048)
			(end 0.508 -0.3048)
			(stroke
				(width 0.1)
				(type default)
			)
			(layer "F.Fab")
		)
		(fp_line
			(start -0.508 -0.3048)
			(end -0.508 0.3048)
			(stroke
				(width 0.1)
				(type default)
			)
			(layer "F.Fab")
		)
		(fp_line
			(start 0.508 -0.3048)
			(end -0.508 -0.3048)
			(stroke
				(width 0.1)
				(type default)
			)
			(layer "F.Fab")
		)
		(pad "1" smd rect
			(at -0.5334 0 270)
			(size 0.7112 0.6096)
			(layers "F.Cu" "F.Mask" "F.Paste")
			(net "FT_USB_DP")
		)
		(pad "2" smd rect
			(at 0.5334 0 270)
			(size 0.7112 0.6096)
			(layers "F.Cu" "F.Mask" "F.Paste")
			(net "R_FT_USB_DP")
		)
		(zone
			(layer "F.Cu")
			(hatch none 0.5)
			(connect_pads
				(clearance 0)
			)
			(min_thickness 0.25)
			(keepout
				(tracks not_allowed)
				(vias allowed)
				(pads allowed)
				(copperpour not_allowed)
				(footprints allowed)
			)
			(placement
				(enabled no)
				(sheetname "")
			)
			(fill
				(thermal_gap 0.5)
				(thermal_bridge_width 0.5)
				(island_removal_mode 0)
			)
			(polygon
				(pts
					(xy 27.7622 -94.3102) (xy 27.7622 -94.1578) (xy 28.3718 -94.1578) (xy 28.3718 -94.3102)
				)
			)
		)
		(zone
			(layer "F.Cu")
			(hatch none 0.5)
			(connect_pads
				(clearance 0)
			)
			(min_thickness 0.25)
			(keepout
				(tracks allowed)
				(vias not_allowed)
				(pads allowed)
				(copperpour not_allowed)
				(footprints allowed)
			)
			(placement
				(enabled no)
				(sheetname "")
			)
			(fill
				(thermal_gap 0.5)
				(thermal_bridge_width 0.5)
				(island_removal_mode 0)
			)
			(polygon
				(pts
					(xy 27.7622 -94.3102) (xy 27.7622 -94.1578) (xy 28.3718 -94.1578) (xy 28.3718 -94.3102)
				)
			)
		)
	)
	(footprint ""
		(layer "F.Cu")
		(at 21.209 -64.643 -90)
		(property "Reference" "R351"
			(at 1.27 -4.10337 90)
			(unlocked yes)
			(layer "F.SilkS")
			(effects
				(font
					(size 0.7874 0.5842)
					(thickness 0.1524)
				)
			)
		)
		(property "Value" "VAL*"
			(at 0.02032 2.13233 270)
			(unlocked yes)
			(layer "F.Fab")
			(hide yes)
			(effects
				(font
					(size 0.7874 0.5842)
					(thickness 0.1524)
				)
			)
		)
		(property "Tolerance" "TOL*"
			(at 0.044704 3.05435 270)
			(unlocked yes)
			(layer "Cmts.User")
			(hide yes)
			(effects
				(font
					(size 0.7874 0.5842)
					(thickness 0.1524)
				)
			)
		)
		(property "User Part Number" "PARTNUM*"
			(at 0.02032 4.024884 270)
			(unlocked yes)
			(layer "Cmts.User")
			(hide yes)
			(effects
				(font
					(size 0.7874 0.5842)
					(thickness 0.1524)
				)
			)
		)
		(property "Device Type" "RESISTOR-G155-100R0-J0,0OHM,-"
			(at 0.008382 1.210564 270)
			(unlocked yes)
			(layer "F.Fab")
			(hide yes)
			(effects
				(font
					(size 0.7874 0.5842)
					(thickness 0.1524)
				)
			)
		)
		(duplicate_pad_numbers_are_jumpers no)
		(fp_line
			(start -1.143 0.5588)
			(end 1.143 0.5588)
			(stroke
				(width 0.1)
				(type default)
			)
			(layer "F.SilkS")
		)
		(fp_line
			(start 1.143 0.5588)
			(end 1.143 -0.5588)
			(stroke
				(width 0.1)
				(type default)
			)
			(layer "F.SilkS")
		)
		(fp_line
			(start -1.143 -0.5588)
			(end -1.143 0.5588)
			(stroke
				(width 0.1)
				(type default)
			)
			(layer "F.SilkS")
		)
		(fp_line
			(start 1.143 -0.5588)
			(end -1.143 -0.5588)
			(stroke
				(width 0.1)
				(type default)
			)
			(layer "F.SilkS")
		)
		(fp_poly
			(pts
				(xy -1.143 0.5588) (xy 1.143 0.5588) (xy 1.143 -0.5588) (xy -1.143 -0.5588)
			)
			(stroke
				(width 0)
				(type default)
			)
			(fill no)
			(layer "F.CrtYd")
		)
		(fp_line
			(start -0.508 0.3048)
			(end 0.508 0.3048)
			(stroke
				(width 0.1)
				(type default)
			)
			(layer "F.Fab")
		)
		(fp_line
			(start 0.508 0.3048)
			(end 0.508 -0.3048)
			(stroke
				(width 0.1)
				(type default)
			)
			(layer "F.Fab")
		)
		(fp_line
			(start -0.508 -0.3048)
			(end -0.508 0.3048)
			(stroke
				(width 0.1)
				(type default)
			)
			(layer "F.Fab")
		)
		(fp_line
			(start 0.508 -0.3048)
			(end -0.508 -0.3048)
			(stroke
				(width 0.1)
				(type default)
			)
			(layer "F.Fab")
		)
		(pad "1" smd rect
			(at -0.5334 0 270)
			(size 0.7112 0.6096)
			(layers "F.Cu" "F.Mask" "F.Paste")
			(net "UNNAMED_8_ICP10100LGA10_I24_R_4")
		)
		(pad "2" smd rect
			(at 0.5334 0 270)
			(size 0.7112 0.6096)
			(layers "F.Cu" "F.Mask" "F.Paste")
			(net "SG")
		)
		(zone
			(layer "F.Cu")
			(hatch none 0.5)
			(connect_pads
				(clearance 0)
			)
			(min_thickness 0.25)
			(keepout
				(tracks allowed)
				(vias not_allowed)
				(pads allowed)
				(copperpour not_allowed)
				(footprints allowed)
			)
			(placement
				(enabled no)
				(sheetname "")
			)
			(fill
				(thermal_gap 0.5)
				(thermal_bridge_width 0.5)
				(island_removal_mode 0)
			)
			(polygon
				(pts
					(xy 20.9042 -64.7192) (xy 20.9042 -64.5668) (xy 21.5138 -64.5668) (xy 21.5138 -64.7192)
				)
			)
		)
		(zone
			(layer "F.Cu")
			(hatch none 0.5)
			(connect_pads
				(clearance 0)
			)
			(min_thickness 0.25)
			(keepout
				(tracks not_allowed)
				(vias allowed)
				(pads allowed)
				(copperpour not_allowed)
				(footprints allowed)
			)
			(placement
				(enabled no)
				(sheetname "")
			)
			(fill
				(thermal_gap 0.5)
				(thermal_bridge_width 0.5)
				(island_removal_mode 0)
			)
			(polygon
				(pts
					(xy 20.9042 -64.7192) (xy 20.9042 -64.5668) (xy 21.5138 -64.5668) (xy 21.5138 -64.7192)
				)
			)
		)
	)
	(footprint ""
		(layer "F.Cu")
		(at 30.34538 -15.58544)
		(property "Reference" "C225"
			(at -0.889 -5.29463 0)
			(unlocked yes)
			(layer "F.SilkS")
			(effects
				(font
					(size 0.7874 0.5842)
					(thickness 0.1524)
				)
			)
		)
		(property "Value" "VAL*"
			(at 0.0762 2.067306 0)
			(unlocked yes)
			(layer "F.Fab")
			(hide yes)
			(effects
				(font
					(size 0.7874 0.5842)
					(thickness 0.1524)
				)
			)
		)
		(property "Tolerance" "TOL*"
			(at 0.0762 3.032506 0)
			(unlocked yes)
			(layer "Cmts.User")
			(hide yes)
			(effects
				(font
					(size 0.7874 0.5842)
					(thickness 0.1524)
				)
			)
		)
		(property "User Part Number" "PARTNUM*"
			(at 0.1016 4.023106 0)
			(unlocked yes)
			(layer "Cmts.User")
			(hide yes)
			(effects
				(font
					(size 0.7874 0.5842)
					(thickness 0.1524)
				)
			)
		)
		(property "Device Type" "CAPACITOR-G105-0B104-EK,0.1UF,A"
			(at 0.0508 1.127506 0)
			(unlocked yes)
			(layer "F.Fab")
			(hide yes)
			(effects
				(font
					(size 0.7874 0.5842)
					(thickness 0.1524)
				)
			)
		)
		(duplicate_pad_numbers_are_jumpers no)
		(fp_line
			(start -1.143 -0.5588)
			(end -1.143 0.5588)
			(stroke
				(width 0.1)
				(type default)
			)
			(layer "F.SilkS")
		)
		(fp_line
			(start -1.143 0.5588)
			(end 1.143 0.5588)
			(stroke
				(width 0.1)
				(type default)
			)
			(layer "F.SilkS")
		)
		(fp_line
			(start 1.143 -0.5588)
			(end -1.143 -0.5588)
			(stroke
				(width 0.1)
				(type default)
			)
			(layer "F.SilkS")
		)
		(fp_line
			(start 1.143 0.5588)
			(end 1.143 -0.5588)
			(stroke
				(width 0.1)
				(type default)
			)
			(layer "F.SilkS")
		)
		(fp_rect
			(start -1.143 0.5588)
			(end 1.143 -0.5588)
			(stroke
				(width 0)
				(type default)
			)
			(fill no)
			(layer "F.CrtYd")
		)
		(fp_line
			(start -0.508 -0.3048)
			(end -0.508 0.3048)
			(stroke
				(width 0.1)
				(type default)
			)
			(layer "F.Fab")
		)
		(fp_line
			(start -0.508 0.3048)
			(end 0.508 0.3048)
			(stroke
				(width 0.1)
				(type default)
			)
			(layer "F.Fab")
		)
		(fp_line
			(start 0.508 -0.3048)
			(end -0.508 -0.3048)
			(stroke
				(width 0.1)
				(type default)
			)
			(layer "F.Fab")
		)
		(fp_line
			(start 0.508 0.3048)
			(end 0.508 -0.3048)
			(stroke
				(width 0.1)
				(type default)
			)
			(layer "F.Fab")
		)
		(pad "1" smd rect
			(at -0.5334 0)
			(size 0.7112 0.6096)
			(layers "F.Cu" "F.Mask" "F.Paste")
			(net "XP3R3V_FPGA")
		)
		(pad "2" smd rect
			(at 0.5334 0)
			(size 0.7112 0.6096)
			(layers "F.Cu" "F.Mask" "F.Paste")
			(net "SG")
		)
		(zone
			(layer "F.Cu")
			(hatch none 0.5)
			(connect_pads
				(clearance 0)
			)
			(min_thickness 0.25)
			(keepout
				(tracks allowed)
				(vias not_allowed)
				(pads allowed)
				(copperpour not_allowed)
				(footprints allowed)
			)
			(placement
				(enabled no)
				(sheetname "")
			)
			(fill
				(thermal_gap 0.5)
				(thermal_bridge_width 0.5)
				(island_removal_mode 0)
			)
			(polygon
				(pts
					(xy 30.26918 -15.28064) (xy 30.42158 -15.28064) (xy 30.42158 -15.89024) (xy 30.26918 -15.89024)
				)
			)
		)
	)
	(footprint ""
		(layer "F.Cu")
		(at 44.831 -128.016)
		(property "Reference" "SP42"
			(at 0 0 0)
			(layer "F.SilkS")
			(hide yes)
			(effects
				(font
					(size 1.27 1.27)
				)
			)
		)
		(property "Value" ""
			(at 0 0 0)
			(layer "F.Fab")
			(effects
				(font
					(size 1.27 1.27)
				)
			)
		)
		(duplicate_pad_numbers_are_jumpers no)
	)
	(footprint ""
		(layer "F.Cu")
		(at 38.608 -123.19)
		(property "Reference" "SP76"
			(at 0 0 0)
			(layer "F.SilkS")
			(hide yes)
			(effects
				(font
					(size 1.27 1.27)
				)
			)
		)
		(property "Value" ""
			(at 0 0 0)
			(layer "F.Fab")
			(effects
				(font
					(size 1.27 1.27)
				)
			)
		)
		(duplicate_pad_numbers_are_jumpers no)
	)
	(footprint ""
		(layer "F.Cu")
		(at 89.9922 -102.4128)
		(property "Reference" "C46"
			(at 3.048 0.16637 0)
			(unlocked yes)
			(layer "F.SilkS")
			(effects
				(font
					(size 0.7874 0.5842)
					(thickness 0.1524)
				)
			)
		)
		(property "Value" "VAL*"
			(at 0.0762 2.067306 0)
			(unlocked yes)
			(layer "F.Fab")
			(hide yes)
			(effects
				(font
					(size 0.7874 0.5842)
					(thickness 0.1524)
				)
			)
		)
		(property "Tolerance" "TOL*"
			(at 0.0762 3.032506 0)
			(unlocked yes)
			(layer "Cmts.User")
			(hide yes)
			(effects
				(font
					(size 0.7874 0.5842)
					(thickness 0.1524)
				)
			)
		)
		(property "User Part Number" "PARTNUM*"
			(at 0.1016 4.023106 0)
			(unlocked yes)
			(layer "Cmts.User")
			(hide yes)
			(effects
				(font
					(size 0.7874 0.5842)
					(thickness 0.1524)
				)
			)
		)
		(property "Device Type" "CAPACITOR-G105-0B104-CK,0.1UF,A"
			(at 0.0508 1.127506 0)
			(unlocked yes)
			(layer "F.Fab")
			(hide yes)
			(effects
				(font
					(size 0.7874 0.5842)
					(thickness 0.1524)
				)
			)
		)
		(duplicate_pad_numbers_are_jumpers no)
		(fp_line
			(start -1.143 -0.5588)
			(end -1.143 0.5588)
			(stroke
				(width 0.1)
				(type default)
			)
			(layer "F.SilkS")
		)
		(fp_line
			(start -1.143 0.5588)
			(end 1.143 0.5588)
			(stroke
				(width 0.1)
				(type default)
			)
			(layer "F.SilkS")
		)
		(fp_line
			(start 1.143 -0.5588)
			(end -1.143 -0.5588)
			(stroke
				(width 0.1)
				(type default)
			)
			(layer "F.SilkS")
		)
		(fp_line
			(start 1.143 0.5588)
			(end 1.143 -0.5588)
			(stroke
				(width 0.1)
				(type default)
			)
			(layer "F.SilkS")
		)
		(fp_rect
			(start -1.143 0.5588)
			(end 1.143 -0.5588)
			(stroke
				(width 0)
				(type default)
			)
			(fill no)
			(layer "F.CrtYd")
		)
		(fp_line
			(start -0.508 -0.3048)
			(end -0.508 0.3048)
			(stroke
				(width 0.1)
				(type default)
			)
			(layer "F.Fab")
		)
		(fp_line
			(start -0.508 0.3048)
			(end 0.508 0.3048)
			(stroke
				(width 0.1)
				(type default)
			)
			(layer "F.Fab")
		)
		(fp_line
			(start 0.508 -0.3048)
			(end -0.508 -0.3048)
			(stroke
				(width 0.1)
				(type default)
			)
			(layer "F.Fab")
		)
		(fp_line
			(start 0.508 0.3048)
			(end 0.508 -0.3048)
			(stroke
				(width 0.1)
				(type default)
			)
			(layer "F.Fab")
		)
		(pad "1" smd rect
			(at -0.5334 0)
			(size 0.7112 0.6096)
			(layers "F.Cu" "F.Mask" "F.Paste")
			(net "XP3R3V_EN")
		)
		(pad "2" smd rect
			(at 0.5334 0)
			(size 0.7112 0.6096)
			(layers "F.Cu" "F.Mask" "F.Paste")
			(net "SG")
		)
		(zone
			(layer "F.Cu")
			(hatch none 0.5)
			(connect_pads
				(clearance 0)
			)
			(min_thickness 0.25)
			(keepout
				(tracks allowed)
				(vias not_allowed)
				(pads allowed)
				(copperpour not_allowed)
				(footprints allowed)
			)
			(placement
				(enabled no)
				(sheetname "")
			)
			(fill
				(thermal_gap 0.5)
				(thermal_bridge_width 0.5)
				(island_removal_mode 0)
			)
			(polygon
				(pts
					(xy 89.916 -102.108) (xy 90.0684 -102.108) (xy 90.0684 -102.7176) (xy 89.916 -102.7176)
				)
			)
		)
	)
	(footprint ""
		(layer "F.Cu")
		(at 79.8576 -44.45 180)
		(property "Reference" "R88"
			(at -0.0254 -14.00937 0)
			(unlocked yes)
			(layer "F.SilkS")
			(effects
				(font
					(size 0.7874 0.5842)
					(thickness 0.1524)
				)
			)
		)
		(property "Value" "VAL*"
			(at 0.02032 2.13233 180)
			(unlocked yes)
			(layer "F.Fab")
			(hide yes)
			(effects
				(font
					(size 0.7874 0.5842)
					(thickness 0.1524)
				)
			)
		)
		(property "Device Type" "RESISTOR-G155-100R0-J0,0OHM,-"
			(at 0.008382 1.210564 180)
			(unlocked yes)
			(layer "F.Fab")
			(hide yes)
			(effects
				(font
					(size 0.7874 0.5842)
					(thickness 0.1524)
				)
			)
		)
		(property "User Part Number" "PARTNUM*"
			(at 0.02032 4.024884 180)
			(unlocked yes)
			(layer "Cmts.User")
			(hide yes)
			(effects
				(font
					(size 0.7874 0.5842)
					(thickness 0.1524)
				)
			)
		)
		(property "Tolerance" "TOL*"
			(at 0.044704 3.05435 180)
			(unlocked yes)
			(layer "Cmts.User")
			(hide yes)
			(effects
				(font
					(size 0.7874 0.5842)
					(thickness 0.1524)
				)
			)
		)
		(duplicate_pad_numbers_are_jumpers no)
		(fp_line
			(start 1.143 0.5588)
			(end 1.143 -0.5588)
			(stroke
				(width 0.1)
				(type default)
			)
			(layer "F.SilkS")
		)
		(fp_line
			(start 1.143 -0.5588)
			(end -1.143 -0.5588)
			(stroke
				(width 0.1)
				(type default)
			)
			(layer "F.SilkS")
		)
		(fp_line
			(start -1.143 0.5588)
			(end 1.143 0.5588)
			(stroke
				(width 0.1)
				(type default)
			)
			(layer "F.SilkS")
		)
		(fp_line
			(start -1.143 -0.5588)
			(end -1.143 0.5588)
			(stroke
				(width 0.1)
				(type default)
			)
			(layer "F.SilkS")
		)
		(fp_rect
			(start 1.143 -0.5588)
			(end -1.143 0.5588)
			(stroke
				(width 0)
				(type default)
			)
			(fill no)
			(layer "F.CrtYd")
		)
		(fp_line
			(start 0.508 0.3048)
			(end 0.508 -0.3048)
			(stroke
				(width 0.1)
				(type default)
			)
			(layer "F.Fab")
		)
		(fp_line
			(start 0.508 -0.3048)
			(end -0.508 -0.3048)
			(stroke
				(width 0.1)
				(type default)
			)
			(layer "F.Fab")
		)
		(fp_line
			(start -0.508 0.3048)
			(end 0.508 0.3048)
			(stroke
				(width 0.1)
				(type default)
			)
			(layer "F.Fab")
		)
		(fp_line
			(start -0.508 -0.3048)
			(end -0.508 0.3048)
			(stroke
				(width 0.1)
				(type default)
			)
			(layer "F.Fab")
		)
		(pad "1" smd rect
			(at -0.5334 0 180)
			(size 0.7112 0.6096)
			(layers "F.Cu" "F.Mask" "F.Paste")
			(net "FPGA_IN_MAC_PPS_OUTN")
		)
		(pad "2" smd rect
			(at 0.5334 0 180)
			(size 0.7112 0.6096)
			(layers "F.Cu" "F.Mask" "F.Paste")
			(net "R_MAC_PPS_OUTN")
		)
		(zone
			(layer "F.Cu")
			(hatch none 0.5)
			(connect_pads
				(clearance 0)
			)
			(min_thickness 0.25)
			(keepout
				(tracks allowed)
				(vias not_allowed)
				(pads allowed)
				(copperpour not_allowed)
				(footprints allowed)
			)
			(placement
				(enabled no)
				(sheetname "")
			)
			(fill
				(thermal_gap 0.5)
				(thermal_bridge_width 0.5)
				(island_removal_mode 0)
			)
			(polygon
				(pts
					(xy 79.7814 -44.1452) (xy 79.9338 -44.1452) (xy 79.9338 -44.7548) (xy 79.7814 -44.7548)
				)
			)
		)
	)
	(footprint ""
		(layer "F.Cu")
		(at 105.2576 -101.3968 180)
		(property "Reference" "U33"
			(at -1.5494 5.11683 0)
			(unlocked yes)
			(layer "F.SilkS")
			(effects
				(font
					(size 0.7874 0.5842)
					(thickness 0.1524)
				)
			)
		)
		(property "Value" ""
			(at 0 0 180)
			(layer "F.Fab")
			(effects
				(font
					(size 1.27 1.27)
				)
			)
		)
		(property "Device Type" "IS32FL3207_QWLA3_TR_QFN29-A223A"
			(at 0 5.031486 180)
			(unlocked yes)
			(layer "F.Fab")
			(hide yes)
			(effects
				(font
					(size 0.7874 0.5842)
					(thickness 0.1524)
				)
			)
		)
		(property "User Part Number" "PARTNUM*"
			(at 0 6.225286 180)
			(unlocked yes)
			(layer "Cmts.User")
			(hide yes)
			(effects
				(font
					(size 0.7874 0.5842)
					(thickness 0.1524)
				)
			)
		)
		(duplicate_pad_numbers_are_jumpers no)
		(fp_line
			(start 3.29184 3.29184)
			(end 3.29184 -3.29184)
			(stroke
				(width 0.1)
				(type default)
			)
			(layer "F.SilkS")
		)
		(fp_line
			(start 3.29184 -3.29184)
			(end -3.29184 -3.29184)
			(stroke
				(width 0.1)
				(type default)
			)
			(layer "F.SilkS")
		)
		(fp_line
			(start -3.29184 3.29184)
			(end 3.29184 3.29184)
			(stroke
				(width 0.1)
				(type default)
			)
			(layer "F.SilkS")
		)
		(fp_line
			(start -3.29184 -3.29184)
			(end -3.29184 3.29184)
			(stroke
				(width 0.1)
				(type default)
			)
			(layer "F.SilkS")
		)
		(fp_poly
			(pts
				(arc
					(start -4.659122 -1.500124)
					(mid -3.643122 -1.500124)
					(end -4.659122 -1.500124)
				)
			)
			(stroke
				(width 0)
				(type default)
			)
			(fill yes)
			(layer "F.SilkS")
		)
		(fp_poly
			(pts
				(xy 1.4605 0.4191)
				(arc
					(start 0.753618 0.4191)
					(mid 0.700385 0.341015)
					(end 0.6223 0.287782)
				)
				(xy 0.6223 -0.4191) (xy 1.4605 -0.4191)
			)
			(stroke
				(width 0)
				(type default)
			)
			(fill yes)
			(layer "F.Paste")
		)
		(fp_poly
			(pts
				(xy 0.4191 1.4605) (xy -0.4191 1.4605)
				(arc
					(start -0.4191 0.753618)
					(mid -0.341015 0.700385)
					(end -0.287782 0.6223)
				)
				(arc
					(start 0.287782 0.6223)
					(mid 0.341015 0.700385)
					(end 0.4191 0.753618)
				)
			)
			(stroke
				(width 0)
				(type default)
			)
			(fill yes)
			(layer "F.Paste")
		)
		(fp_poly
			(pts
				(arc
					(start 0.4191 -0.753618)
					(mid 0.341015 -0.700385)
					(end 0.287782 -0.6223)
				)
				(arc
					(start -0.287782 -0.6223)
					(mid -0.341015 -0.700385)
					(end -0.4191 -0.753618)
				)
				(xy -0.4191 -1.4605) (xy 0.4191 -1.4605)
			)
			(stroke
				(width 0)
				(type default)
			)
			(fill yes)
			(layer "F.Paste")
		)
		(fp_poly
			(pts
				(arc
					(start -0.6223 0.287782)
					(mid -0.700385 0.341015)
					(end -0.753618 0.4191)
				)
				(xy -1.4605 0.4191) (xy -1.4605 -0.4191)
				(arc
					(start -0.753618 -0.4191)
					(mid -0.700385 -0.341015)
					(end -0.6223 -0.287782)
				)
			)
			(stroke
				(width 0)
				(type default)
			)
			(fill yes)
			(layer "F.Paste")
		)
		(fp_poly
			(pts
				(arc
					(start 0.4191 0.287782)
					(mid 0.341015 0.341015)
					(end 0.287782 0.4191)
				)
				(arc
					(start -0.287782 0.4191)
					(mid -0.341015 0.341015)
					(end -0.4191 0.287782)
				)
				(arc
					(start -0.4191 -0.287782)
					(mid -0.341015 -0.341015)
					(end -0.287782 -0.4191)
				)
				(arc
					(start 0.287782 -0.4191)
					(mid 0.341015 -0.341015)
					(end 0.4191 -0.287782)
				)
			)
			(stroke
				(width 0)
				(type default)
			)
			(fill yes)
			(layer "F.Paste")
		)
		(fp_poly
			(pts
				(arc
					(start -0.6223 -0.753618)
					(mid -0.700385 -0.700385)
					(end -0.753618 -0.6223)
				)
				(xy -1.4605 -0.6223)
				(arc
					(start -1.4605 -1.20396)
					(mid -1.385214 -1.02599)
					(end -1.2065 -0.9525)
				)
				(arc
					(start -1.2065 -0.9525)
					(mid -1.026895 -1.026895)
					(end -0.9525 -1.2065)
				)
				(arc
					(start -0.9525 -1.2065)
					(mid -1.025108 -1.3843)
					(end -1.20142 -1.4605)
				)
				(xy -0.6223 -1.4605)
			)
			(stroke
				(width 0)
				(type default)
			)
			(fill yes)
			(layer "F.Paste")
		)
		(fp_poly
			(pts
				(xy 1.4605 -0.6223)
				(arc
					(start 0.753618 -0.6223)
					(mid 0.700385 -0.700385)
					(end 0.6223 -0.753618)
				)
				(xy 0.6223 -1.4605)
				(arc
					(start 1.20142 -1.4605)
					(mid 1.025072 -1.384336)
					(end 0.9525 -1.2065)
				)
				(arc
					(start 0.9525 -1.2065)
					(mid 1.026895 -1.026895)
					(end 1.2065 -0.9525)
				)
				(arc
					(start 1.2065 -0.9525)
					(mid 1.380633 -1.021584)
					(end 1.459992 -1.19126)
				)
				(xy 1.4605 -1.19126)
			)
			(stroke
				(width 0)
				(type default)
			)
			(fill yes)
			(layer "F.Paste")
		)
		(fp_poly
			(pts
				(arc
					(start 0.9525 1.2065)
					(mid 1.025999 1.385205)
					(end 1.20396 1.4605)
				)
				(xy 0.6223 1.4605)
				(arc
					(start 0.6223 0.753618)
					(mid 0.700385 0.700385)
					(end 0.753618 0.6223)
				)
				(xy 1.4605 0.6223) (xy 1.4605 1.1938)
				(arc
					(start 1.460246 1.1938)
					(mid 1.381602 1.022415)
					(end 1.2065 0.9525)
				)
				(arc
					(start 1.2065 0.9525)
					(mid 1.026895 1.026895)
					(end 0.9525 1.2065)
				)
			)
			(stroke
				(width 0)
				(type default)
			)
			(fill yes)
			(layer "F.Paste")
		)
		(fp_poly
			(pts
				(xy -0.6223 1.4605) (xy -1.19634 1.4605)
				(arc
					(start -1.196594 1.460246)
					(mid -1.023469 1.382525)
					(end -0.9525 1.2065)
				)
				(arc
					(start -0.9525 1.2065)
					(mid -1.026895 1.026895)
					(end -1.2065 0.9525)
				)
				(arc
					(start -1.2065 0.9525)
					(mid -1.3843 1.025108)
					(end -1.4605 1.20142)
				)
				(xy -1.4605 0.6223)
				(arc
					(start -0.753618 0.6223)
					(mid -0.700385 0.700385)
					(end -0.6223 0.753618)
				)
			)
			(stroke
				(width 0)
				(type default)
			)
			(fill yes)
			(layer "F.Paste")
		)
		(fp_rect
			(start -3.54584 3.54584)
			(end 3.54584 -3.54584)
			(stroke
				(width 0)
				(type default)
			)
			(fill no)
			(layer "F.CrtYd")
		)
		(fp_line
			(start 2.500122 2.500122)
			(end 2.500122 -2.500122)
			(stroke
				(width 0.1)
				(type default)
			)
			(layer "F.Fab")
		)
		(fp_line
			(start 2.500122 -2.500122)
			(end -2.500122 -2.500122)
			(stroke
				(width 0.1)
				(type default)
			)
			(layer "F.Fab")
		)
		(fp_line
			(start -2.500122 2.500122)
			(end 2.500122 2.500122)
			(stroke
				(width 0.1)
				(type default)
			)
			(layer "F.Fab")
		)
		(fp_line
			(start -2.500122 -2.500122)
			(end -2.500122 2.500122)
			(stroke
				(width 0.1)
				(type default)
			)
			(layer "F.Fab")
		)
		(fp_poly
			(pts
				(arc
					(start -4.216654 -1.5748)
					(mid -3.200654 -1.5748)
					(end -4.216654 -1.5748)
				)
			)
			(stroke
				(width 0)
				(type default)
			)
			(fill yes)
			(layer "F.Fab")
		)
		(fp_text user "15"
			(at 4.1656 1.44145 0)
			(unlocked yes)
			(layer "F.SilkS")
			(effects
				(font
					(size 0.635 0.4064)
					(thickness 0.1524)
				)
			)
		)
		(fp_text user "21"
			(at 4.0386 -1.35255 0)
			(unlocked yes)
			(layer "F.SilkS")
			(effects
				(font
					(size 0.635 0.4064)
					(thickness 0.1524)
				)
			)
		)
		(fp_text user "14"
			(at 2.0066 4.10845 0)
			(unlocked yes)
			(layer "F.SilkS")
			(effects
				(font
					(size 0.635 0.4064)
					(thickness 0.1524)
				)
			)
		)
		(fp_text user "22"
			(at 1.6256 -3.76555 0)
			(unlocked yes)
			(layer "F.SilkS")
			(effects
				(font
					(size 0.635 0.4064)
					(thickness 0.1524)
				)
			)
		)
		(fp_text user "8"
			(at -1.5494 3.98145 0)
			(unlocked yes)
			(layer "F.SilkS")
			(effects
				(font
					(size 0.635 0.4064)
					(thickness 0.1524)
				)
			)
		)
		(fp_text user "28"
			(at -2.0574 -3.89255 0)
			(unlocked yes)
			(layer "F.SilkS")
			(effects
				(font
					(size 0.635 0.4064)
					(thickness 0.1524)
				)
			)
		)
		(fp_text user "7"
			(at -3.8354 2.12725 0)
			(unlocked yes)
			(layer "F.SilkS")
			(effects
				(font
					(size 0.635 0.4064)
					(thickness 0.1524)
				)
			)
		)
		(fp_text user "15"
			(at 4.20624 1.710182 0)
			(unlocked yes)
			(layer "F.Fab")
			(effects
				(font
					(size 0.7874 0.5842)
					(thickness 0.1524)
				)
			)
		)
		(fp_text user "21"
			(at 4.20624 -1.290066 0)
			(unlocked yes)
			(layer "F.Fab")
			(effects
				(font
					(size 0.7874 0.5842)
					(thickness 0.1524)
				)
			)
		)
		(fp_text user "14"
			(at 1.500124 4.239006 0)
			(unlocked yes)
			(layer "F.Fab")
			(effects
				(font
					(size 0.7874 0.5842)
					(thickness 0.1524)
				)
			)
		)
		(fp_text user "22"
			(at 1.500124 -3.792982 0)
			(unlocked yes)
			(layer "F.Fab")
			(effects
				(font
					(size 0.7874 0.5842)
					(thickness 0.1524)
				)
			)
		)
		(fp_text user "8"
			(at -1.500124 4.239006 0)
			(unlocked yes)
			(layer "F.Fab")
			(effects
				(font
					(size 0.7874 0.5842)
					(thickness 0.1524)
				)
			)
		)
		(fp_text user "28"
			(at -1.500124 -3.792982 0)
			(unlocked yes)
			(layer "F.Fab")
			(effects
				(font
					(size 0.7874 0.5842)
					(thickness 0.1524)
				)
			)
		)
		(fp_text user "7"
			(at -4.20624 1.710182 0)
			(unlocked yes)
			(layer "F.Fab")
			(effects
				(font
					(size 0.7874 0.5842)
					(thickness 0.1524)
				)
			)
		)
		(pad "1" smd rect
			(at -2.45364 -1.500124 180)
			(size 1.1684 0.3048)
			(layers "F.Cu" "F.Mask" "F.Paste")
			(net "RGB_LED_SHUTDOWN_N")
		)
		(pad "2" smd rect
			(at -2.41554 -0.999998 180)
			(size 1.2446 0.3048)
			(layers "F.Cu" "F.Mask" "F.Paste")
			(net "UNNAMED_14_IS32FL3207QWLA3TRQFN")
		)
		(pad "3" smd rect
			(at -2.41554 -0.500126 180)
			(size 1.2446 0.3048)
			(layers "F.Cu" "F.Mask" "F.Paste")
			(net "XP3R3V_FPGA")
		)
		(pad "4" smd rect
			(at -2.41554 0 180)
			(size 1.2446 0.3048)
			(layers "F.Cu" "F.Mask" "F.Paste")
			(net "SG")
		)
		(pad "5" smd rect
			(at -2.41554 0.500126 180)
			(size 1.2446 0.3048)
			(layers "F.Cu" "F.Mask" "F.Paste")
			(net "UNNAMED_14_IS32FL3207QWLA3TRQ_1")
		)
		(pad "6" smd rect
			(at -2.41554 0.999998 180)
			(size 1.2446 0.3048)
			(layers "F.Cu" "F.Mask" "F.Paste")
			(net "R_RGB_LED_I2C_SDA")
		)
		(pad "7" smd rect
			(at -2.45364 1.500124 180)
			(size 1.1684 0.3048)
			(layers "F.Cu" "F.Mask" "F.Paste")
			(net "R_RGB_LED_I2C_SCL")
		)
		(pad "8" smd rect
			(at -1.500124 2.45364 180)
			(size 0.3048 1.1684)
			(layers "F.Cu" "F.Mask" "F.Paste")
			(net "SMA1_LED_GREEN_N")
		)
		(pad "9" smd rect
			(at -0.999998 2.41554 180)
			(size 0.3048 1.2446)
			(layers "F.Cu" "F.Mask" "F.Paste")
			(net "SMA1_LED_RED_N")
		)
		(pad "10" smd rect
			(at -0.500126 2.41554 180)
			(size 0.3048 1.2446)
			(layers "F.Cu" "F.Mask" "F.Paste")
			(net "SMA1_LED_BLUE_N")
		)
		(pad "11" smd rect
			(at 0 2.41554 180)
			(size 0.3048 1.2446)
			(layers "F.Cu" "F.Mask" "F.Paste")
			(net "SG")
		)
		(pad "12" smd rect
			(at 0.500126 2.41554 180)
			(size 0.3048 1.2446)
			(layers "F.Cu" "F.Mask" "F.Paste")
			(net "SMA2_LED_GREEN_N")
		)
		(pad "13" smd rect
			(at 0.999998 2.41554 180)
			(size 0.3048 1.2446)
			(layers "F.Cu" "F.Mask" "F.Paste")
			(net "SMA2_LED_RED_N")
		)
		(pad "14" smd rect
			(at 1.500124 2.45364 180)
			(size 0.3048 1.1684)
			(layers "F.Cu" "F.Mask" "F.Paste")
			(net "SMA2_LED_BLUE_N")
		)
		(pad "15" smd rect
			(at 2.45364 1.500124 180)
			(size 1.1684 0.3048)
			(layers "F.Cu" "F.Mask" "F.Paste")
			(net "SMA3_LED_GREEN_N")
		)
		(pad "16" smd rect
			(at 2.41554 0.999998 180)
			(size 1.2446 0.3048)
			(layers "F.Cu" "F.Mask" "F.Paste")
			(net "SMA3_LED_RED_N")
		)
		(pad "17" smd rect
			(at 2.41554 0.500126 180)
			(size 1.2446 0.3048)
			(layers "F.Cu" "F.Mask" "F.Paste")
			(net "SMA3_LED_BLUE_N")
		)
		(pad "18" smd rect
			(at 2.41554 0 180)
			(size 1.2446 0.3048)
			(layers "F.Cu" "F.Mask" "F.Paste")
			(net "SG")
		)
		(pad "19" smd rect
			(at 2.41554 -0.500126 180)
			(size 1.2446 0.3048)
			(layers "F.Cu" "F.Mask" "F.Paste")
			(net "SMA4_LED_GREEN_N")
		)
		(pad "20" smd rect
			(at 2.41554 -0.999998 180)
			(size 1.2446 0.3048)
			(layers "F.Cu" "F.Mask" "F.Paste")
			(net "SMA4_LED_RED_N")
		)
		(pad "21" smd rect
			(at 2.45364 -1.500124 180)
			(size 1.1684 0.3048)
			(layers "F.Cu" "F.Mask" "F.Paste")
			(net "SMA4_LED_BLUE_N")
		)
		(pad "22" smd rect
			(at 1.500124 -2.45364 180)
			(size 0.3048 1.1684)
			(layers "F.Cu" "F.Mask" "F.Paste")
			(net "GPS_SMA_LED_GREEN_N")
		)
		(pad "23" smd rect
			(at 0.999998 -2.41554 180)
			(size 0.3048 1.2446)
			(layers "F.Cu" "F.Mask" "F.Paste")
			(net "GPS_SMA_LED_RED_N")
		)
		(pad "24" smd rect
			(at 0.500126 -2.41554 180)
			(size 0.3048 1.2446)
			(layers "F.Cu" "F.Mask" "F.Paste")
			(net "GPS_SMA_LED_BLUE_N")
		)
		(pad "25" smd rect
			(at 0 -2.41554 180)
			(size 0.3048 1.2446)
			(layers "F.Cu" "F.Mask" "F.Paste")
			(net "SG")
		)
		(pad "26" smd rect
			(at -0.500126 -2.41554 180)
			(size 0.3048 1.2446)
			(layers "F.Cu" "F.Mask" "F.Paste")
			(net "Net_785")
		)
		(pad "27" smd rect
			(at -0.999998 -2.41554 180)
			(size 0.3048 1.2446)
			(layers "F.Cu" "F.Mask" "F.Paste")
			(net "Net_784")
		)
		(pad "28" smd rect
			(at -1.500124 -2.45364 180)
			(size 0.3048 1.1684)
			(layers "F.Cu" "F.Mask" "F.Paste")
			(net "Net_783")
		)
		(pad "29" smd rect
			(at 0 0 180)
			(size 2.921 2.921)
			(layers "F.Cu" "F.Mask" "F.Paste")
			(net "SG")
		)
	)
	(footprint ""
		(layer "F.Cu")
		(at 13.0556 -25.4)
		(property "Reference" "C311"
			(at -2.6416 0.03937 0)
			(unlocked yes)
			(layer "F.SilkS")
			(effects
				(font
					(size 0.7874 0.5842)
					(thickness 0.1524)
				)
			)
		)
		(property "Value" "VAL*"
			(at 0.193548 2.13614 0)
			(unlocked yes)
			(layer "F.Fab")
			(hide yes)
			(effects
				(font
					(size 0.7874 0.5842)
					(thickness 0.1524)
				)
			)
		)
		(property "User Part Number" "PARTNUM*"
			(at 0.216154 4.185666 0)
			(unlocked yes)
			(layer "Cmts.User")
			(hide yes)
			(effects
				(font
					(size 0.7874 0.5842)
					(thickness 0.1524)
				)
			)
		)
		(property "Device Type" "CAPACITOR-G104-0A180-FJ,18PF,5%"
			(at 0.184404 1.180592 0)
			(unlocked yes)
			(layer "F.Fab")
			(hide yes)
			(effects
				(font
					(size 0.7874 0.5842)
					(thickness 0.1524)
				)
			)
		)
		(property "Tolerance" "TOL*"
			(at 0.216154 3.1496 0)
			(unlocked yes)
			(layer "Cmts.User")
			(hide yes)
			(effects
				(font
					(size 0.7874 0.5842)
					(thickness 0.1524)
				)
			)
		)
		(duplicate_pad_numbers_are_jumpers no)
		(fp_line
			(start -0.671322 -0.4445)
			(end 0.671322 -0.4445)
			(stroke
				(width 0.1)
				(type default)
			)
			(layer "F.SilkS")
		)
		(fp_line
			(start -0.671322 0.4445)
			(end -0.671322 -0.4445)
			(stroke
				(width 0.1)
				(type default)
			)
			(layer "F.SilkS")
		)
		(fp_line
			(start 0.671322 -0.4445)
			(end 0.671322 0.4445)
			(stroke
				(width 0.1)
				(type default)
			)
			(layer "F.SilkS")
		)
		(fp_line
			(start 0.671322 0.4445)
			(end -0.671322 0.4445)
			(stroke
				(width 0.1)
				(type default)
			)
			(layer "F.SilkS")
		)
		(fp_rect
			(start -0.671322 0.4445)
			(end 0.671322 -0.4445)
			(stroke
				(width 0)
				(type default)
			)
			(fill no)
			(layer "F.CrtYd")
		)
		(fp_line
			(start -0.31496 -0.1651)
			(end -0.31496 0.1651)
			(stroke
				(width 0.1)
				(type default)
			)
			(layer "F.Fab")
		)
		(fp_line
			(start -0.31496 0.1651)
			(end 0.31496 0.1651)
			(stroke
				(width 0.1)
				(type default)
			)
			(layer "F.Fab")
		)
		(fp_line
			(start 0.31496 -0.1651)
			(end -0.31496 -0.1651)
			(stroke
				(width 0.1)
				(type default)
			)
			(layer "F.Fab")
		)
		(fp_line
			(start 0.31496 0.1651)
			(end 0.31496 -0.1651)
			(stroke
				(width 0.1)
				(type default)
			)
			(layer "F.Fab")
		)
		(pad "1" smd rect
			(at -0.264922 0)
			(size 0.3048 0.381)
			(layers "F.Cu" "F.Mask" "F.Paste")
			(net "SG")
		)
		(pad "2" smd rect
			(at 0.264922 0)
			(size 0.3048 0.381)
			(layers "F.Cu" "F.Mask" "F.Paste")
			(net "UNNAMED_12_CAPACITOR_I321_2")
		)
		(zone
			(layer "F.Cu")
			(hatch none 0.5)
			(connect_pads
				(clearance 0)
			)
			(min_thickness 0.25)
			(keepout
				(tracks allowed)
				(vias not_allowed)
				(pads allowed)
				(copperpour not_allowed)
				(footprints allowed)
			)
			(placement
				(enabled no)
				(sheetname "")
			)
			(fill
				(thermal_gap 0.5)
				(thermal_bridge_width 0.5)
				(island_removal_mode 0)
			)
			(polygon
				(pts
					(xy 12.943078 -25.5905) (xy 12.943078 -25.2095) (xy 13.168122 -25.2095) (xy 13.168122 -25.5905)
				)
			)
		)
		(zone
			(layer "F.Cu")
			(hatch none 0.5)
			(connect_pads
				(clearance 0)
			)
			(min_thickness 0.25)
			(keepout
				(tracks not_allowed)
				(vias allowed)
				(pads allowed)
				(copperpour not_allowed)
				(footprints allowed)
			)
			(placement
				(enabled no)
				(sheetname "")
			)
			(fill
				(thermal_gap 0.5)
				(thermal_bridge_width 0.5)
				(island_removal_mode 0)
			)
			(polygon
				(pts
					(xy 12.943078 -25.2095) (xy 13.168122 -25.2095) (xy 13.168122 -25.5905) (xy 12.943078 -25.5905)
				)
			)
		)
	)
	(footprint ""
		(layer "F.Cu")
		(at 36.83 -125.603)
		(property "Reference" "SP75"
			(at 0 0 0)
			(layer "F.SilkS")
			(hide yes)
			(effects
				(font
					(size 1.27 1.27)
				)
			)
		)
		(property "Value" ""
			(at 0 0 0)
			(layer "F.Fab")
			(effects
				(font
					(size 1.27 1.27)
				)
			)
		)
		(duplicate_pad_numbers_are_jumpers no)
	)
	(footprint ""
		(layer "F.Cu")
		(at 108.966 -31.369 90)
		(property "Reference" "TP204"
			(at -1.17475 -0.6858 0)
			(unlocked yes)
			(layer "F.SilkS")
			(effects
				(font
					(size 0.635 0.4064)
					(thickness 0.1524)
				)
				(justify left)
			)
		)
		(property "Value" ""
			(at 0 0 90)
			(layer "F.Fab")
			(effects
				(font
					(size 1.27 1.27)
				)
			)
		)
		(property "Device Type" "TP_PIONT-TP010CT020B030_PTH-TPA"
			(at -1.341882 0.996696 90)
			(unlocked yes)
			(layer "F.Fab")
			(hide yes)
			(effects
				(font
					(size 0.7874 0.5842)
					(thickness 0.1524)
				)
				(justify left)
			)
		)
		(duplicate_pad_numbers_are_jumpers no)
		(fp_poly
			(pts
				(arc
					(start 0 0.889)
					(mid 0 -0.889)
					(end 0 0.889)
				)
			)
			(stroke
				(width 0)
				(type default)
			)
			(fill no)
			(layer "B.CrtYd")
		)
		(fp_poly
			(pts
				(arc
					(start 0 0.889)
					(mid 0 -0.889)
					(end 0 0.889)
				)
			)
			(stroke
				(width 0)
				(type default)
			)
			(fill no)
			(layer "F.CrtYd")
		)
		(pad "1" thru_hole circle
			(at 0 0 90)
			(size 0.508 0.508)
			(drill 0.254)
			(layers "*.Cu" "*.Mask")
			(remove_unused_layers no)
			(net "IO_L24N_35")
			(clearance 0.1016)
			(padstack
				(mode front_inner_back)
				(layer "Inner"
					(shape circle)
					(size 0.508 0.508)
					(clearance 0.1016)
				)
				(layer "B.Cu"
					(shape circle)
					(size 0.762 0.762)
					(clearance -0.0254)
				)
			)
		)
	)
	(footprint ""
		(layer "F.Cu")
		(at 103.9622 -64.2874 -90)
		(property "Reference" "R308"
			(at 2.6924 -0.85217 90)
			(unlocked yes)
			(layer "F.SilkS")
			(effects
				(font
					(size 0.7874 0.5842)
					(thickness 0.1524)
				)
			)
		)
		(property "Value" "VAL*"
			(at 0.02032 2.13233 270)
			(unlocked yes)
			(layer "F.Fab")
			(hide yes)
			(effects
				(font
					(size 0.7874 0.5842)
					(thickness 0.1524)
				)
			)
		)
		(property "Tolerance" "TOL*"
			(at 0.044704 3.05435 270)
			(unlocked yes)
			(layer "Cmts.User")
			(hide yes)
			(effects
				(font
					(size 0.7874 0.5842)
					(thickness 0.1524)
				)
			)
		)
		(property "User Part Number" "PARTNUM*"
			(at 0.02032 4.024884 270)
			(unlocked yes)
			(layer "Cmts.User")
			(hide yes)
			(effects
				(font
					(size 0.7874 0.5842)
					(thickness 0.1524)
				)
			)
		)
		(property "Device Type" "RESISTOR-G155-11002-01,10KOHM,A"
			(at 0.008382 1.210564 270)
			(unlocked yes)
			(layer "F.Fab")
			(hide yes)
			(effects
				(font
					(size 0.7874 0.5842)
					(thickness 0.1524)
				)
			)
		)
		(duplicate_pad_numbers_are_jumpers no)
		(fp_line
			(start -1.143 0.5588)
			(end 1.143 0.5588)
			(stroke
				(width 0.1)
				(type default)
			)
			(layer "F.SilkS")
		)
		(fp_line
			(start 1.143 0.5588)
			(end 1.143 -0.5588)
			(stroke
				(width 0.1)
				(type default)
			)
			(layer "F.SilkS")
		)
		(fp_line
			(start -1.143 -0.5588)
			(end -1.143 0.5588)
			(stroke
				(width 0.1)
				(type default)
			)
			(layer "F.SilkS")
		)
		(fp_line
			(start 1.143 -0.5588)
			(end -1.143 -0.5588)
			(stroke
				(width 0.1)
				(type default)
			)
			(layer "F.SilkS")
		)
		(fp_poly
			(pts
				(xy -1.143 0.5588) (xy 1.143 0.5588) (xy 1.143 -0.5588) (xy -1.143 -0.5588)
			)
			(stroke
				(width 0)
				(type default)
			)
			(fill no)
			(layer "F.CrtYd")
		)
		(fp_line
			(start -0.508 0.3048)
			(end 0.508 0.3048)
			(stroke
				(width 0.1)
				(type default)
			)
			(layer "F.Fab")
		)
		(fp_line
			(start 0.508 0.3048)
			(end 0.508 -0.3048)
			(stroke
				(width 0.1)
				(type default)
			)
			(layer "F.Fab")
		)
		(fp_line
			(start -0.508 -0.3048)
			(end -0.508 0.3048)
			(stroke
				(width 0.1)
				(type default)
			)
			(layer "F.Fab")
		)
		(fp_line
			(start 0.508 -0.3048)
			(end -0.508 -0.3048)
			(stroke
				(width 0.1)
				(type default)
			)
			(layer "F.Fab")
		)
		(pad "1" smd rect
			(at -0.5334 0 270)
			(size 0.7112 0.6096)
			(layers "F.Cu" "F.Mask" "F.Paste")
			(net "XP3R3V_FPGA")
		)
		(pad "2" smd rect
			(at 0.5334 0 270)
			(size 0.7112 0.6096)
			(layers "F.Cu" "F.Mask" "F.Paste")
			(net "FPGA_IO_5")
		)
		(zone
			(layer "F.Cu")
			(hatch none 0.5)
			(connect_pads
				(clearance 0)
			)
			(min_thickness 0.25)
			(keepout
				(tracks not_allowed)
				(vias allowed)
				(pads allowed)
				(copperpour not_allowed)
				(footprints allowed)
			)
			(placement
				(enabled no)
				(sheetname "")
			)
			(fill
				(thermal_gap 0.5)
				(thermal_bridge_width 0.5)
				(island_removal_mode 0)
			)
			(polygon
				(pts
					(xy 103.6574 -64.3636) (xy 103.6574 -64.2112) (xy 104.267 -64.2112) (xy 104.267 -64.3636)
				)
			)
		)
		(zone
			(layer "F.Cu")
			(hatch none 0.5)
			(connect_pads
				(clearance 0)
			)
			(min_thickness 0.25)
			(keepout
				(tracks allowed)
				(vias not_allowed)
				(pads allowed)
				(copperpour not_allowed)
				(footprints allowed)
			)
			(placement
				(enabled no)
				(sheetname "")
			)
			(fill
				(thermal_gap 0.5)
				(thermal_bridge_width 0.5)
				(island_removal_mode 0)
			)
			(polygon
				(pts
					(xy 103.6574 -64.3636) (xy 103.6574 -64.2112) (xy 104.267 -64.2112) (xy 104.267 -64.3636)
				)
			)
		)
	)
	(footprint ""
		(layer "F.Cu")
		(at 77.851 -43.053)
		(property "Reference" "TP51"
			(at -1.48463 2.8702 90)
			(unlocked yes)
			(layer "F.SilkS")
			(effects
				(font
					(size 0.7874 0.5842)
					(thickness 0.1524)
				)
				(justify left)
			)
		)
		(property "Value" ""
			(at 0 0 0)
			(layer "F.Fab")
			(effects
				(font
					(size 1.27 1.27)
				)
			)
		)
		(property "Device Type" "TP_PIONT-TP010CT020B030_PTH-TPA"
			(at -1.341882 0.996696 0)
			(unlocked yes)
			(layer "F.Fab")
			(hide yes)
			(effects
				(font
					(size 0.7874 0.5842)
					(thickness 0.000001)
				)
				(justify left)
			)
		)
		(duplicate_pad_numbers_are_jumpers no)
		(fp_poly
			(pts
				(arc
					(start 0.889 0)
					(mid -0.889 0)
					(end 0.889 0)
				)
			)
			(stroke
				(width 0)
				(type default)
			)
			(fill no)
			(layer "B.CrtYd")
		)
		(fp_poly
			(pts
				(arc
					(start 0.889 0)
					(mid -0.889 0)
					(end 0.889 0)
				)
			)
			(stroke
				(width 0)
				(type default)
			)
			(fill no)
			(layer "F.CrtYd")
		)
		(pad "1" thru_hole circle
			(at 0 0)
			(size 0.508 0.508)
			(drill 0.254)
			(layers "*.Cu" "*.Mask")
			(remove_unused_layers no)
			(net "MAC_ALARM")
			(clearance 0.1016)
			(padstack
				(mode front_inner_back)
				(layer "Inner"
					(shape circle)
					(size 0.508 0.508)
					(clearance 0.1016)
				)
				(layer "B.Cu"
					(shape circle)
					(size 0.762 0.762)
					(clearance -0.0254)
				)
			)
		)
	)
	(footprint ""
		(layer "F.Cu")
		(at 13.068808 -57.2516 90)
		(property "Reference" "R381"
			(at -0.3556 -2.361438 90)
			(unlocked yes)
			(layer "F.SilkS")
			(effects
				(font
					(size 0.7874 0.5842)
					(thickness 0.1524)
				)
			)
		)
		(property "Value" "VAL*"
			(at 0.02032 2.13233 90)
			(unlocked yes)
			(layer "F.Fab")
			(hide yes)
			(effects
				(font
					(size 0.7874 0.5842)
					(thickness 0.1524)
				)
			)
		)
		(property "Device Type" "RESISTOR-G155-14701-01,4.7KOHMA"
			(at 0.008382 1.210564 90)
			(unlocked yes)
			(layer "F.Fab")
			(hide yes)
			(effects
				(font
					(size 0.7874 0.5842)
					(thickness 0.1524)
				)
			)
		)
		(property "User Part Number" "PARTNUM*"
			(at 0.02032 4.024884 90)
			(unlocked yes)
			(layer "Cmts.User")
			(hide yes)
			(effects
				(font
					(size 0.7874 0.5842)
					(thickness 0.1524)
				)
			)
		)
		(property "Tolerance" "TOL*"
			(at 0.044704 3.05435 90)
			(unlocked yes)
			(layer "Cmts.User")
			(hide yes)
			(effects
				(font
					(size 0.7874 0.5842)
					(thickness 0.1524)
				)
			)
		)
		(duplicate_pad_numbers_are_jumpers no)
		(fp_line
			(start 1.143 -0.5588)
			(end -1.143 -0.5588)
			(stroke
				(width 0.1)
				(type default)
			)
			(layer "F.SilkS")
		)
		(fp_line
			(start -1.143 -0.5588)
			(end -1.143 0.5588)
			(stroke
				(width 0.1)
				(type default)
			)
			(layer "F.SilkS")
		)
		(fp_line
			(start 1.143 0.5588)
			(end 1.143 -0.5588)
			(stroke
				(width 0.1)
				(type default)
			)
			(layer "F.SilkS")
		)
		(fp_line
			(start -1.143 0.5588)
			(end 1.143 0.5588)
			(stroke
				(width 0.1)
				(type default)
			)
			(layer "F.SilkS")
		)
		(fp_rect
			(start 1.143 0.5588)
			(end -1.143 -0.5588)
			(stroke
				(width 0)
				(type default)
			)
			(fill no)
			(layer "F.CrtYd")
		)
		(fp_line
			(start 0.508 -0.3048)
			(end -0.508 -0.3048)
			(stroke
				(width 0.1)
				(type default)
			)
			(layer "F.Fab")
		)
		(fp_line
			(start -0.508 -0.3048)
			(end -0.508 0.3048)
			(stroke
				(width 0.1)
				(type default)
			)
			(layer "F.Fab")
		)
		(fp_line
			(start 0.508 0.3048)
			(end 0.508 -0.3048)
			(stroke
				(width 0.1)
				(type default)
			)
			(layer "F.Fab")
		)
		(fp_line
			(start -0.508 0.3048)
			(end 0.508 0.3048)
			(stroke
				(width 0.1)
				(type default)
			)
			(layer "F.Fab")
		)
		(pad "1" smd rect
			(at -0.5334 0 90)
			(size 0.7112 0.6096)
			(layers "F.Cu" "F.Mask" "F.Paste")
			(net "XP3R3V_FPGA")
		)
		(pad "2" smd rect
			(at 0.5334 0 90)
			(size 0.7112 0.6096)
			(layers "F.Cu" "F.Mask" "F.Paste")
			(net "SMA1_SIG_IN_BF_EN_N")
		)
		(zone
			(layer "F.Cu")
			(hatch none 0.5)
			(connect_pads
				(clearance 0)
			)
			(min_thickness 0.25)
			(keepout
				(tracks not_allowed)
				(vias allowed)
				(pads allowed)
				(copperpour not_allowed)
				(footprints allowed)
			)
			(placement
				(enabled no)
				(sheetname "")
			)
			(fill
				(thermal_gap 0.5)
				(thermal_bridge_width 0.5)
				(island_removal_mode 0)
			)
			(polygon
				(pts
					(xy 13.373608 -57.3278) (xy 12.764008 -57.3278) (xy 12.764008 -57.1754) (xy 13.373608 -57.1754)
				)
			)
		)
		(zone
			(layer "F.Cu")
			(hatch none 0.5)
			(connect_pads
				(clearance 0)
			)
			(min_thickness 0.25)
			(keepout
				(tracks allowed)
				(vias not_allowed)
				(pads allowed)
				(copperpour not_allowed)
				(footprints allowed)
			)
			(placement
				(enabled no)
				(sheetname "")
			)
			(fill
				(thermal_gap 0.5)
				(thermal_bridge_width 0.5)
				(island_removal_mode 0)
			)
			(polygon
				(pts
					(xy 13.373608 -57.3278) (xy 12.764008 -57.3278) (xy 12.764008 -57.1754) (xy 13.373608 -57.1754)
				)
			)
		)
	)
	(footprint ""
		(layer "F.Cu")
		(at 31.877 -98.679 180)
		(property "Reference" "Y2"
			(at 1.143 3.13563 0)
			(unlocked yes)
			(layer "F.SilkS")
			(effects
				(font
					(size 0.7874 0.5842)
					(thickness 0.1524)
				)
			)
		)
		(property "Value" ""
			(at 0 0 180)
			(layer "F.Fab")
			(effects
				(font
					(size 1.27 1.27)
				)
			)
		)
		(property "User Part Number" "PARTNUM*"
			(at 0.009906 4.56819 180)
			(unlocked yes)
			(layer "Cmts.User")
			(hide yes)
			(effects
				(font
					(size 0.7874 0.5842)
					(thickness 0.1524)
				)
			)
		)
		(property "Device Type" "XTAL_4-G131-10038-02"
			(at 0.009906 3.37439 180)
			(unlocked yes)
			(layer "F.Fab")
			(hide yes)
			(effects
				(font
					(size 0.7874 0.5842)
					(thickness 0.1524)
				)
			)
		)
		(duplicate_pad_numbers_are_jumpers no)
		(fp_line
			(start 2.052574 1.700784)
			(end -2.052574 1.700784)
			(stroke
				(width 0.1)
				(type default)
			)
			(layer "F.SilkS")
		)
		(fp_line
			(start 2.052574 -1.700784)
			(end 2.052574 1.700784)
			(stroke
				(width 0.1)
				(type default)
			)
			(layer "F.SilkS")
		)
		(fp_line
			(start -2.052574 1.700784)
			(end -2.052574 -1.700784)
			(stroke
				(width 0.1)
				(type default)
			)
			(layer "F.SilkS")
		)
		(fp_line
			(start -2.052574 -1.700784)
			(end 2.052574 -1.700784)
			(stroke
				(width 0.1)
				(type default)
			)
			(layer "F.SilkS")
		)
		(fp_poly
			(pts
				(arc
					(start -1.799336 2.413)
					(mid -1.037336 2.413)
					(end -1.799336 2.413)
				)
			)
			(stroke
				(width 0)
				(type default)
			)
			(fill yes)
			(layer "F.SilkS")
		)
		(fp_rect
			(start 2.306574 1.954784)
			(end -2.306574 -1.954784)
			(stroke
				(width 0)
				(type default)
			)
			(fill no)
			(layer "F.CrtYd")
		)
		(fp_line
			(start 1.649984 1.299972)
			(end -1.649984 1.299972)
			(stroke
				(width 0.1)
				(type default)
			)
			(layer "F.Fab")
		)
		(fp_line
			(start 1.649984 -1.299972)
			(end 1.649984 1.299972)
			(stroke
				(width 0.1)
				(type default)
			)
			(layer "F.Fab")
		)
		(fp_line
			(start -1.649984 1.299972)
			(end -1.649984 -1.299972)
			(stroke
				(width 0.1)
				(type default)
			)
			(layer "F.Fab")
		)
		(fp_line
			(start -1.649984 -1.299972)
			(end 1.649984 -1.299972)
			(stroke
				(width 0.1)
				(type default)
			)
			(layer "F.Fab")
		)
		(fp_poly
			(pts
				(arc
					(start -1.799336 2.032)
					(mid -1.037336 2.032)
					(end -1.799336 2.032)
				)
			)
			(stroke
				(width 0)
				(type default)
			)
			(fill yes)
			(layer "F.Fab")
		)
		(fp_text user "2"
			(at 2.667 2.62763 0)
			(unlocked yes)
			(layer "F.SilkS")
			(effects
				(font
					(size 0.7874 0.5842)
					(thickness 0.1524)
				)
			)
		)
		(fp_text user "3"
			(at 2.54 -2.07137 0)
			(unlocked yes)
			(layer "F.SilkS")
			(effects
				(font
					(size 0.7874 0.5842)
					(thickness 0.1524)
				)
			)
		)
		(fp_text user "4"
			(at -2.667 -2.07137 0)
			(unlocked yes)
			(layer "F.SilkS")
			(effects
				(font
					(size 0.7874 0.5842)
					(thickness 0.1524)
				)
			)
		)
		(fp_text user "3"
			(at 2.286 -1.43637 0)
			(unlocked yes)
			(layer "F.Fab")
			(effects
				(font
					(size 0.7874 0.5842)
					(thickness 0.1524)
				)
			)
		)
		(fp_text user "2"
			(at 2.159 1.99263 0)
			(unlocked yes)
			(layer "F.Fab")
			(effects
				(font
					(size 0.7874 0.5842)
					(thickness 0.1524)
				)
			)
		)
		(fp_text user "4"
			(at -2.413 -1.30937 0)
			(unlocked yes)
			(layer "F.Fab")
			(effects
				(font
					(size 0.7874 0.5842)
					(thickness 0.1524)
				)
			)
		)
		(pad "1" smd rect
			(at -1.100074 0.849884 180)
			(size 1.397 1.1938)
			(layers "F.Cu" "F.Mask" "F.Paste")
			(net "UNNAMED_524_CAPACITOR_I7_2")
		)
		(pad "2" smd rect
			(at 1.100074 0.849884 180)
			(size 1.397 1.1938)
			(layers "F.Cu" "F.Mask" "F.Paste")
			(net "SG")
		)
		(pad "3" smd rect
			(at 1.100074 -0.849884 180)
			(size 1.397 1.1938)
			(layers "F.Cu" "F.Mask" "F.Paste")
			(net "UNNAMED_524_CAPACITOR_I10_2")
		)
		(pad "4" smd rect
			(at -1.100074 -0.849884 180)
			(size 1.397 1.1938)
			(layers "F.Cu" "F.Mask" "F.Paste")
			(net "SG")
		)
		(zone
			(layer "F.Cu")
			(hatch none 0.5)
			(connect_pads
				(clearance 0)
			)
			(min_thickness 0.25)
			(keepout
				(tracks allowed)
				(vias not_allowed)
				(pads allowed)
				(copperpour not_allowed)
				(footprints allowed)
			)
			(placement
				(enabled no)
				(sheetname "")
			)
			(fill
				(thermal_gap 0.5)
				(thermal_bridge_width 0.5)
				(island_removal_mode 0)
			)
			(polygon
				(pts
					(xy 32.278574 -99.978972) (xy 32.278574 -98.931984) (xy 33.526984 -98.931984) (xy 33.526984 -98.426016)
					(xy 32.278574 -98.426016) (xy 32.278574 -97.379028) (xy 31.475426 -97.379028) (xy 31.475426 -98.426016)
					(xy 30.227016 -98.426016) (xy 30.227016 -98.931984) (xy 31.475426 -98.931984) (xy 31.475426 -99.978972)
				)
			)
		)
	)
	(footprint ""
		(layer "F.Cu")
		(at 25.7556 -17.5514)
		(property "Reference" "U7"
			(at 0.94742 -2.52603 0)
			(unlocked yes)
			(layer "F.SilkS")
			(effects
				(font
					(size 0.7874 0.5842)
					(thickness 0.1524)
				)
			)
		)
		(property "Value" ""
			(at 0 0 0)
			(layer "F.Fab")
			(effects
				(font
					(size 1.27 1.27)
				)
			)
		)
		(property "Device Type" "AT24MAC402_SOT23_5-A221-00002-A"
			(at 0.0508 2.549906 0)
			(unlocked yes)
			(layer "F.Fab")
			(hide yes)
			(effects
				(font
					(size 0.7874 0.5842)
					(thickness 0.1524)
				)
			)
		)
		(property "User Part Number" "PARTNUM*"
			(at 0.0508 3.515106 0)
			(unlocked yes)
			(layer "Cmts.User")
			(hide yes)
			(effects
				(font
					(size 0.7874 0.5842)
					(thickness 0.1524)
				)
			)
		)
		(duplicate_pad_numbers_are_jumpers no)
		(fp_line
			(start -2.286 -1.45796)
			(end -1.0541 -1.45796)
			(stroke
				(width 0.1)
				(type default)
			)
			(layer "F.SilkS")
		)
		(fp_line
			(start -2.286 1.45796)
			(end -2.286 -1.45796)
			(stroke
				(width 0.1)
				(type default)
			)
			(layer "F.SilkS")
		)
		(fp_line
			(start -1.0541 -1.704086)
			(end 1.0541 -1.704086)
			(stroke
				(width 0.1)
				(type default)
			)
			(layer "F.SilkS")
		)
		(fp_line
			(start -1.0541 -1.45796)
			(end -1.0541 -1.704086)
			(stroke
				(width 0.1)
				(type default)
			)
			(layer "F.SilkS")
		)
		(fp_line
			(start -1.0541 1.45796)
			(end -2.286 1.45796)
			(stroke
				(width 0.1)
				(type default)
			)
			(layer "F.SilkS")
		)
		(fp_line
			(start -1.0541 1.704086)
			(end -1.0541 1.45796)
			(stroke
				(width 0.1)
				(type default)
			)
			(layer "F.SilkS")
		)
		(fp_line
			(start 1.0541 -1.704086)
			(end 1.0541 -1.45796)
			(stroke
				(width 0.1)
				(type default)
			)
			(layer "F.SilkS")
		)
		(fp_line
			(start 1.0541 -1.45796)
			(end 2.286 -1.45796)
			(stroke
				(width 0.1)
				(type default)
			)
			(layer "F.SilkS")
		)
		(fp_line
			(start 1.0541 -0.44196)
			(end 1.0541 0.44196)
			(stroke
				(width 0.1)
				(type default)
			)
			(layer "F.SilkS")
		)
		(fp_line
			(start 1.0541 0.44196)
			(end 2.286 0.44196)
			(stroke
				(width 0.1)
				(type default)
			)
			(layer "F.SilkS")
		)
		(fp_line
			(start 1.0541 1.45796)
			(end 1.0541 1.704086)
			(stroke
				(width 0.1)
				(type default)
			)
			(layer "F.SilkS")
		)
		(fp_line
			(start 1.0541 1.704086)
			(end -1.0541 1.704086)
			(stroke
				(width 0.1)
				(type default)
			)
			(layer "F.SilkS")
		)
		(fp_line
			(start 2.286 -1.45796)
			(end 2.286 -0.44196)
			(stroke
				(width 0.1)
				(type default)
			)
			(layer "F.SilkS")
		)
		(fp_line
			(start 2.286 -0.44196)
			(end 1.0541 -0.44196)
			(stroke
				(width 0.1)
				(type default)
			)
			(layer "F.SilkS")
		)
		(fp_line
			(start 2.286 0.44196)
			(end 2.286 1.45796)
			(stroke
				(width 0.1)
				(type default)
			)
			(layer "F.SilkS")
		)
		(fp_line
			(start 2.286 1.45796)
			(end 1.0541 1.45796)
			(stroke
				(width 0.1)
				(type default)
			)
			(layer "F.SilkS")
		)
		(fp_poly
			(pts
				(arc
					(start -1.59258 -1.9304)
					(mid -2.35458 -1.9304)
					(end -1.59258 -1.9304)
				)
			)
			(stroke
				(width 0)
				(type default)
			)
			(fill yes)
			(layer "F.SilkS")
		)
		(fp_rect
			(start -2.54 1.9558)
			(end 2.54 -1.9558)
			(stroke
				(width 0)
				(type default)
			)
			(fill no)
			(layer "F.CrtYd")
		)
		(fp_line
			(start -1.500124 -1.199896)
			(end -0.700024 -1.199896)
			(stroke
				(width 0.1)
				(type default)
			)
			(layer "F.Fab")
		)
		(fp_line
			(start -1.500124 -0.700024)
			(end -1.500124 -1.199896)
			(stroke
				(width 0.1)
				(type default)
			)
			(layer "F.Fab")
		)
		(fp_line
			(start -1.500124 -0.249936)
			(end -0.700024 -0.249936)
			(stroke
				(width 0.1)
				(type default)
			)
			(layer "F.Fab")
		)
		(fp_line
			(start -1.500124 0.249936)
			(end -1.500124 -0.249936)
			(stroke
				(width 0.1)
				(type default)
			)
			(layer "F.Fab")
		)
		(fp_line
			(start -1.500124 0.700024)
			(end -0.700024 0.700024)
			(stroke
				(width 0.1)
				(type default)
			)
			(layer "F.Fab")
		)
		(fp_line
			(start -1.500124 1.199896)
			(end -1.500124 0.700024)
			(stroke
				(width 0.1)
				(type default)
			)
			(layer "F.Fab")
		)
		(fp_line
			(start -0.8001 -1.450086)
			(end 0.8001 -1.450086)
			(stroke
				(width 0.1)
				(type default)
			)
			(layer "F.Fab")
		)
		(fp_line
			(start -0.8001 -1.199896)
			(end -0.8001 -1.450086)
			(stroke
				(width 0.1)
				(type default)
			)
			(layer "F.Fab")
		)
		(fp_line
			(start -0.8001 -0.700024)
			(end -0.8001 -0.249936)
			(stroke
				(width 0.1)
				(type default)
			)
			(layer "F.Fab")
		)
		(fp_line
			(start -0.8001 0.249936)
			(end -0.8001 0.700024)
			(stroke
				(width 0.1)
				(type default)
			)
			(layer "F.Fab")
		)
		(fp_line
			(start -0.8001 1.199896)
			(end -0.8001 1.450086)
			(stroke
				(width 0.1)
				(type default)
			)
			(layer "F.Fab")
		)
		(fp_line
			(start -0.8001 1.450086)
			(end -0.599948 1.249934)
			(stroke
				(width 0.1)
				(type default)
			)
			(layer "F.Fab")
		)
		(fp_line
			(start -0.8001 1.450086)
			(end 0.8001 1.450086)
			(stroke
				(width 0.1)
				(type default)
			)
			(layer "F.Fab")
		)
		(fp_line
			(start -0.700024 -1.199896)
			(end -0.700024 -0.700024)
			(stroke
				(width 0.1)
				(type default)
			)
			(layer "F.Fab")
		)
		(fp_line
			(start -0.700024 -0.700024)
			(end -1.500124 -0.700024)
			(stroke
				(width 0.1)
				(type default)
			)
			(layer "F.Fab")
		)
		(fp_line
			(start -0.700024 -0.249936)
			(end -0.700024 0.249936)
			(stroke
				(width 0.1)
				(type default)
			)
			(layer "F.Fab")
		)
		(fp_line
			(start -0.700024 0.249936)
			(end -1.500124 0.249936)
			(stroke
				(width 0.1)
				(type default)
			)
			(layer "F.Fab")
		)
		(fp_line
			(start -0.700024 0.700024)
			(end -0.700024 1.199896)
			(stroke
				(width 0.1)
				(type default)
			)
			(layer "F.Fab")
		)
		(fp_line
			(start -0.700024 1.199896)
			(end -1.500124 1.199896)
			(stroke
				(width 0.1)
				(type default)
			)
			(layer "F.Fab")
		)
		(fp_line
			(start -0.599948 -1.249934)
			(end -0.8001 -1.450086)
			(stroke
				(width 0.1)
				(type default)
			)
			(layer "F.Fab")
		)
		(fp_line
			(start -0.599948 -1.249934)
			(end 0.599948 -1.249934)
			(stroke
				(width 0.1)
				(type default)
			)
			(layer "F.Fab")
		)
		(fp_line
			(start -0.599948 1.249934)
			(end -0.599948 -1.249934)
			(stroke
				(width 0.1)
				(type default)
			)
			(layer "F.Fab")
		)
		(fp_line
			(start 0.599948 -1.249934)
			(end 0.599948 1.249934)
			(stroke
				(width 0.1)
				(type default)
			)
			(layer "F.Fab")
		)
		(fp_line
			(start 0.599948 -1.249934)
			(end 0.8001 -1.450086)
			(stroke
				(width 0.1)
				(type default)
			)
			(layer "F.Fab")
		)
		(fp_line
			(start 0.599948 1.249934)
			(end -0.599948 1.249934)
			(stroke
				(width 0.1)
				(type default)
			)
			(layer "F.Fab")
		)
		(fp_line
			(start 0.700024 -1.199896)
			(end 1.500124 -1.199896)
			(stroke
				(width 0.1)
				(type default)
			)
			(layer "F.Fab")
		)
		(fp_line
			(start 0.700024 -0.700024)
			(end 0.700024 -1.199896)
			(stroke
				(width 0.1)
				(type default)
			)
			(layer "F.Fab")
		)
		(fp_line
			(start 0.700024 0.700024)
			(end 1.500124 0.700024)
			(stroke
				(width 0.1)
				(type default)
			)
			(layer "F.Fab")
		)
		(fp_line
			(start 0.700024 1.199896)
			(end 0.700024 0.700024)
			(stroke
				(width 0.1)
				(type default)
			)
			(layer "F.Fab")
		)
		(fp_line
			(start 0.8001 -1.450086)
			(end 0.8001 -1.199896)
			(stroke
				(width 0.1)
				(type default)
			)
			(layer "F.Fab")
		)
		(fp_line
			(start 0.8001 -0.700024)
			(end 0.8001 0.700024)
			(stroke
				(width 0.1)
				(type default)
			)
			(layer "F.Fab")
		)
		(fp_line
			(start 0.8001 1.450086)
			(end 0.599948 1.249934)
			(stroke
				(width 0.1)
				(type default)
			)
			(layer "F.Fab")
		)
		(fp_line
			(start 0.8001 1.450086)
			(end 0.8001 1.199896)
			(stroke
				(width 0.1)
				(type default)
			)
			(layer "F.Fab")
		)
		(fp_line
			(start 1.500124 -1.199896)
			(end 1.500124 -0.700024)
			(stroke
				(width 0.1)
				(type default)
			)
			(layer "F.Fab")
		)
		(fp_line
			(start 1.500124 -0.700024)
			(end 0.700024 -0.700024)
			(stroke
				(width 0.1)
				(type default)
			)
			(layer "F.Fab")
		)
		(fp_line
			(start 1.500124 0.700024)
			(end 1.500124 1.199896)
			(stroke
				(width 0.1)
				(type default)
			)
			(layer "F.Fab")
		)
		(fp_line
			(start 1.500124 1.199896)
			(end 0.700024 1.199896)
			(stroke
				(width 0.1)
				(type default)
			)
			(layer "F.Fab")
		)
		(fp_poly
			(pts
				(arc
					(start -0.200152 -0.94996)
					(mid -0.499872 -0.94996)
					(end -0.200152 -0.94996)
				)
			)
			(stroke
				(width 0)
				(type default)
			)
			(fill yes)
			(layer "F.Fab")
		)
		(fp_text user "3"
			(at -1.71958 2.17297 0)
			(unlocked yes)
			(layer "F.SilkS")
			(effects
				(font
					(size 0.7874 0.5842)
					(thickness 0.1524)
				)
			)
		)
		(fp_text user "5"
			(at 2.6924 -1.84023 0)
			(unlocked yes)
			(layer "F.SilkS")
			(effects
				(font
					(size 0.7874 0.5842)
					(thickness 0.1524)
				)
			)
		)
		(fp_text user "4"
			(at 2.9464 1.58877 0)
			(unlocked yes)
			(layer "F.SilkS")
			(effects
				(font
					(size 0.7874 0.5842)
					(thickness 0.1524)
				)
			)
		)
		(fp_text user "3"
			(at -2.794 0.91567 0)
			(unlocked yes)
			(layer "F.Fab")
			(effects
				(font
					(size 0.7874 0.5842)
					(thickness 0.1524)
				)
			)
		)
		(fp_text user "5"
			(at 2.032 -0.83693 0)
			(unlocked yes)
			(layer "F.Fab")
			(effects
				(font
					(size 0.7874 0.5842)
					(thickness 0.1524)
				)
			)
		)
		(fp_text user "4"
			(at 2.032 1.09347 0)
			(unlocked yes)
			(layer "F.Fab")
			(effects
				(font
					(size 0.7874 0.5842)
					(thickness 0.1524)
				)
			)
		)
		(pad "1" smd rect
			(at -1.4351 -0.94996 90)
			(size 0.508 1.1938)
			(layers "F.Cu" "F.Mask" "F.Paste")
			(net "EEPROM_SCL")
		)
		(pad "2" smd rect
			(at -1.4351 0 90)
			(size 0.508 1.1938)
			(layers "F.Cu" "F.Mask" "F.Paste")
			(net "SG")
		)
		(pad "3" smd rect
			(at -1.4351 0.94996 90)
			(size 0.508 1.1938)
			(layers "F.Cu" "F.Mask" "F.Paste")
			(net "PRI_EEPROM_SDA")
		)
		(pad "4" smd rect
			(at 1.4351 0.94996 90)
			(size 0.508 1.1938)
			(layers "F.Cu" "F.Mask" "F.Paste")
			(net "XP3R3V_FPGA")
		)
		(pad "5" smd rect
			(at 1.4351 -0.94996 90)
			(size 0.508 1.1938)
			(layers "F.Cu" "F.Mask" "F.Paste")
			(net "SN_EEPROM_WP")
		)
	)
	(footprint ""
		(layer "F.Cu")
		(at 11.557 -30.4546 -90)
		(property "Reference" "R496"
			(at -0.1524 2.11963 90)
			(unlocked yes)
			(layer "F.SilkS")
			(effects
				(font
					(size 0.7874 0.5842)
					(thickness 0.1524)
				)
			)
		)
		(property "Value" "VAL*"
			(at 0.02032 2.13233 270)
			(unlocked yes)
			(layer "F.Fab")
			(hide yes)
			(effects
				(font
					(size 0.7874 0.5842)
					(thickness 0.1524)
				)
			)
		)
		(property "Tolerance" "TOL*"
			(at 0.044704 3.05435 270)
			(unlocked yes)
			(layer "Cmts.User")
			(hide yes)
			(effects
				(font
					(size 0.7874 0.5842)
					(thickness 0.1524)
				)
			)
		)
		(property "User Part Number" "PARTNUM*"
			(at 0.02032 4.024884 270)
			(unlocked yes)
			(layer "Cmts.User")
			(hide yes)
			(effects
				(font
					(size 0.7874 0.5842)
					(thickness 0.1524)
				)
			)
		)
		(property "Device Type" "RESISTOR-G155-11004-01,1MOHM,1%"
			(at 0.008382 1.210564 270)
			(unlocked yes)
			(layer "F.Fab")
			(hide yes)
			(effects
				(font
					(size 0.7874 0.5842)
					(thickness 0.1524)
				)
			)
		)
		(duplicate_pad_numbers_are_jumpers no)
		(fp_line
			(start -1.143 0.5588)
			(end 1.143 0.5588)
			(stroke
				(width 0.1)
				(type default)
			)
			(layer "F.SilkS")
		)
		(fp_line
			(start 1.143 0.5588)
			(end 1.143 -0.5588)
			(stroke
				(width 0.1)
				(type default)
			)
			(layer "F.SilkS")
		)
		(fp_line
			(start -1.143 -0.5588)
			(end -1.143 0.5588)
			(stroke
				(width 0.1)
				(type default)
			)
			(layer "F.SilkS")
		)
		(fp_line
			(start 1.143 -0.5588)
			(end -1.143 -0.5588)
			(stroke
				(width 0.1)
				(type default)
			)
			(layer "F.SilkS")
		)
		(fp_poly
			(pts
				(xy -1.143 0.5588) (xy 1.143 0.5588) (xy 1.143 -0.5588) (xy -1.143 -0.5588)
			)
			(stroke
				(width 0)
				(type default)
			)
			(fill no)
			(layer "F.CrtYd")
		)
		(fp_line
			(start -0.508 0.3048)
			(end 0.508 0.3048)
			(stroke
				(width 0.1)
				(type default)
			)
			(layer "F.Fab")
		)
		(fp_line
			(start 0.508 0.3048)
			(end 0.508 -0.3048)
			(stroke
				(width 0.1)
				(type default)
			)
			(layer "F.Fab")
		)
		(fp_line
			(start -0.508 -0.3048)
			(end -0.508 0.3048)
			(stroke
				(width 0.1)
				(type default)
			)
			(layer "F.Fab")
		)
		(fp_line
			(start 0.508 -0.3048)
			(end -0.508 -0.3048)
			(stroke
				(width 0.1)
				(type default)
			)
			(layer "F.Fab")
		)
		(pad "1" smd rect
			(at -0.5334 0 270)
			(size 0.7112 0.6096)
			(layers "F.Cu" "F.Mask" "F.Paste")
			(net "SG")
		)
		(pad "2" smd rect
			(at 0.5334 0 270)
			(size 0.7112 0.6096)
			(layers "F.Cu" "F.Mask" "F.Paste")
			(net "BF_SMA3_SIG_IO_CONN")
		)
		(zone
			(layer "F.Cu")
			(hatch none 0.5)
			(connect_pads
				(clearance 0)
			)
			(min_thickness 0.25)
			(keepout
				(tracks not_allowed)
				(vias allowed)
				(pads allowed)
				(copperpour not_allowed)
				(footprints allowed)
			)
			(placement
				(enabled no)
				(sheetname "")
			)
			(fill
				(thermal_gap 0.5)
				(thermal_bridge_width 0.5)
				(island_removal_mode 0)
			)
			(polygon
				(pts
					(xy 11.2522 -30.5308) (xy 11.2522 -30.3784) (xy 11.8618 -30.3784) (xy 11.8618 -30.5308)
				)
			)
		)
		(zone
			(layer "F.Cu")
			(hatch none 0.5)
			(connect_pads
				(clearance 0)
			)
			(min_thickness 0.25)
			(keepout
				(tracks allowed)
				(vias not_allowed)
				(pads allowed)
				(copperpour not_allowed)
				(footprints allowed)
			)
			(placement
				(enabled no)
				(sheetname "")
			)
			(fill
				(thermal_gap 0.5)
				(thermal_bridge_width 0.5)
				(island_removal_mode 0)
			)
			(polygon
				(pts
					(xy 11.2522 -30.5308) (xy 11.2522 -30.3784) (xy 11.8618 -30.3784) (xy 11.8618 -30.5308)
				)
			)
		)
	)
	(footprint ""
		(layer "F.Cu")
		(at 141.05001 -104.350058 -90)
		(property "Reference" "DS7"
			(at 0.972058 1.57226 90)
			(unlocked yes)
			(layer "F.SilkS")
			(effects
				(font
					(size 0.635 0.4064)
					(thickness 0.1524)
				)
			)
		)
		(property "Value" ""
			(at 0 0 270)
			(layer "F.Fab")
			(effects
				(font
					(size 1.27 1.27)
				)
			)
		)
		(property "Device Type" "OPTICAL-G170-10143-01"
			(at 0.1778 1.483081 270)
			(unlocked yes)
			(layer "F.Fab")
			(hide yes)
			(effects
				(font
					(size 0.786892 0.583946)
					(thickness 0.000001)
				)
			)
		)
		(property "User Part Number" "PARTNUM*"
			(at 0.1778 2.422881 270)
			(unlocked yes)
			(layer "Cmts.User")
			(hide yes)
			(effects
				(font
					(size 0.786892 0.583946)
					(thickness 0.000001)
				)
			)
		)
		(duplicate_pad_numbers_are_jumpers no)
		(fp_line
			(start -1.0668 1.2192)
			(end -2.3368 1.2192)
			(stroke
				(width 0.1)
				(type default)
			)
			(layer "F.SilkS")
		)
		(fp_line
			(start -1.397508 0.704088)
			(end -1.397508 -0.704088)
			(stroke
				(width 0.1)
				(type default)
			)
			(layer "F.SilkS")
		)
		(fp_line
			(start 1.397508 0.704088)
			(end -1.397508 0.704088)
			(stroke
				(width 0.1)
				(type default)
			)
			(layer "F.SilkS")
		)
		(fp_line
			(start -1.7018 0.5842)
			(end -1.7018 1.8542)
			(stroke
				(width 0.1)
				(type default)
			)
			(layer "F.SilkS")
		)
		(fp_line
			(start -1.397508 -0.704088)
			(end 1.397508 -0.704088)
			(stroke
				(width 0.1)
				(type default)
			)
			(layer "F.SilkS")
		)
		(fp_line
			(start 1.397508 -0.704088)
			(end 1.397508 0.704088)
			(stroke
				(width 0.1)
				(type default)
			)
			(layer "F.SilkS")
		)
		(fp_rect
			(start 1.397508 -0.704088)
			(end 1.905508 0.704088)
			(stroke
				(width 0)
				(type default)
			)
			(fill yes)
			(layer "F.SilkS")
		)
		(fp_rect
			(start -1.651508 -0.958088)
			(end 1.905508 0.958088)
			(stroke
				(width 0)
				(type default)
			)
			(fill no)
			(layer "F.CrtYd")
		)
		(fp_line
			(start -0.9398 1.4732)
			(end -2.2098 1.4732)
			(stroke
				(width 0.1)
				(type default)
			)
			(layer "F.Fab")
		)
		(fp_line
			(start -1.5748 0.8382)
			(end -1.5748 2.1082)
			(stroke
				(width 0.1)
				(type default)
			)
			(layer "F.Fab")
		)
		(fp_line
			(start -0.850138 0.450088)
			(end 0.850138 0.450088)
			(stroke
				(width 0.1)
				(type default)
			)
			(layer "F.Fab")
		)
		(fp_line
			(start 0.850138 0.450088)
			(end 0.850138 -0.450088)
			(stroke
				(width 0.1)
				(type default)
			)
			(layer "F.Fab")
		)
		(fp_line
			(start -0.850138 -0.450088)
			(end -0.850138 0.450088)
			(stroke
				(width 0.1)
				(type default)
			)
			(layer "F.Fab")
		)
		(fp_line
			(start 0.850138 -0.450088)
			(end -0.850138 -0.450088)
			(stroke
				(width 0.1)
				(type default)
			)
			(layer "F.Fab")
		)
		(fp_rect
			(start 0.342138 -0.450088)
			(end 0.850138 0.450088)
			(stroke
				(width 0)
				(type default)
			)
			(fill yes)
			(layer "F.Fab")
		)
		(fp_text user "A"
			(at -0.647192 1.47701 0)
			(unlocked yes)
			(layer "F.SilkS")
			(effects
				(font
					(size 0.635 0.4064)
					(thickness 0.1524)
				)
			)
		)
		(fp_text user "C"
			(at 2.400808 0.71501 0)
			(unlocked yes)
			(layer "F.SilkS")
			(effects
				(font
					(size 0.635 0.4064)
					(thickness 0.1524)
				)
			)
		)
		(fp_text user "A"
			(at -0.766572 0.96901 0)
			(unlocked yes)
			(layer "F.Fab")
			(effects
				(font
					(size 0.7874 0.5842)
					(thickness 0.1524)
				)
			)
		)
		(fp_text user "C"
			(at 1.646428 0.96901 0)
			(unlocked yes)
			(layer "F.Fab")
			(effects
				(font
					(size 0.7874 0.5842)
					(thickness 0.1524)
				)
			)
		)
		(pad "A" smd rect
			(at -0.749808 0 270)
			(size 0.7874 0.7874)
			(layers "F.Cu" "F.Mask" "F.Paste")
			(net "UNNAMED_14_OPTICAL_I141_A")
		)
		(pad "C" smd rect
			(at 0.749808 0 270)
			(size 0.7874 0.7874)
			(layers "F.Cu" "F.Mask" "F.Paste")
			(net "SG")
		)
	)
	(footprint ""
		(layer "F.Cu")
		(at 5.969 -54.356 90)
		(property "Reference" "CR4"
			(at 0.381 2.57937 90)
			(unlocked yes)
			(layer "F.SilkS")
			(effects
				(font
					(size 0.7874 0.5842)
					(thickness 0.1524)
				)
			)
		)
		(property "Value" ""
			(at 0 0 90)
			(layer "F.Fab")
			(effects
				(font
					(size 1.27 1.27)
				)
			)
		)
		(property "Device Type" "DIODE_4_V1-G122-10123-01"
			(at 0.254 2.702306 90)
			(unlocked yes)
			(layer "F.Fab")
			(hide yes)
			(effects
				(font
					(size 0.7874 0.5842)
					(thickness 0.1524)
				)
			)
		)
		(property "User Part Number" "PARTNUM*"
			(at 0.254 3.718306 90)
			(unlocked yes)
			(layer "Cmts.User")
			(hide yes)
			(effects
				(font
					(size 0.7874 0.5842)
					(thickness 0.1524)
				)
			)
		)
		(duplicate_pad_numbers_are_jumpers no)
		(fp_line
			(start 2.0828 -1.7018)
			(end 2.0828 1.7018)
			(stroke
				(width 0.1)
				(type default)
			)
			(layer "F.SilkS")
		)
		(fp_line
			(start -2.0828 -1.7018)
			(end 2.0828 -1.7018)
			(stroke
				(width 0.1)
				(type default)
			)
			(layer "F.SilkS")
		)
		(fp_line
			(start 2.0828 1.7018)
			(end -2.0828 1.7018)
			(stroke
				(width 0.1)
				(type default)
			)
			(layer "F.SilkS")
		)
		(fp_line
			(start -2.0828 1.7018)
			(end -2.0828 -1.7018)
			(stroke
				(width 0.1)
				(type default)
			)
			(layer "F.SilkS")
		)
		(fp_poly
			(pts
				(arc
					(start -2.6162 -0.508)
					(mid -2.6162 -1.27)
					(end -2.6162 -0.508)
				)
			)
			(stroke
				(width 0)
				(type default)
			)
			(fill yes)
			(layer "F.SilkS")
		)
		(fp_rect
			(start -2.3368 -1.9304)
			(end 2.3368 1.9304)
			(stroke
				(width 0)
				(type default)
			)
			(fill no)
			(layer "F.CrtYd")
		)
		(fp_line
			(start 0.6477 -1.42875)
			(end 0.6477 1.42875)
			(stroke
				(width 0.1)
				(type default)
			)
			(layer "F.Fab")
		)
		(fp_line
			(start -0.6477 -1.42875)
			(end 0.6477 -1.42875)
			(stroke
				(width 0.1)
				(type default)
			)
			(layer "F.Fab")
		)
		(fp_line
			(start 1.143 -1.1811)
			(end 1.143 -0.7239)
			(stroke
				(width 0.1)
				(type default)
			)
			(layer "F.Fab")
		)
		(fp_line
			(start 0.6477 -1.1811)
			(end 1.143 -1.1811)
			(stroke
				(width 0.1)
				(type default)
			)
			(layer "F.Fab")
		)
		(fp_line
			(start -0.6477 -1.1811)
			(end -0.6477 -0.3175)
			(stroke
				(width 0.1)
				(type default)
			)
			(layer "F.Fab")
		)
		(fp_line
			(start -1.143 -1.1811)
			(end -0.6477 -1.1811)
			(stroke
				(width 0.1)
				(type default)
			)
			(layer "F.Fab")
		)
		(fp_line
			(start 1.143 -0.7239)
			(end 0.6477 -0.7239)
			(stroke
				(width 0.1)
				(type default)
			)
			(layer "F.Fab")
		)
		(fp_line
			(start 0.6477 -0.7239)
			(end 0.6477 -1.1811)
			(stroke
				(width 0.1)
				(type default)
			)
			(layer "F.Fab")
		)
		(fp_line
			(start -0.6477 -0.3175)
			(end -1.143 -0.3175)
			(stroke
				(width 0.1)
				(type default)
			)
			(layer "F.Fab")
		)
		(fp_line
			(start -1.143 -0.3175)
			(end -1.143 -1.1811)
			(stroke
				(width 0.1)
				(type default)
			)
			(layer "F.Fab")
		)
		(fp_line
			(start 1.143 0.7239)
			(end 1.143 1.1811)
			(stroke
				(width 0.1)
				(type default)
			)
			(layer "F.Fab")
		)
		(fp_line
			(start 0.6477 0.7239)
			(end 1.143 0.7239)
			(stroke
				(width 0.1)
				(type default)
			)
			(layer "F.Fab")
		)
		(fp_line
			(start -0.6477 0.7239)
			(end -0.6477 1.1811)
			(stroke
				(width 0.1)
				(type default)
			)
			(layer "F.Fab")
		)
		(fp_line
			(start -1.143 0.7239)
			(end -0.6477 0.7239)
			(stroke
				(width 0.1)
				(type default)
			)
			(layer "F.Fab")
		)
		(fp_line
			(start 1.143 1.1811)
			(end 0.6477 1.1811)
			(stroke
				(width 0.1)
				(type default)
			)
			(layer "F.Fab")
		)
		(fp_line
			(start 0.6477 1.1811)
			(end 0.6477 0.7239)
			(stroke
				(width 0.1)
				(type default)
			)
			(layer "F.Fab")
		)
		(fp_line
			(start -0.6477 1.1811)
			(end -1.143 1.1811)
			(stroke
				(width 0.1)
				(type default)
			)
			(layer "F.Fab")
		)
		(fp_line
			(start -1.143 1.1811)
			(end -1.143 0.7239)
			(stroke
				(width 0.1)
				(type default)
			)
			(layer "F.Fab")
		)
		(fp_line
			(start 0.6477 1.42875)
			(end -0.6477 1.42875)
			(stroke
				(width 0.1)
				(type default)
			)
			(layer "F.Fab")
		)
		(fp_line
			(start -0.6477 1.42875)
			(end -0.6477 -1.42875)
			(stroke
				(width 0.1)
				(type default)
			)
			(layer "F.Fab")
		)
		(fp_poly
			(pts
				(arc
					(start -0.381 -0.5588)
					(mid -0.381 -0.9398)
					(end -0.381 -0.5588)
				)
			)
			(stroke
				(width 0)
				(type default)
			)
			(fill yes)
			(layer "F.Fab")
		)
		(fp_text user "4"
			(at 1.36525 -2.3622 0)
			(unlocked yes)
			(layer "F.SilkS")
			(effects
				(font
					(size 0.635 0.4064)
					(thickness 0.1524)
				)
				(justify left)
			)
		)
		(fp_text user "2"
			(at -2.57175 2.0828 0)
			(unlocked yes)
			(layer "F.SilkS")
			(effects
				(font
					(size 0.635 0.4064)
					(thickness 0.1524)
				)
				(justify left)
			)
		)
		(fp_text user "3"
			(at 1.92405 2.1209 0)
			(unlocked yes)
			(layer "F.SilkS")
			(effects
				(font
					(size 0.635 0.4064)
					(thickness 0.1524)
				)
				(justify left)
			)
		)
		(fp_text user "4"
			(at 1.668526 -1.822704 0)
			(unlocked yes)
			(layer "F.Fab")
			(effects
				(font
					(size 0.7874 0.5842)
					(thickness 0.1524)
				)
				(justify left)
			)
		)
		(fp_text user "2"
			(at -1.887474 0.844296 0)
			(unlocked yes)
			(layer "F.Fab")
			(effects
				(font
					(size 0.7874 0.5842)
					(thickness 0.1524)
				)
				(justify left)
			)
		)
		(fp_text user "3"
			(at 1.287526 1.479296 0)
			(unlocked yes)
			(layer "F.Fab")
			(effects
				(font
					(size 0.7874 0.5842)
					(thickness 0.1524)
				)
				(justify left)
			)
		)
		(pad "1" smd rect
			(at -1.1049 -0.7493 90)
			(size 1.4478 1.0922)
			(layers "F.Cu" "F.Mask" "F.Paste")
			(net "SG")
		)
		(pad "2" smd rect
			(at -1.1049 0.9525 90)
			(size 1.4478 0.9906)
			(layers "F.Cu" "F.Mask" "F.Paste")
			(net "SMA2_SIG_IO_CONN")
		)
		(pad "3" smd rect
			(at 1.1049 0.9525 90)
			(size 1.4478 0.9906)
			(layers "F.Cu" "F.Mask" "F.Paste")
			(net "SMA1_SIG_IO_CONN")
		)
		(pad "4" smd rect
			(at 1.1049 -0.9525 90)
			(size 1.4478 0.9906)
			(layers "F.Cu" "F.Mask" "F.Paste")
			(net "Net_567")
		)
		(zone
			(layer "F.Cu")
			(hatch none 0.5)
			(connect_pads
				(clearance 0)
			)
			(min_thickness 0.25)
			(keepout
				(tracks allowed)
				(vias not_allowed)
				(pads allowed)
				(copperpour not_allowed)
				(footprints allowed)
			)
			(placement
				(enabled no)
				(sheetname "")
			)
			(fill
				(thermal_gap 0.5)
				(thermal_bridge_width 0.5)
				(island_removal_mode 0)
			)
			(polygon
				(pts
					(xy 4.6736 -53.7083) (xy 4.5339 -53.7083) (xy 4.5339 -54.737) (xy 5.5118 -54.737) (xy 5.5118 -55.0037)
					(xy 6.4262 -55.0037) (xy 6.4262 -54.737) (xy 7.4041 -54.737) (xy 7.4041 -53.975) (xy 6.4262 -53.975)
					(xy 6.4262 -53.7083) (xy 5.7658 -53.7083) (xy 5.7658 -53.975) (xy 4.6736 -53.975)
				)
			)
		)
	)
	(footprint ""
		(layer "F.Cu")
		(at 13.462 -66.167 -90)
		(property "Reference" "R120"
			(at -4.953 0.59563 90)
			(unlocked yes)
			(layer "F.SilkS")
			(effects
				(font
					(size 0.7874 0.5842)
					(thickness 0.1524)
				)
			)
		)
		(property "Value" "VAL*"
			(at 0.02032 2.13233 270)
			(unlocked yes)
			(layer "F.Fab")
			(hide yes)
			(effects
				(font
					(size 0.7874 0.5842)
					(thickness 0.1524)
				)
			)
		)
		(property "Tolerance" "TOL*"
			(at 0.044704 3.05435 270)
			(unlocked yes)
			(layer "Cmts.User")
			(hide yes)
			(effects
				(font
					(size 0.7874 0.5842)
					(thickness 0.1524)
				)
			)
		)
		(property "User Part Number" "PARTNUM*"
			(at 0.02032 4.024884 270)
			(unlocked yes)
			(layer "Cmts.User")
			(hide yes)
			(effects
				(font
					(size 0.7874 0.5842)
					(thickness 0.1524)
				)
			)
		)
		(property "Device Type" "RESISTOR-G155-11000-01,100OHM,A"
			(at 0.008382 1.210564 270)
			(unlocked yes)
			(layer "F.Fab")
			(hide yes)
			(effects
				(font
					(size 0.7874 0.5842)
					(thickness 0.1524)
				)
			)
		)
		(duplicate_pad_numbers_are_jumpers no)
		(fp_line
			(start -1.143 0.5588)
			(end 1.143 0.5588)
			(stroke
				(width 0.1)
				(type default)
			)
			(layer "F.SilkS")
		)
		(fp_line
			(start 1.143 0.5588)
			(end 1.143 -0.5588)
			(stroke
				(width 0.1)
				(type default)
			)
			(layer "F.SilkS")
		)
		(fp_line
			(start -1.143 -0.5588)
			(end -1.143 0.5588)
			(stroke
				(width 0.1)
				(type default)
			)
			(layer "F.SilkS")
		)
		(fp_line
			(start 1.143 -0.5588)
			(end -1.143 -0.5588)
			(stroke
				(width 0.1)
				(type default)
			)
			(layer "F.SilkS")
		)
		(fp_poly
			(pts
				(xy -1.143 0.5588) (xy 1.143 0.5588) (xy 1.143 -0.5588) (xy -1.143 -0.5588)
			)
			(stroke
				(width 0)
				(type default)
			)
			(fill no)
			(layer "F.CrtYd")
		)
		(fp_line
			(start -0.508 0.3048)
			(end 0.508 0.3048)
			(stroke
				(width 0.1)
				(type default)
			)
			(layer "F.Fab")
		)
		(fp_line
			(start 0.508 0.3048)
			(end 0.508 -0.3048)
			(stroke
				(width 0.1)
				(type default)
			)
			(layer "F.Fab")
		)
		(fp_line
			(start -0.508 -0.3048)
			(end -0.508 0.3048)
			(stroke
				(width 0.1)
				(type default)
			)
			(layer "F.Fab")
		)
		(fp_line
			(start 0.508 -0.3048)
			(end -0.508 -0.3048)
			(stroke
				(width 0.1)
				(type default)
			)
			(layer "F.Fab")
		)
		(pad "1" smd rect
			(at -0.5334 0 270)
			(size 0.7112 0.6096)
			(layers "F.Cu" "F.Mask" "F.Paste")
			(net "ANT1_OUT")
		)
		(pad "2" smd rect
			(at 0.5334 0 270)
			(size 0.7112 0.6096)
			(layers "F.Cu" "F.Mask" "F.Paste")
			(net "UNNAMED_12_74HCT2G125DPTSSOP8_6")
		)
		(zone
			(layer "F.Cu")
			(hatch none 0.5)
			(connect_pads
				(clearance 0)
			)
			(min_thickness 0.25)
			(keepout
				(tracks allowed)
				(vias not_allowed)
				(pads allowed)
				(copperpour not_allowed)
				(footprints allowed)
			)
			(placement
				(enabled no)
				(sheetname "")
			)
			(fill
				(thermal_gap 0.5)
				(thermal_bridge_width 0.5)
				(island_removal_mode 0)
			)
			(polygon
				(pts
					(xy 13.1572 -66.2432) (xy 13.1572 -66.0908) (xy 13.7668 -66.0908) (xy 13.7668 -66.2432)
				)
			)
		)
		(zone
			(layer "F.Cu")
			(hatch none 0.5)
			(connect_pads
				(clearance 0)
			)
			(min_thickness 0.25)
			(keepout
				(tracks not_allowed)
				(vias allowed)
				(pads allowed)
				(copperpour not_allowed)
				(footprints allowed)
			)
			(placement
				(enabled no)
				(sheetname "")
			)
			(fill
				(thermal_gap 0.5)
				(thermal_bridge_width 0.5)
				(island_removal_mode 0)
			)
			(polygon
				(pts
					(xy 13.1572 -66.2432) (xy 13.1572 -66.0908) (xy 13.7668 -66.0908) (xy 13.7668 -66.2432)
				)
			)
		)
	)
	(footprint ""
		(layer "F.Cu")
		(at 135.4074 -57.3786 -90)
		(property "Reference" "C255"
			(at -0.4064 2.14503 90)
			(unlocked yes)
			(layer "F.SilkS")
			(effects
				(font
					(size 0.7874 0.5842)
					(thickness 0.1524)
				)
			)
		)
		(property "Value" "VAL*"
			(at 0.0762 2.067306 270)
			(unlocked yes)
			(layer "F.Fab")
			(hide yes)
			(effects
				(font
					(size 0.7874 0.5842)
					(thickness 0.1524)
				)
			)
		)
		(property "Device Type" "CAPACITOR-G105-0B104-EK,0.1UF,A"
			(at 0.0508 1.127506 270)
			(unlocked yes)
			(layer "F.Fab")
			(hide yes)
			(effects
				(font
					(size 0.7874 0.5842)
					(thickness 0.1524)
				)
			)
		)
		(property "User Part Number" "PARTNUM*"
			(at 0.1016 4.023106 270)
			(unlocked yes)
			(layer "Cmts.User")
			(hide yes)
			(effects
				(font
					(size 0.7874 0.5842)
					(thickness 0.1524)
				)
			)
		)
		(property "Tolerance" "TOL*"
			(at 0.0762 3.032506 270)
			(unlocked yes)
			(layer "Cmts.User")
			(hide yes)
			(effects
				(font
					(size 0.7874 0.5842)
					(thickness 0.1524)
				)
			)
		)
		(duplicate_pad_numbers_are_jumpers no)
		(fp_line
			(start -1.143 0.5588)
			(end 1.143 0.5588)
			(stroke
				(width 0.1)
				(type default)
			)
			(layer "F.SilkS")
		)
		(fp_line
			(start 1.143 0.5588)
			(end 1.143 -0.5588)
			(stroke
				(width 0.1)
				(type default)
			)
			(layer "F.SilkS")
		)
		(fp_line
			(start -1.143 -0.5588)
			(end -1.143 0.5588)
			(stroke
				(width 0.1)
				(type default)
			)
			(layer "F.SilkS")
		)
		(fp_line
			(start 1.143 -0.5588)
			(end -1.143 -0.5588)
			(stroke
				(width 0.1)
				(type default)
			)
			(layer "F.SilkS")
		)
		(fp_rect
			(start -1.143 -0.5588)
			(end 1.143 0.5588)
			(stroke
				(width 0)
				(type default)
			)
			(fill no)
			(layer "F.CrtYd")
		)
		(fp_line
			(start -0.508 0.3048)
			(end 0.508 0.3048)
			(stroke
				(width 0.1)
				(type default)
			)
			(layer "F.Fab")
		)
		(fp_line
			(start 0.508 0.3048)
			(end 0.508 -0.3048)
			(stroke
				(width 0.1)
				(type default)
			)
			(layer "F.Fab")
		)
		(fp_line
			(start -0.508 -0.3048)
			(end -0.508 0.3048)
			(stroke
				(width 0.1)
				(type default)
			)
			(layer "F.Fab")
		)
		(fp_line
			(start 0.508 -0.3048)
			(end -0.508 -0.3048)
			(stroke
				(width 0.1)
				(type default)
			)
			(layer "F.Fab")
		)
		(pad "1" smd rect
			(at -0.5334 0 270)
			(size 0.7112 0.6096)
			(layers "F.Cu" "F.Mask" "F.Paste")
			(net "XP12R0V")
		)
		(pad "2" smd rect
			(at 0.5334 0 270)
			(size 0.7112 0.6096)
			(layers "F.Cu" "F.Mask" "F.Paste")
			(net "SG")
		)
		(zone
			(layer "F.Cu")
			(hatch none 0.5)
			(connect_pads
				(clearance 0)
			)
			(min_thickness 0.25)
			(keepout
				(tracks allowed)
				(vias not_allowed)
				(pads allowed)
				(copperpour not_allowed)
				(footprints allowed)
			)
			(placement
				(enabled no)
				(sheetname "")
			)
			(fill
				(thermal_gap 0.5)
				(thermal_bridge_width 0.5)
				(island_removal_mode 0)
			)
			(polygon
				(pts
					(xy 135.7122 -57.4548) (xy 135.1026 -57.4548) (xy 135.1026 -57.3024) (xy 135.7122 -57.3024)
				)
			)
		)
	)
	(footprint ""
		(layer "F.Cu")
		(at 119.6848 -29.3878 90)
		(property "Reference" "TP203"
			(at -4.1656 1.12395 90)
			(unlocked yes)
			(layer "F.SilkS")
			(effects
				(font
					(size 0.635 0.4064)
					(thickness 0.1524)
				)
				(justify left)
			)
		)
		(property "Value" ""
			(at 0 0 90)
			(layer "F.Fab")
			(effects
				(font
					(size 1.27 1.27)
				)
			)
		)
		(property "Device Type" "TP_PIONT-TP010CT020B030_PTH-TPA"
			(at -1.341882 0.996696 90)
			(unlocked yes)
			(layer "F.Fab")
			(hide yes)
			(effects
				(font
					(size 0.7874 0.5842)
					(thickness 0.1524)
				)
				(justify left)
			)
		)
		(duplicate_pad_numbers_are_jumpers no)
		(fp_poly
			(pts
				(arc
					(start 0 0.889)
					(mid 0 -0.889)
					(end 0 0.889)
				)
			)
			(stroke
				(width 0)
				(type default)
			)
			(fill no)
			(layer "B.CrtYd")
		)
		(fp_poly
			(pts
				(arc
					(start 0 0.889)
					(mid 0 -0.889)
					(end 0 0.889)
				)
			)
			(stroke
				(width 0)
				(type default)
			)
			(fill no)
			(layer "F.CrtYd")
		)
		(pad "1" thru_hole circle
			(at 0 0 90)
			(size 0.508 0.508)
			(drill 0.254)
			(layers "*.Cu" "*.Mask")
			(remove_unused_layers no)
			(net "IO_L24P_35")
			(clearance 0.1016)
			(padstack
				(mode front_inner_back)
				(layer "Inner"
					(shape circle)
					(size 0.508 0.508)
					(clearance 0.1016)
				)
				(layer "B.Cu"
					(shape circle)
					(size 0.762 0.762)
					(clearance -0.0254)
				)
			)
		)
	)
	(footprint ""
		(layer "F.Cu")
		(at 89.9922 -101.2698)
		(property "Reference" "C49"
			(at 3.048 0.16637 0)
			(unlocked yes)
			(layer "F.SilkS")
			(effects
				(font
					(size 0.7874 0.5842)
					(thickness 0.1524)
				)
			)
		)
		(property "Value" "VAL*"
			(at 0.0762 2.067306 0)
			(unlocked yes)
			(layer "F.Fab")
			(hide yes)
			(effects
				(font
					(size 0.7874 0.5842)
					(thickness 0.1524)
				)
			)
		)
		(property "Tolerance" "TOL*"
			(at 0.0762 3.032506 0)
			(unlocked yes)
			(layer "Cmts.User")
			(hide yes)
			(effects
				(font
					(size 0.7874 0.5842)
					(thickness 0.1524)
				)
			)
		)
		(property "User Part Number" "PARTNUM*"
			(at 0.1016 4.023106 0)
			(unlocked yes)
			(layer "Cmts.User")
			(hide yes)
			(effects
				(font
					(size 0.7874 0.5842)
					(thickness 0.1524)
				)
			)
		)
		(property "Device Type" "CAPACITOR-G105-0B223-EK,0.022UA"
			(at 0.0508 1.127506 0)
			(unlocked yes)
			(layer "F.Fab")
			(hide yes)
			(effects
				(font
					(size 0.7874 0.5842)
					(thickness 0.1524)
				)
			)
		)
		(duplicate_pad_numbers_are_jumpers no)
		(fp_line
			(start -1.143 -0.5588)
			(end -1.143 0.5588)
			(stroke
				(width 0.1)
				(type default)
			)
			(layer "F.SilkS")
		)
		(fp_line
			(start -1.143 0.5588)
			(end 1.143 0.5588)
			(stroke
				(width 0.1)
				(type default)
			)
			(layer "F.SilkS")
		)
		(fp_line
			(start 1.143 -0.5588)
			(end -1.143 -0.5588)
			(stroke
				(width 0.1)
				(type default)
			)
			(layer "F.SilkS")
		)
		(fp_line
			(start 1.143 0.5588)
			(end 1.143 -0.5588)
			(stroke
				(width 0.1)
				(type default)
			)
			(layer "F.SilkS")
		)
		(fp_rect
			(start -1.143 0.5588)
			(end 1.143 -0.5588)
			(stroke
				(width 0)
				(type default)
			)
			(fill no)
			(layer "F.CrtYd")
		)
		(fp_line
			(start -0.508 -0.3048)
			(end -0.508 0.3048)
			(stroke
				(width 0.1)
				(type default)
			)
			(layer "F.Fab")
		)
		(fp_line
			(start -0.508 0.3048)
			(end 0.508 0.3048)
			(stroke
				(width 0.1)
				(type default)
			)
			(layer "F.Fab")
		)
		(fp_line
			(start 0.508 -0.3048)
			(end -0.508 -0.3048)
			(stroke
				(width 0.1)
				(type default)
			)
			(layer "F.Fab")
		)
		(fp_line
			(start 0.508 0.3048)
			(end 0.508 -0.3048)
			(stroke
				(width 0.1)
				(type default)
			)
			(layer "F.Fab")
		)
		(pad "1" smd rect
			(at -0.5334 0)
			(size 0.7112 0.6096)
			(layers "F.Cu" "F.Mask" "F.Paste")
			(net "XP3R3V_SS")
		)
		(pad "2" smd rect
			(at 0.5334 0)
			(size 0.7112 0.6096)
			(layers "F.Cu" "F.Mask" "F.Paste")
			(net "XP3R3V_AGND")
		)
		(zone
			(layer "F.Cu")
			(hatch none 0.5)
			(connect_pads
				(clearance 0)
			)
			(min_thickness 0.25)
			(keepout
				(tracks allowed)
				(vias not_allowed)
				(pads allowed)
				(copperpour not_allowed)
				(footprints allowed)
			)
			(placement
				(enabled no)
				(sheetname "")
			)
			(fill
				(thermal_gap 0.5)
				(thermal_bridge_width 0.5)
				(island_removal_mode 0)
			)
			(polygon
				(pts
					(xy 89.916 -100.965) (xy 90.0684 -100.965) (xy 90.0684 -101.5746) (xy 89.916 -101.5746)
				)
			)
		)
	)
	(footprint ""
		(layer "F.Cu")
		(at 45.649896 -3.500374)
		(property "Reference" "GF1"
			(at 13.786104 -5.350256 0)
			(unlocked yes)
			(layer "F.SilkS")
			(effects
				(font
					(size 0.7874 0.5842)
					(thickness 0.1524)
				)
			)
		)
		(property "Value" ""
			(at 0 0 0)
			(layer "F.Fab")
			(effects
				(font
					(size 1.27 1.27)
				)
			)
		)
		(property "Device Type" "CONN_64P_GF-S_M_EF64_PCIE_P039A"
			(at 19.1262 4.810506 0)
			(unlocked yes)
			(layer "F.Fab")
			(hide yes)
			(effects
				(font
					(size 0.7874 0.5842)
					(thickness 0.1524)
				)
			)
		)
		(property "User Part Number" "PARTNUM*"
			(at 19.1262 5.978906 0)
			(unlocked yes)
			(layer "Cmts.User")
			(hide yes)
			(effects
				(font
					(size 0.7874 0.5842)
					(thickness 0.1524)
				)
			)
		)
		(duplicate_pad_numbers_are_jumpers no)
		(fp_poly
			(pts
				(xy -0.343408 4.0132) (xy 33.351216 4.0132) (xy 34.156904 3.207512) (xy 34.156904 -2.6035) (xy -1.149096 -2.6035)
				(xy -1.149096 3.207512)
			)
			(stroke
				(width 0)
				(type default)
			)
			(fill no)
			(layer "B.CrtYd")
		)
		(fp_poly
			(pts
				(xy -0.343408 4.0132) (xy 33.351216 4.0132) (xy 34.156904 3.207512) (xy 34.156904 -2.6035) (xy -1.149096 -2.6035)
				(xy -1.149096 3.207512)
			)
			(stroke
				(width 0)
				(type default)
			)
			(fill no)
			(layer "F.CrtYd")
		)
		(fp_line
			(start -0.641096 2.9972)
			(end -0.641096 -5.715)
			(stroke
				(width 0.1)
				(type default)
			)
			(layer "B.Fab")
		)
		(fp_line
			(start -0.133096 3.5052)
			(end -0.641096 2.9972)
			(stroke
				(width 0.1)
				(type default)
			)
			(layer "B.Fab")
		)
		(fp_line
			(start 10.039604 3.5052)
			(end -0.133096 3.5052)
			(stroke
				(width 0.1)
				(type default)
			)
			(layer "B.Fab")
		)
		(fp_line
			(start 10.547604 -3.9497)
			(end 10.547604 2.9972)
			(stroke
				(width 0.1)
				(type default)
			)
			(layer "B.Fab")
		)
		(fp_line
			(start 10.547604 2.9972)
			(end 10.039604 3.5052)
			(stroke
				(width 0.1)
				(type default)
			)
			(layer "B.Fab")
		)
		(fp_line
			(start 12.452604 2.9972)
			(end 12.452604 -3.9497)
			(stroke
				(width 0.1)
				(type default)
			)
			(layer "B.Fab")
		)
		(fp_line
			(start 12.960604 3.5052)
			(end 12.452604 2.9972)
			(stroke
				(width 0.1)
				(type default)
			)
			(layer "B.Fab")
		)
		(fp_line
			(start 33.140904 3.5052)
			(end 12.960604 3.5052)
			(stroke
				(width 0.1)
				(type default)
			)
			(layer "B.Fab")
		)
		(fp_line
			(start 33.648904 -5.715)
			(end 33.648904 2.9972)
			(stroke
				(width 0.1)
				(type default)
			)
			(layer "B.Fab")
		)
		(fp_line
			(start 33.648904 2.9972)
			(end 33.140904 3.5052)
			(stroke
				(width 0.1)
				(type default)
			)
			(layer "B.Fab")
		)
		(fp_arc
			(start 10.547604 -3.9497)
			(mid 10.826576 -4.623236)
			(end 11.500104 -4.9022)
			(stroke
				(width 0.1)
				(type default)
			)
			(layer "B.Fab")
		)
		(fp_arc
			(start 11.500104 -4.9022)
			(mid 12.173614 -4.623218)
			(end 12.452604 -3.9497)
			(stroke
				(width 0.1)
				(type default)
			)
			(layer "B.Fab")
		)
		(fp_line
			(start -0.641096 2.9972)
			(end -0.641096 -5.715)
			(stroke
				(width 0.1)
				(type default)
			)
			(layer "F.Fab")
		)
		(fp_line
			(start -0.133096 3.5052)
			(end -0.641096 2.9972)
			(stroke
				(width 0.1)
				(type default)
			)
			(layer "F.Fab")
		)
		(fp_line
			(start 10.039604 3.5052)
			(end -0.133096 3.5052)
			(stroke
				(width 0.1)
				(type default)
			)
			(layer "F.Fab")
		)
		(fp_line
			(start 10.547604 -3.9497)
			(end 10.547604 2.9972)
			(stroke
				(width 0.1)
				(type default)
			)
			(layer "F.Fab")
		)
		(fp_line
			(start 10.547604 2.9972)
			(end 10.039604 3.5052)
			(stroke
				(width 0.1)
				(type default)
			)
			(layer "F.Fab")
		)
		(fp_line
			(start 12.452604 2.9972)
			(end 12.452604 -3.9497)
			(stroke
				(width 0.1)
				(type default)
			)
			(layer "F.Fab")
		)
		(fp_line
			(start 12.960604 3.5052)
			(end 12.452604 2.9972)
			(stroke
				(width 0.1)
				(type default)
			)
			(layer "F.Fab")
		)
		(fp_line
			(start 33.140904 3.5052)
			(end 12.960604 3.5052)
			(stroke
				(width 0.1)
				(type default)
			)
			(layer "F.Fab")
		)
		(fp_line
			(start 33.648904 -5.715)
			(end 33.648904 2.9972)
			(stroke
				(width 0.1)
				(type default)
			)
			(layer "F.Fab")
		)
		(fp_line
			(start 33.648904 2.9972)
			(end 33.140904 3.5052)
			(stroke
				(width 0.1)
				(type default)
			)
			(layer "F.Fab")
		)
		(fp_arc
			(start 10.547604 -3.9497)
			(mid 10.826576 -4.623236)
			(end 11.500104 -4.9022)
			(stroke
				(width 0.1)
				(type default)
			)
			(layer "F.Fab")
		)
		(fp_arc
			(start 11.500104 -4.9022)
			(mid 12.173614 -4.623218)
			(end 12.452604 -3.9497)
			(stroke
				(width 0.1)
				(type default)
			)
			(layer "F.Fab")
		)
		(fp_text user "B1"
			(at 2.991104 -6.620256 0)
			(unlocked yes)
			(layer "F.SilkS")
			(effects
				(font
					(size 0.7874 0.5842)
					(thickness 0.1524)
				)
			)
		)
		(fp_text user "B32"
			(at 31.185104 -4.588256 0)
			(unlocked yes)
			(layer "F.SilkS")
			(effects
				(font
					(size 0.7874 0.5842)
					(thickness 0.1524)
				)
			)
		)
		(fp_text user "A1"
			(at 1.467104 -6.112256 0)
			(unlocked yes)
			(layer "B.SilkS")
			(effects
				(font
					(size 0.7874 0.5842)
					(thickness 0.1524)
				)
				(justify mirror)
			)
		)
		(fp_text user "A32"
			(at 32.542734 -5.135626 270)
			(unlocked yes)
			(layer "B.SilkS")
			(effects
				(font
					(size 0.7874 0.5842)
					(thickness 0.1524)
				)
				(justify mirror)
			)
		)
		(fp_text user "A1"
			(at 0.1016 -3.774948 0)
			(unlocked yes)
			(layer "B.Fab")
			(effects
				(font
					(size 0.7874 0.5842)
					(thickness 0.1524)
				)
				(justify mirror)
			)
		)
		(fp_text user "A32"
			(at 32.328104 -3.965956 0)
			(unlocked yes)
			(layer "B.Fab")
			(effects
				(font
					(size 0.7874 0.5842)
					(thickness 0.1524)
				)
				(justify mirror)
			)
		)
		(fp_text user "B1"
			(at 0.1524 -3.774948 0)
			(unlocked yes)
			(layer "F.Fab")
			(effects
				(font
					(size 0.7874 0.5842)
					(thickness 0.1524)
				)
			)
		)
		(fp_text user "B32"
			(at 32.5628 -3.825748 0)
			(unlocked yes)
			(layer "F.Fab")
			(effects
				(font
					(size 0.7874 0.5842)
					(thickness 0.1524)
				)
			)
		)
		(pad "A1" smd rect
			(at 0 -0.4953)
			(size 0.7112 3.2004)
			(layers "F.Cu" "F.Mask" "F.Paste")
			(net "CARD_PRESENT")
		)
		(pad "A2" smd rect
			(at 0.999998 0)
			(size 0.7112 4.191)
			(layers "F.Cu" "F.Mask" "F.Paste")
			(net "XP12R0V_PCIE")
		)
		(pad "A3" smd rect
			(at 1.999996 0)
			(size 0.7112 4.191)
			(layers "F.Cu" "F.Mask" "F.Paste")
			(net "XP12R0V_PCIE")
		)
		(pad "A4" smd rect
			(at 2.999994 0)
			(size 0.7112 4.191)
			(layers "F.Cu" "F.Mask" "F.Paste")
			(net "SG")
		)
		(pad "A5" smd rect
			(at 3.999992 0)
			(size 0.7112 4.191)
			(layers "F.Cu" "F.Mask" "F.Paste")
			(net "PCIE_CONN_TCK")
		)
		(pad "A6" smd rect
			(at 4.99999 0)
			(size 0.7112 4.191)
			(layers "F.Cu" "F.Mask" "F.Paste")
			(net "PCIE_CONN_TDI")
		)
		(pad "A7" smd rect
			(at 5.999988 0)
			(size 0.7112 4.191)
			(layers "F.Cu" "F.Mask" "F.Paste")
			(net "PCIE_CONN_TDO")
		)
		(pad "A8" smd rect
			(at 6.999986 0)
			(size 0.7112 4.191)
			(layers "F.Cu" "F.Mask" "F.Paste")
			(net "PCIE_CONN_TMS")
		)
		(pad "A9" smd rect
			(at 7.999984 0)
			(size 0.7112 4.191)
			(layers "F.Cu" "F.Mask" "F.Paste")
			(net "XP3R3V_PCIE")
		)
		(pad "A10" smd rect
			(at 8.999982 0)
			(size 0.7112 4.191)
			(layers "F.Cu" "F.Mask" "F.Paste")
			(net "XP3R3V_PCIE")
		)
		(pad "A11" smd rect
			(at 9.99998 0)
			(size 0.7112 4.191)
			(layers "F.Cu" "F.Mask" "F.Paste")
			(net "PCIE_CONN_PERST_N")
		)
		(pad "A12" smd rect
			(at 12.999974 0)
			(size 0.7112 4.191)
			(layers "F.Cu" "F.Mask" "F.Paste")
			(net "SG")
		)
		(pad "A13" smd rect
			(at 13.999972 0)
			(size 0.7112 4.191)
			(layers "F.Cu" "F.Mask" "F.Paste")
			(net "C_PCIEREFCLKP")
		)
		(pad "A14" smd rect
			(at 14.99997 0)
			(size 0.7112 4.191)
			(layers "F.Cu" "F.Mask" "F.Paste")
			(net "C_PCIEREFCLKN")
		)
		(pad "A15" smd rect
			(at 15.999968 0)
			(size 0.7112 4.191)
			(layers "F.Cu" "F.Mask" "F.Paste")
			(net "SG")
		)
		(pad "A16" smd rect
			(at 16.999966 0)
			(size 0.7112 4.191)
			(layers "F.Cu" "F.Mask" "F.Paste")
			(net "C_CPU_RX_PCIE_MGT0_TXP")
		)
		(pad "A17" smd rect
			(at 17.999964 0)
			(size 0.7112 4.191)
			(layers "F.Cu" "F.Mask" "F.Paste")
			(net "C_CPU_RX_PCIE_MGT0_TXN")
		)
		(pad "A18" smd rect
			(at 18.999962 0)
			(size 0.7112 4.191)
			(layers "F.Cu" "F.Mask" "F.Paste")
			(net "SG")
		)
		(pad "A19" smd rect
			(at 19.99996 0)
			(size 0.7112 4.191)
			(layers "F.Cu" "F.Mask" "F.Paste")
			(net "Net_752")
		)
		(pad "A20" smd rect
			(at 20.999958 0)
			(size 0.7112 4.191)
			(layers "F.Cu" "F.Mask" "F.Paste")
			(net "SG")
		)
		(pad "A21" smd rect
			(at 21.999956 0)
			(size 0.7112 4.191)
			(layers "F.Cu" "F.Mask" "F.Paste")
			(net "C_CPU_RX_PCIE_MGT1_TXP")
		)
		(pad "A22" smd rect
			(at 22.999954 0)
			(size 0.7112 4.191)
			(layers "F.Cu" "F.Mask" "F.Paste")
			(net "C_CPU_RX_PCIE_MGT1_TXN")
		)
		(pad "A23" smd rect
			(at 23.999952 0)
			(size 0.7112 4.191)
			(layers "F.Cu" "F.Mask" "F.Paste")
			(net "SG")
		)
		(pad "A24" smd rect
			(at 24.99995 0)
			(size 0.7112 4.191)
			(layers "F.Cu" "F.Mask" "F.Paste")
			(net "SG")
		)
		(pad "A25" smd rect
			(at 25.999948 0)
			(size 0.7112 4.191)
			(layers "F.Cu" "F.Mask" "F.Paste")
			(net "C_CPU_RX_PCIE_MGT2_TXP")
		)
		(pad "A26" smd rect
			(at 26.999946 0)
			(size 0.7112 4.191)
			(layers "F.Cu" "F.Mask" "F.Paste")
			(net "C_CPU_RX_PCIE_MGT2_TXN")
		)
		(pad "A27" smd rect
			(at 27.999944 0)
			(size 0.7112 4.191)
			(layers "F.Cu" "F.Mask" "F.Paste")
			(net "SG")
		)
		(pad "A28" smd rect
			(at 28.999942 0)
			(size 0.7112 4.191)
			(layers "F.Cu" "F.Mask" "F.Paste")
			(net "SG")
		)
		(pad "A29" smd rect
			(at 29.99994 0)
			(size 0.7112 4.191)
			(layers "F.Cu" "F.Mask" "F.Paste")
			(net "C_CPU_RX_PCIE_MGT3_TXP")
		)
		(pad "A30" smd rect
			(at 30.999938 0)
			(size 0.7112 4.191)
			(layers "F.Cu" "F.Mask" "F.Paste")
			(net "C_CPU_RX_PCIE_MGT3_TXN")
		)
		(pad "A31" smd rect
			(at 31.999936 0)
			(size 0.7112 4.191)
			(layers "F.Cu" "F.Mask" "F.Paste")
			(net "SG")
		)
		(pad "A32" smd rect
			(at 32.999934 0)
			(size 0.7112 4.191)
			(layers "F.Cu" "F.Mask" "F.Paste")
			(net "Net_750")
		)
		(pad "B1" smd rect
			(at 0 0)
			(size 0.7112 4.191)
			(layers "F.Cu" "F.Mask" "F.Paste")
			(net "XP12R0V_PCIE")
		)
		(pad "B2" smd rect
			(at 0.999998 0)
			(size 0.7112 4.191)
			(layers "F.Cu" "F.Mask" "F.Paste")
			(net "XP12R0V_PCIE")
		)
		(pad "B3" smd rect
			(at 1.999996 0)
			(size 0.7112 4.191)
			(layers "F.Cu" "F.Mask" "F.Paste")
			(net "XP12R0V_PCIE")
		)
		(pad "B4" smd rect
			(at 2.999994 0)
			(size 0.7112 4.191)
			(layers "F.Cu" "F.Mask" "F.Paste")
			(net "SG")
		)
		(pad "B5" smd rect
			(at 3.999992 0)
			(size 0.7112 4.191)
			(layers "F.Cu" "F.Mask" "F.Paste")
			(net "PCIE_CONN_SMCLK")
		)
		(pad "B6" smd rect
			(at 4.99999 0)
			(size 0.7112 4.191)
			(layers "F.Cu" "F.Mask" "F.Paste")
			(net "PCIE_CONN_SMDAT")
		)
		(pad "B7" smd rect
			(at 5.999988 0)
			(size 0.7112 4.191)
			(layers "F.Cu" "F.Mask" "F.Paste")
			(net "SG")
		)
		(pad "B8" smd rect
			(at 6.999986 0)
			(size 0.7112 4.191)
			(layers "F.Cu" "F.Mask" "F.Paste")
			(net "XP3R3V_PCIE")
		)
		(pad "B9" smd rect
			(at 7.999984 0)
			(size 0.7112 4.191)
			(layers "F.Cu" "F.Mask" "F.Paste")
			(net "Net_754")
		)
		(pad "B10" smd rect
			(at 8.999982 0)
			(size 0.7112 4.191)
			(layers "F.Cu" "F.Mask" "F.Paste")
			(net "XP3R3V_AUX_PCIE")
		)
		(pad "B11" smd rect
			(at 9.99998 0)
			(size 0.7112 4.191)
			(layers "F.Cu" "F.Mask" "F.Paste")
			(net "Net_749")
		)
		(pad "B12" smd rect
			(at 12.999974 0)
			(size 0.7112 4.191)
			(layers "F.Cu" "F.Mask" "F.Paste")
			(net "Net_753")
		)
		(pad "B13" smd rect
			(at 13.999972 0)
			(size 0.7112 4.191)
			(layers "F.Cu" "F.Mask" "F.Paste")
			(net "SG")
		)
		(pad "B14" smd rect
			(at 14.99997 0)
			(size 0.7112 4.191)
			(layers "F.Cu" "F.Mask" "F.Paste")
			(net "CPU_TX_PCIE_MGT_0_RXP")
		)
		(pad "B15" smd rect
			(at 15.999968 0)
			(size 0.7112 4.191)
			(layers "F.Cu" "F.Mask" "F.Paste")
			(net "CPU_TX_PCIE_MGT_0_RXN")
		)
		(pad "B16" smd rect
			(at 16.999966 0)
			(size 0.7112 4.191)
			(layers "F.Cu" "F.Mask" "F.Paste")
			(net "SG")
		)
		(pad "B17" smd rect
			(at 17.999964 0)
			(size 0.7112 4.191)
			(layers "F.Cu" "F.Mask" "F.Paste")
			(net "UNNAMED_3_CONN64PGF_I61_PRSNT21")
		)
		(pad "B18" smd rect
			(at 18.999962 0)
			(size 0.7112 4.191)
			(layers "F.Cu" "F.Mask" "F.Paste")
			(net "SG")
		)
		(pad "B19" smd rect
			(at 19.99996 0)
			(size 0.7112 4.191)
			(layers "F.Cu" "F.Mask" "F.Paste")
			(net "CPU_TX_PCIE_MGT_1_RXP")
		)
		(pad "B20" smd rect
			(at 20.999958 0)
			(size 0.7112 4.191)
			(layers "F.Cu" "F.Mask" "F.Paste")
			(net "CPU_TX_PCIE_MGT_1_RXN")
		)
		(pad "B21" smd rect
			(at 21.999956 0)
			(size 0.7112 4.191)
			(layers "F.Cu" "F.Mask" "F.Paste")
			(net "SG")
		)
		(pad "B22" smd rect
			(at 22.999954 0)
			(size 0.7112 4.191)
			(layers "F.Cu" "F.Mask" "F.Paste")
			(net "SG")
		)
		(pad "B23" smd rect
			(at 23.999952 0)
			(size 0.7112 4.191)
			(layers "F.Cu" "F.Mask" "F.Paste")
			(net "CPU_TX_PCIE_MGT_2_RXP")
		)
		(pad "B24" smd rect
			(at 24.99995 0)
			(size 0.7112 4.191)
			(layers "F.Cu" "F.Mask" "F.Paste")
			(net "CPU_TX_PCIE_MGT_2_RXN")
		)
		(pad "B25" smd rect
			(at 25.999948 0)
			(size 0.7112 4.191)
			(layers "F.Cu" "F.Mask" "F.Paste")
			(net "SG")
		)
		(pad "B26" smd rect
			(at 26.999946 0)
			(size 0.7112 4.191)
			(layers "F.Cu" "F.Mask" "F.Paste")
			(net "SG")
		)
		(pad "B27" smd rect
			(at 27.999944 0)
			(size 0.7112 4.191)
			(layers "F.Cu" "F.Mask" "F.Paste")
			(net "CPU_TX_PCIE_MGT_3_RXP")
		)
		(pad "B28" smd rect
			(at 28.999942 0)
			(size 0.7112 4.191)
			(layers "F.Cu" "F.Mask" "F.Paste")
			(net "CPU_TX_PCIE_MGT_3_RXN")
		)
		(pad "B29" smd rect
			(at 29.99994 0)
			(size 0.7112 4.191)
			(layers "F.Cu" "F.Mask" "F.Paste")
			(net "SG")
		)
		(pad "B30" smd rect
			(at 30.999938 0)
			(size 0.7112 4.191)
			(layers "F.Cu" "F.Mask" "F.Paste")
			(net "Net_751")
		)
		(pad "B31" smd rect
			(at 31.999936 -0.4953)
			(size 0.7112 3.2004)
			(layers "F.Cu" "F.Mask" "F.Paste")
			(net "UNNAMED_3_CONN64PGF_I61_PRSNT22")
		)
		(pad "B32" smd rect
			(at 32.999934 0)
			(size 0.7112 4.191)
			(layers "F.Cu" "F.Mask" "F.Paste")
			(net "SG")
		)
		(zone
			(layers "F.Cu" "B.Cu" "In1.Cu" "In2.Cu" "In3.Cu" "In4.Cu" "In5.Cu" "In6.Cu"
				"In7.Cu" "In8.Cu"
			)
			(hatch none 0.5)
			(connect_pads
				(clearance 0)
			)
			(min_thickness 0.25)
			(keepout
				(tracks allowed)
				(vias not_allowed)
				(pads allowed)
				(copperpour not_allowed)
				(footprints allowed)
			)
			(placement
				(enabled no)
				(sheetname "")
			)
			(fill
				(thermal_gap 0.5)
				(thermal_bridge_width 0.5)
				(island_removal_mode 0)
			)
			(polygon
				(pts
					(xy 45.5168 0.004826) (xy 78.7908 0.004826) (xy 79.2988 -0.503174) (xy 79.2988 -6.865874) (xy 45.0088 -6.865874)
					(xy 45.0088 -0.503174)
				)
			)
		)
	)
	(footprint ""
		(layer "F.Cu")
		(at 88.6714 -64.4144 90)
		(property "Reference" "L19"
			(at 12.8016 -10.01903 90)
			(unlocked yes)
			(layer "F.SilkS")
			(effects
				(font
					(size 0.7874 0.5842)
					(thickness 0.1524)
				)
			)
		)
		(property "Value" "VAL*"
			(at 0.014732 2.526538 90)
			(unlocked yes)
			(layer "F.Fab")
			(hide yes)
			(effects
				(font
					(size 0.7874 0.5842)
					(thickness 0.000001)
				)
			)
		)
		(property "Tolerance" "TOL*"
			(at 0.014732 3.503676 90)
			(unlocked yes)
			(layer "Cmts.User")
			(hide yes)
			(effects
				(font
					(size 0.7874 0.5842)
					(thickness 0.000001)
				)
			)
		)
		(property "User Part Number" "PARTNUM*"
			(at 0.02794 4.480814 90)
			(unlocked yes)
			(layer "Cmts.User")
			(hide yes)
			(effects
				(font
					(size 0.7874 0.5842)
					(thickness 0.000001)
				)
			)
		)
		(property "Device Type" "FERRITEBEAD-G191-10097-01,600OA"
			(at 0.014732 1.600708 90)
			(unlocked yes)
			(layer "F.Fab")
			(hide yes)
			(effects
				(font
					(size 0.7874 0.5842)
					(thickness 0.000001)
				)
			)
		)
		(duplicate_pad_numbers_are_jumpers no)
		(fp_line
			(start 1.3208 -0.7112)
			(end 1.3208 0.7112)
			(stroke
				(width 0.1)
				(type default)
			)
			(layer "F.SilkS")
		)
		(fp_line
			(start -1.3208 -0.7112)
			(end 1.3208 -0.7112)
			(stroke
				(width 0.1)
				(type default)
			)
			(layer "F.SilkS")
		)
		(fp_line
			(start 1.3208 0.7112)
			(end -1.3208 0.7112)
			(stroke
				(width 0.1)
				(type default)
			)
			(layer "F.SilkS")
		)
		(fp_line
			(start -1.3208 0.7112)
			(end -1.3208 -0.7112)
			(stroke
				(width 0.1)
				(type default)
			)
			(layer "F.SilkS")
		)
		(fp_rect
			(start -1.3208 0.7112)
			(end 1.3208 -0.7112)
			(stroke
				(width 0)
				(type default)
			)
			(fill no)
			(layer "F.CrtYd")
		)
		(fp_line
			(start 0.8128 -0.4572)
			(end 0.8128 0.4572)
			(stroke
				(width 0.1)
				(type default)
			)
			(layer "F.Fab")
		)
		(fp_line
			(start -0.8128 -0.4572)
			(end 0.8128 -0.4572)
			(stroke
				(width 0.1)
				(type default)
			)
			(layer "F.Fab")
		)
		(fp_line
			(start 0.8128 0.4572)
			(end -0.8128 0.4572)
			(stroke
				(width 0.1)
				(type default)
			)
			(layer "F.Fab")
		)
		(fp_line
			(start -0.8128 0.4572)
			(end -0.8128 -0.4572)
			(stroke
				(width 0.1)
				(type default)
			)
			(layer "F.Fab")
		)
		(pad "1" smd rect
			(at -0.6858 0 90)
			(size 0.762 0.8636)
			(layers "F.Cu" "F.Mask" "F.Paste")
			(net "VDD_BNO085")
		)
		(pad "2" smd rect
			(at 0.6858 0 90)
			(size 0.762 0.8636)
			(layers "F.Cu" "F.Mask" "F.Paste")
			(net "XP3R3V_FPGA")
		)
		(zone
			(layer "F.Cu")
			(hatch none 0.5)
			(connect_pads
				(clearance 0)
			)
			(min_thickness 0.25)
			(keepout
				(tracks allowed)
				(vias not_allowed)
				(pads allowed)
				(copperpour not_allowed)
				(footprints allowed)
			)
			(placement
				(enabled no)
				(sheetname "")
			)
			(fill
				(thermal_gap 0.5)
				(thermal_bridge_width 0.5)
				(island_removal_mode 0)
			)
			(polygon
				(pts
					(xy 89.1286 -64.262) (xy 89.1286 -64.5668) (xy 88.2142 -64.5668) (xy 88.2142 -64.262)
				)
			)
		)
		(zone
			(layer "F.Cu")
			(hatch none 0.5)
			(connect_pads
				(clearance 0)
			)
			(min_thickness 0.25)
			(keepout
				(tracks not_allowed)
				(vias allowed)
				(pads allowed)
				(copperpour not_allowed)
				(footprints allowed)
			)
			(placement
				(enabled no)
				(sheetname "")
			)
			(fill
				(thermal_gap 0.5)
				(thermal_bridge_width 0.5)
				(island_removal_mode 0)
			)
			(polygon
				(pts
					(xy 89.1286 -64.262) (xy 89.1286 -64.5668) (xy 88.2142 -64.5668) (xy 88.2142 -64.262)
				)
			)
		)
	)
	(footprint ""
		(layer "F.Cu")
		(at 153.049986 -104.350058 -90)
		(property "Reference" "DS20"
			(at 1.099058 -1.548384 90)
			(unlocked yes)
			(layer "F.SilkS")
			(effects
				(font
					(size 0.7874 0.5842)
					(thickness 0.1524)
				)
			)
		)
		(property "Value" ""
			(at 0 0 270)
			(layer "F.Fab")
			(effects
				(font
					(size 1.27 1.27)
				)
			)
		)
		(property "Device Type" "OPTICAL-G170-10143-01"
			(at 0.1778 1.483081 270)
			(unlocked yes)
			(layer "F.Fab")
			(hide yes)
			(effects
				(font
					(size 0.786892 0.583946)
					(thickness 0.000001)
				)
			)
		)
		(property "User Part Number" "PARTNUM*"
			(at 0.1778 2.422881 270)
			(unlocked yes)
			(layer "Cmts.User")
			(hide yes)
			(effects
				(font
					(size 0.786892 0.583946)
					(thickness 0.000001)
				)
			)
		)
		(duplicate_pad_numbers_are_jumpers no)
		(fp_line
			(start -1.1938 1.7272)
			(end -2.4638 1.7272)
			(stroke
				(width 0.1)
				(type default)
			)
			(layer "F.SilkS")
		)
		(fp_line
			(start -1.8288 1.0922)
			(end -1.8288 2.3622)
			(stroke
				(width 0.1)
				(type default)
			)
			(layer "F.SilkS")
		)
		(fp_line
			(start -1.397508 0.704088)
			(end -1.397508 -0.704088)
			(stroke
				(width 0.1)
				(type default)
			)
			(layer "F.SilkS")
		)
		(fp_line
			(start 1.397508 0.704088)
			(end -1.397508 0.704088)
			(stroke
				(width 0.1)
				(type default)
			)
			(layer "F.SilkS")
		)
		(fp_line
			(start -1.397508 -0.704088)
			(end 1.397508 -0.704088)
			(stroke
				(width 0.1)
				(type default)
			)
			(layer "F.SilkS")
		)
		(fp_line
			(start 1.397508 -0.704088)
			(end 1.397508 0.704088)
			(stroke
				(width 0.1)
				(type default)
			)
			(layer "F.SilkS")
		)
		(fp_poly
			(pts
				(xy 1.397508 0.704088) (xy 1.397508 -0.704088) (xy 1.905508 -0.704088) (xy 1.905508 0.704088)
			)
			(stroke
				(width 0)
				(type default)
			)
			(fill yes)
			(layer "F.SilkS")
		)
		(fp_poly
			(pts
				(xy -1.651508 0.958088) (xy 1.905508 0.958088) (xy 1.905508 -0.958088) (xy -1.651508 -0.958088)
			)
			(stroke
				(width 0)
				(type default)
			)
			(fill no)
			(layer "F.CrtYd")
		)
		(fp_line
			(start -1.4478 1.3462)
			(end -2.7178 1.3462)
			(stroke
				(width 0.1)
				(type default)
			)
			(layer "F.Fab")
		)
		(fp_line
			(start -2.0828 0.7112)
			(end -2.0828 1.9812)
			(stroke
				(width 0.1)
				(type default)
			)
			(layer "F.Fab")
		)
		(fp_line
			(start -0.850138 0.450088)
			(end 0.850138 0.450088)
			(stroke
				(width 0.1)
				(type default)
			)
			(layer "F.Fab")
		)
		(fp_line
			(start 0.850138 0.450088)
			(end 0.850138 -0.450088)
			(stroke
				(width 0.1)
				(type default)
			)
			(layer "F.Fab")
		)
		(fp_line
			(start -0.850138 -0.450088)
			(end -0.850138 0.450088)
			(stroke
				(width 0.1)
				(type default)
			)
			(layer "F.Fab")
		)
		(fp_line
			(start 0.850138 -0.450088)
			(end -0.850138 -0.450088)
			(stroke
				(width 0.1)
				(type default)
			)
			(layer "F.Fab")
		)
		(fp_poly
			(pts
				(xy 0.850138 -0.450088) (xy 0.850138 0.450088) (xy 0.342138 0.450088) (xy 0.342138 -0.450088)
			)
			(stroke
				(width 0)
				(type default)
			)
			(fill yes)
			(layer "F.Fab")
		)
		(fp_text user "C"
			(at 2.527808 0.268986 0)
			(unlocked yes)
			(layer "F.SilkS")
			(effects
				(font
					(size 0.635 0.4064)
					(thickness 0.1524)
				)
			)
		)
		(fp_text user "A"
			(at -1.028192 -1.255014 0)
			(unlocked yes)
			(layer "F.SilkS")
			(effects
				(font
					(size 0.635 0.4064)
					(thickness 0.1524)
				)
			)
		)
		(fp_text user "A"
			(at -1.020572 1.030986 0)
			(unlocked yes)
			(layer "F.Fab")
			(effects
				(font
					(size 0.7874 0.5842)
					(thickness 0.1524)
				)
			)
		)
		(fp_text user "C"
			(at 2.281428 -0.112014 0)
			(unlocked yes)
			(layer "F.Fab")
			(effects
				(font
					(size 0.7874 0.5842)
					(thickness 0.1524)
				)
			)
		)
		(pad "A" smd rect
			(at -0.749808 0 270)
			(size 0.7874 0.7874)
			(layers "F.Cu" "F.Mask" "F.Paste")
			(net "UNNAMED_14_OPTICAL_I194_A")
		)
		(pad "C" smd rect
			(at 0.749808 0 270)
			(size 0.7874 0.7874)
			(layers "F.Cu" "F.Mask" "F.Paste")
			(net "SG")
		)
	)
	(footprint ""
		(layer "F.Cu")
		(at 139.329922 -100.7618 180)
		(property "Reference" "R12"
			(at 1.153922 1.05283 0)
			(unlocked yes)
			(layer "F.SilkS")
			(effects
				(font
					(size 0.7874 0.5842)
					(thickness 0.1524)
				)
			)
		)
		(property "Value" "VAL*"
			(at 0.02032 2.13233 180)
			(unlocked yes)
			(layer "F.Fab")
			(hide yes)
			(effects
				(font
					(size 0.7874 0.5842)
					(thickness 0.1524)
				)
			)
		)
		(property "Device Type" "RESISTOR-G155-11002-01,10KOHM,A"
			(at 0.008382 1.210564 180)
			(unlocked yes)
			(layer "F.Fab")
			(hide yes)
			(effects
				(font
					(size 0.7874 0.5842)
					(thickness 0.1524)
				)
			)
		)
		(property "User Part Number" "PARTNUM*"
			(at 0.02032 4.024884 180)
			(unlocked yes)
			(layer "Cmts.User")
			(hide yes)
			(effects
				(font
					(size 0.7874 0.5842)
					(thickness 0.1524)
				)
			)
		)
		(property "Tolerance" "TOL*"
			(at 0.044704 3.05435 180)
			(unlocked yes)
			(layer "Cmts.User")
			(hide yes)
			(effects
				(font
					(size 0.7874 0.5842)
					(thickness 0.1524)
				)
			)
		)
		(duplicate_pad_numbers_are_jumpers no)
		(fp_line
			(start 1.143 0.5588)
			(end 1.143 -0.5588)
			(stroke
				(width 0.1)
				(type default)
			)
			(layer "F.SilkS")
		)
		(fp_line
			(start 1.143 -0.5588)
			(end -1.143 -0.5588)
			(stroke
				(width 0.1)
				(type default)
			)
			(layer "F.SilkS")
		)
		(fp_line
			(start -1.143 0.5588)
			(end 1.143 0.5588)
			(stroke
				(width 0.1)
				(type default)
			)
			(layer "F.SilkS")
		)
		(fp_line
			(start -1.143 -0.5588)
			(end -1.143 0.5588)
			(stroke
				(width 0.1)
				(type default)
			)
			(layer "F.SilkS")
		)
		(fp_rect
			(start -1.143 0.5588)
			(end 1.143 -0.5588)
			(stroke
				(width 0)
				(type default)
			)
			(fill no)
			(layer "F.CrtYd")
		)
		(fp_line
			(start 0.508 0.3048)
			(end 0.508 -0.3048)
			(stroke
				(width 0.1)
				(type default)
			)
			(layer "F.Fab")
		)
		(fp_line
			(start 0.508 -0.3048)
			(end -0.508 -0.3048)
			(stroke
				(width 0.1)
				(type default)
			)
			(layer "F.Fab")
		)
		(fp_line
			(start -0.508 0.3048)
			(end 0.508 0.3048)
			(stroke
				(width 0.1)
				(type default)
			)
			(layer "F.Fab")
		)
		(fp_line
			(start -0.508 -0.3048)
			(end -0.508 0.3048)
			(stroke
				(width 0.1)
				(type default)
			)
			(layer "F.Fab")
		)
		(pad "1" smd rect
			(at -0.5334 0 180)
			(size 0.7112 0.6096)
			(layers "F.Cu" "F.Mask" "F.Paste")
			(net "XP12R0V_A_OV")
		)
		(pad "2" smd rect
			(at 0.5334 0 180)
			(size 0.7112 0.6096)
			(layers "F.Cu" "F.Mask" "F.Paste")
			(net "SG")
		)
		(zone
			(layer "F.Cu")
			(hatch none 0.5)
			(connect_pads
				(clearance 0)
			)
			(min_thickness 0.25)
			(keepout
				(tracks allowed)
				(vias not_allowed)
				(pads allowed)
				(copperpour not_allowed)
				(footprints allowed)
			)
			(placement
				(enabled no)
				(sheetname "")
			)
			(fill
				(thermal_gap 0.5)
				(thermal_bridge_width 0.5)
				(island_removal_mode 0)
			)
			(polygon
				(pts
					(xy 139.406122 -101.0666) (xy 139.253722 -101.0666) (xy 139.253722 -100.457) (xy 139.406122 -100.457)
				)
			)
		)
	)
	(footprint ""
		(layer "F.Cu")
		(at 89.8398 -104.6734 180)
		(property "Reference" "C77"
			(at -1.7272 0.69723 0)
			(unlocked yes)
			(layer "F.SilkS")
			(effects
				(font
					(size 0.7874 0.5842)
					(thickness 0.1524)
				)
			)
		)
		(property "Value" "VAL*"
			(at 0.193548 2.13614 180)
			(unlocked yes)
			(layer "F.Fab")
			(hide yes)
			(effects
				(font
					(size 0.7874 0.5842)
					(thickness 0.1524)
				)
			)
		)
		(property "User Part Number" "PARTNUM*"
			(at 0.216154 4.185666 180)
			(unlocked yes)
			(layer "Cmts.User")
			(hide yes)
			(effects
				(font
					(size 0.7874 0.5842)
					(thickness 0.1524)
				)
			)
		)
		(property "Device Type" "CAPACITOR-G104-0B103-EK,0.01UFA"
			(at 0.184404 1.180592 180)
			(unlocked yes)
			(layer "F.Fab")
			(hide yes)
			(effects
				(font
					(size 0.7874 0.5842)
					(thickness 0.1524)
				)
			)
		)
		(property "Tolerance" "TOL*"
			(at 0.216154 3.1496 180)
			(unlocked yes)
			(layer "Cmts.User")
			(hide yes)
			(effects
				(font
					(size 0.7874 0.5842)
					(thickness 0.1524)
				)
			)
		)
		(duplicate_pad_numbers_are_jumpers no)
		(fp_line
			(start 0.671322 0.4445)
			(end -0.671322 0.4445)
			(stroke
				(width 0.1)
				(type default)
			)
			(layer "F.SilkS")
		)
		(fp_line
			(start 0.671322 -0.4445)
			(end 0.671322 0.4445)
			(stroke
				(width 0.1)
				(type default)
			)
			(layer "F.SilkS")
		)
		(fp_line
			(start -0.671322 0.4445)
			(end -0.671322 -0.4445)
			(stroke
				(width 0.1)
				(type default)
			)
			(layer "F.SilkS")
		)
		(fp_line
			(start -0.671322 -0.4445)
			(end 0.671322 -0.4445)
			(stroke
				(width 0.1)
				(type default)
			)
			(layer "F.SilkS")
		)
		(fp_rect
			(start 0.671322 -0.4445)
			(end -0.671322 0.4445)
			(stroke
				(width 0)
				(type default)
			)
			(fill no)
			(layer "F.CrtYd")
		)
		(fp_line
			(start 0.31496 0.1651)
			(end 0.31496 -0.1651)
			(stroke
				(width 0.1)
				(type default)
			)
			(layer "F.Fab")
		)
		(fp_line
			(start 0.31496 -0.1651)
			(end -0.31496 -0.1651)
			(stroke
				(width 0.1)
				(type default)
			)
			(layer "F.Fab")
		)
		(fp_line
			(start -0.31496 0.1651)
			(end 0.31496 0.1651)
			(stroke
				(width 0.1)
				(type default)
			)
			(layer "F.Fab")
		)
		(fp_line
			(start -0.31496 -0.1651)
			(end -0.31496 0.1651)
			(stroke
				(width 0.1)
				(type default)
			)
			(layer "F.Fab")
		)
		(pad "1" smd rect
			(at -0.264922 0 180)
			(size 0.3048 0.381)
			(layers "F.Cu" "F.Mask" "F.Paste")
			(net "SG")
		)
		(pad "2" smd rect
			(at 0.264922 0 180)
			(size 0.3048 0.381)
			(layers "F.Cu" "F.Mask" "F.Paste")
			(net "R_XP3R3V_PG")
		)
		(zone
			(layer "F.Cu")
			(hatch none 0.5)
			(connect_pads
				(clearance 0)
			)
			(min_thickness 0.25)
			(keepout
				(tracks allowed)
				(vias not_allowed)
				(pads allowed)
				(copperpour not_allowed)
				(footprints allowed)
			)
			(placement
				(enabled no)
				(sheetname "")
			)
			(fill
				(thermal_gap 0.5)
				(thermal_bridge_width 0.5)
				(island_removal_mode 0)
			)
			(polygon
				(pts
					(xy 89.727278 -104.4829) (xy 89.952322 -104.4829) (xy 89.952322 -104.8639) (xy 89.727278 -104.8639)
				)
			)
		)
	)
	(footprint ""
		(layer "F.Cu")
		(at 13.589 -41.91)
		(property "Reference" "R383"
			(at 0 1.17475 0)
			(unlocked yes)
			(layer "F.SilkS")
			(effects
				(font
					(size 0.635 0.4064)
					(thickness 0.1524)
				)
			)
		)
		(property "Value" "VAL*"
			(at 0.02032 2.13233 0)
			(unlocked yes)
			(layer "F.Fab")
			(hide yes)
			(effects
				(font
					(size 0.7874 0.5842)
					(thickness 0.1524)
				)
			)
		)
		(property "Tolerance" "TOL*"
			(at 0.044704 3.05435 0)
			(unlocked yes)
			(layer "Cmts.User")
			(hide yes)
			(effects
				(font
					(size 0.7874 0.5842)
					(thickness 0.1524)
				)
			)
		)
		(property "User Part Number" "PARTNUM*"
			(at 0.02032 4.024884 0)
			(unlocked yes)
			(layer "Cmts.User")
			(hide yes)
			(effects
				(font
					(size 0.7874 0.5842)
					(thickness 0.1524)
				)
			)
		)
		(property "Device Type" "RESISTOR-G155-14701-01,4.7KOHMA"
			(at 0.008382 1.210564 0)
			(unlocked yes)
			(layer "F.Fab")
			(hide yes)
			(effects
				(font
					(size 0.7874 0.5842)
					(thickness 0.1524)
				)
			)
		)
		(duplicate_pad_numbers_are_jumpers no)
		(fp_line
			(start -1.143 -0.5588)
			(end -1.143 0.5588)
			(stroke
				(width 0.1)
				(type default)
			)
			(layer "F.SilkS")
		)
		(fp_line
			(start -1.143 0.5588)
			(end 1.143 0.5588)
			(stroke
				(width 0.1)
				(type default)
			)
			(layer "F.SilkS")
		)
		(fp_line
			(start 1.143 -0.5588)
			(end -1.143 -0.5588)
			(stroke
				(width 0.1)
				(type default)
			)
			(layer "F.SilkS")
		)
		(fp_line
			(start 1.143 0.5588)
			(end 1.143 -0.5588)
			(stroke
				(width 0.1)
				(type default)
			)
			(layer "F.SilkS")
		)
		(fp_rect
			(start 1.143 0.5588)
			(end -1.143 -0.5588)
			(stroke
				(width 0)
				(type default)
			)
			(fill no)
			(layer "F.CrtYd")
		)
		(fp_line
			(start -0.508 -0.3048)
			(end -0.508 0.3048)
			(stroke
				(width 0.1)
				(type default)
			)
			(layer "F.Fab")
		)
		(fp_line
			(start -0.508 0.3048)
			(end 0.508 0.3048)
			(stroke
				(width 0.1)
				(type default)
			)
			(layer "F.Fab")
		)
		(fp_line
			(start 0.508 -0.3048)
			(end -0.508 -0.3048)
			(stroke
				(width 0.1)
				(type default)
			)
			(layer "F.Fab")
		)
		(fp_line
			(start 0.508 0.3048)
			(end 0.508 -0.3048)
			(stroke
				(width 0.1)
				(type default)
			)
			(layer "F.Fab")
		)
		(pad "1" smd rect
			(at -0.5334 0)
			(size 0.7112 0.6096)
			(layers "F.Cu" "F.Mask" "F.Paste")
			(net "XP3R3V_FPGA")
		)
		(pad "2" smd rect
			(at 0.5334 0)
			(size 0.7112 0.6096)
			(layers "F.Cu" "F.Mask" "F.Paste")
			(net "SMA2_SIG_IN_BF_EN_N")
		)
		(zone
			(layer "F.Cu")
			(hatch none 0.5)
			(connect_pads
				(clearance 0)
			)
			(min_thickness 0.25)
			(keepout
				(tracks not_allowed)
				(vias allowed)
				(pads allowed)
				(copperpour not_allowed)
				(footprints allowed)
			)
			(placement
				(enabled no)
				(sheetname "")
			)
			(fill
				(thermal_gap 0.5)
				(thermal_bridge_width 0.5)
				(island_removal_mode 0)
			)
			(polygon
				(pts
					(xy 13.6652 -41.6052) (xy 13.6652 -42.2148) (xy 13.5128 -42.2148) (xy 13.5128 -41.6052)
				)
			)
		)
		(zone
			(layer "F.Cu")
			(hatch none 0.5)
			(connect_pads
				(clearance 0)
			)
			(min_thickness 0.25)
			(keepout
				(tracks allowed)
				(vias not_allowed)
				(pads allowed)
				(copperpour not_allowed)
				(footprints allowed)
			)
			(placement
				(enabled no)
				(sheetname "")
			)
			(fill
				(thermal_gap 0.5)
				(thermal_bridge_width 0.5)
				(island_removal_mode 0)
			)
			(polygon
				(pts
					(xy 13.6652 -41.6052) (xy 13.6652 -42.2148) (xy 13.5128 -42.2148) (xy 13.5128 -41.6052)
				)
			)
		)
	)
	(footprint ""
		(layer "F.Cu")
		(at 16.129 -21.463)
		(property "Reference" "TP35"
			(at -0.08763 -0.9398 90)
			(unlocked yes)
			(layer "F.SilkS")
			(effects
				(font
					(size 0.7874 0.5842)
					(thickness 0.1524)
				)
				(justify left)
			)
		)
		(property "Value" ""
			(at 0 0 0)
			(layer "F.Fab")
			(effects
				(font
					(size 1.27 1.27)
				)
			)
		)
		(property "Device Type" "TP_PIONT-TP010CT020B030_PTH-TPA"
			(at -1.341882 0.996696 0)
			(unlocked yes)
			(layer "F.Fab")
			(hide yes)
			(effects
				(font
					(size 0.7874 0.5842)
					(thickness 0.000001)
				)
				(justify left)
			)
		)
		(duplicate_pad_numbers_are_jumpers no)
		(fp_poly
			(pts
				(arc
					(start 0.889 0)
					(mid -0.889 0)
					(end 0.889 0)
				)
			)
			(stroke
				(width 0)
				(type default)
			)
			(fill no)
			(layer "B.CrtYd")
		)
		(fp_poly
			(pts
				(arc
					(start 0.889 0)
					(mid -0.889 0)
					(end 0.889 0)
				)
			)
			(stroke
				(width 0)
				(type default)
			)
			(fill no)
			(layer "F.CrtYd")
		)
		(pad "1" thru_hole circle
			(at 0 0)
			(size 0.508 0.508)
			(drill 0.254)
			(layers "*.Cu" "*.Mask")
			(remove_unused_layers no)
			(net "SMA4_SIG_OUT_BF_EN_N")
			(clearance 0.1016)
			(padstack
				(mode front_inner_back)
				(layer "Inner"
					(shape circle)
					(size 0.508 0.508)
					(clearance 0.1016)
				)
				(layer "B.Cu"
					(shape circle)
					(size 0.762 0.762)
					(clearance -0.0254)
				)
			)
		)
	)
	(footprint ""
		(layer "F.Cu")
		(at 79.756 -46.99)
		(property "Reference" "R98"
			(at 0.127 14.13637 0)
			(unlocked yes)
			(layer "F.SilkS")
			(effects
				(font
					(size 0.7874 0.5842)
					(thickness 0.1524)
				)
			)
		)
		(property "Value" "VAL*"
			(at 0.02032 2.13233 0)
			(unlocked yes)
			(layer "F.Fab")
			(hide yes)
			(effects
				(font
					(size 0.7874 0.5842)
					(thickness 0.1524)
				)
			)
		)
		(property "Device Type" "RESISTOR-G155-100R0-J0,0OHM,-"
			(at 0.008382 1.210564 0)
			(unlocked yes)
			(layer "F.Fab")
			(hide yes)
			(effects
				(font
					(size 0.7874 0.5842)
					(thickness 0.1524)
				)
			)
		)
		(property "User Part Number" "PARTNUM*"
			(at 0.02032 4.024884 0)
			(unlocked yes)
			(layer "Cmts.User")
			(hide yes)
			(effects
				(font
					(size 0.7874 0.5842)
					(thickness 0.1524)
				)
			)
		)
		(property "Tolerance" "TOL*"
			(at 0.044704 3.05435 0)
			(unlocked yes)
			(layer "Cmts.User")
			(hide yes)
			(effects
				(font
					(size 0.7874 0.5842)
					(thickness 0.1524)
				)
			)
		)
		(duplicate_pad_numbers_are_jumpers no)
		(fp_line
			(start -1.143 -0.5588)
			(end -1.143 0.5588)
			(stroke
				(width 0.1)
				(type default)
			)
			(layer "F.SilkS")
		)
		(fp_line
			(start -1.143 0.5588)
			(end 1.143 0.5588)
			(stroke
				(width 0.1)
				(type default)
			)
			(layer "F.SilkS")
		)
		(fp_line
			(start 1.143 -0.5588)
			(end -1.143 -0.5588)
			(stroke
				(width 0.1)
				(type default)
			)
			(layer "F.SilkS")
		)
		(fp_line
			(start 1.143 0.5588)
			(end 1.143 -0.5588)
			(stroke
				(width 0.1)
				(type default)
			)
			(layer "F.SilkS")
		)
		(fp_poly
			(pts
				(xy -1.143 0.5588) (xy 1.143 0.5588) (xy 1.143 -0.5588) (xy -1.143 -0.5588)
			)
			(stroke
				(width 0)
				(type default)
			)
			(fill no)
			(layer "F.CrtYd")
		)
		(fp_line
			(start -0.508 -0.3048)
			(end -0.508 0.3048)
			(stroke
				(width 0.1)
				(type default)
			)
			(layer "F.Fab")
		)
		(fp_line
			(start -0.508 0.3048)
			(end 0.508 0.3048)
			(stroke
				(width 0.1)
				(type default)
			)
			(layer "F.Fab")
		)
		(fp_line
			(start 0.508 -0.3048)
			(end -0.508 -0.3048)
			(stroke
				(width 0.1)
				(type default)
			)
			(layer "F.Fab")
		)
		(fp_line
			(start 0.508 0.3048)
			(end 0.508 -0.3048)
			(stroke
				(width 0.1)
				(type default)
			)
			(layer "F.Fab")
		)
		(pad "1" smd rect
			(at -0.5334 0)
			(size 0.7112 0.6096)
			(layers "F.Cu" "F.Mask" "F.Paste")
			(net "R_MAC_USB_DM")
		)
		(pad "2" smd rect
			(at 0.5334 0)
			(size 0.7112 0.6096)
			(layers "F.Cu" "F.Mask" "F.Paste")
			(net "MUX_USB_DM")
		)
		(zone
			(layer "F.Cu")
			(hatch none 0.5)
			(connect_pads
				(clearance 0)
			)
			(min_thickness 0.25)
			(keepout
				(tracks not_allowed)
				(vias allowed)
				(pads allowed)
				(copperpour not_allowed)
				(footprints allowed)
			)
			(placement
				(enabled no)
				(sheetname "")
			)
			(fill
				(thermal_gap 0.5)
				(thermal_bridge_width 0.5)
				(island_removal_mode 0)
			)
			(polygon
				(pts
					(xy 79.6798 -46.6852) (xy 79.8322 -46.6852) (xy 79.8322 -47.2948) (xy 79.6798 -47.2948)
				)
			)
		)
		(zone
			(layer "F.Cu")
			(hatch none 0.5)
			(connect_pads
				(clearance 0)
			)
			(min_thickness 0.25)
			(keepout
				(tracks allowed)
				(vias not_allowed)
				(pads allowed)
				(copperpour not_allowed)
				(footprints allowed)
			)
			(placement
				(enabled no)
				(sheetname "")
			)
			(fill
				(thermal_gap 0.5)
				(thermal_bridge_width 0.5)
				(island_removal_mode 0)
			)
			(polygon
				(pts
					(xy 79.6798 -46.6852) (xy 79.8322 -46.6852) (xy 79.8322 -47.2948) (xy 79.6798 -47.2948)
				)
			)
		)
	)
	(footprint ""
		(layer "F.Cu")
		(at 133.223 -37.338)
		(property "Reference" "C177"
			(at 4.445 3.97637 0)
			(unlocked yes)
			(layer "F.SilkS")
			(effects
				(font
					(size 0.7874 0.5842)
					(thickness 0.1524)
				)
			)
		)
		(property "Value" "VAL*"
			(at 0.1016 3.769106 0)
			(unlocked yes)
			(layer "F.Fab")
			(hide yes)
			(effects
				(font
					(size 0.7874 0.5842)
					(thickness 0.1524)
				)
			)
		)
		(property "Tolerance" "TOL*"
			(at 0.127 4.734306 0)
			(unlocked yes)
			(layer "Cmts.User")
			(hide yes)
			(effects
				(font
					(size 0.7874 0.5842)
					(thickness 0.1524)
				)
			)
		)
		(property "User Part Number" "PARTNUM*"
			(at 0.2032 5.801106 0)
			(unlocked yes)
			(layer "Cmts.User")
			(hide yes)
			(effects
				(font
					(size 0.7874 0.5842)
					(thickness 0.1524)
				)
			)
		)
		(property "Device Type" "CAPACITOR-G109-0G107-BM,100UF,A"
			(at 0.0762 2.829306 0)
			(unlocked yes)
			(layer "F.Fab")
			(hide yes)
			(effects
				(font
					(size 0.7874 0.5842)
					(thickness 0.1524)
				)
			)
		)
		(duplicate_pad_numbers_are_jumpers no)
		(fp_line
			(start -2.159 -1.5748)
			(end 2.159 -1.5748)
			(stroke
				(width 0.1)
				(type default)
			)
			(layer "F.SilkS")
		)
		(fp_line
			(start -2.159 1.5748)
			(end -2.159 -1.5748)
			(stroke
				(width 0.1)
				(type default)
			)
			(layer "F.SilkS")
		)
		(fp_line
			(start 2.159 -1.5748)
			(end 2.159 1.5748)
			(stroke
				(width 0.1)
				(type default)
			)
			(layer "F.SilkS")
		)
		(fp_line
			(start 2.159 1.5748)
			(end -2.159 1.5748)
			(stroke
				(width 0.1)
				(type default)
			)
			(layer "F.SilkS")
		)
		(fp_rect
			(start -2.159 -1.5748)
			(end 2.159 1.5748)
			(stroke
				(width 0)
				(type default)
			)
			(fill no)
			(layer "F.CrtYd")
		)
		(fp_line
			(start -1.6002 -1.2446)
			(end -1.6002 1.2446)
			(stroke
				(width 0.1)
				(type default)
			)
			(layer "F.Fab")
		)
		(fp_line
			(start -1.6002 1.2446)
			(end 1.6002 1.2446)
			(stroke
				(width 0.1)
				(type default)
			)
			(layer "F.Fab")
		)
		(fp_line
			(start 1.6002 -1.2446)
			(end -1.6002 -1.2446)
			(stroke
				(width 0.1)
				(type default)
			)
			(layer "F.Fab")
		)
		(fp_line
			(start 1.6002 1.2446)
			(end 1.6002 -1.2446)
			(stroke
				(width 0.1)
				(type default)
			)
			(layer "F.Fab")
		)
		(pad "1" smd rect
			(at -1.3335 0)
			(size 1.143 2.6416)
			(layers "F.Cu" "F.Mask" "F.Paste")
			(net "XP1R0V_FPGA_VCCINT")
		)
		(pad "2" smd rect
			(at 1.3335 0)
			(size 1.143 2.6416)
			(layers "F.Cu" "F.Mask" "F.Paste")
			(net "SG")
		)
		(zone
			(layer "F.Cu")
			(hatch none 0.5)
			(connect_pads
				(clearance 0)
			)
			(min_thickness 0.25)
			(keepout
				(tracks allowed)
				(vias not_allowed)
				(pads allowed)
				(copperpour not_allowed)
				(footprints allowed)
			)
			(placement
				(enabled no)
				(sheetname "")
			)
			(fill
				(thermal_gap 0.5)
				(thermal_bridge_width 0.5)
				(island_removal_mode 0)
			)
			(polygon
				(pts
					(xy 132.5372 -38.735) (xy 132.5372 -35.941) (xy 133.9088 -35.941) (xy 133.9088 -38.735)
				)
			)
		)
	)
	(footprint ""
		(layer "F.Cu")
		(at 35.179 -104.267 -90)
		(property "Reference" "R6"
			(at -1.397 4.02463 90)
			(unlocked yes)
			(layer "F.SilkS")
			(effects
				(font
					(size 0.7874 0.5842)
					(thickness 0.1524)
				)
			)
		)
		(property "Value" "VAL*"
			(at 0.02032 2.13233 270)
			(unlocked yes)
			(layer "F.Fab")
			(hide yes)
			(effects
				(font
					(size 0.7874 0.5842)
					(thickness 0.1524)
				)
			)
		)
		(property "Device Type" "RESISTOR-G155-120R0-01,20OHM,1%"
			(at 0.008382 1.210564 270)
			(unlocked yes)
			(layer "F.Fab")
			(hide yes)
			(effects
				(font
					(size 0.7874 0.5842)
					(thickness 0.1524)
				)
			)
		)
		(property "User Part Number" "PARTNUM*"
			(at 0.02032 4.024884 270)
			(unlocked yes)
			(layer "Cmts.User")
			(hide yes)
			(effects
				(font
					(size 0.7874 0.5842)
					(thickness 0.1524)
				)
			)
		)
		(property "Tolerance" "TOL*"
			(at 0.044704 3.05435 270)
			(unlocked yes)
			(layer "Cmts.User")
			(hide yes)
			(effects
				(font
					(size 0.7874 0.5842)
					(thickness 0.1524)
				)
			)
		)
		(duplicate_pad_numbers_are_jumpers no)
		(fp_line
			(start -1.143 0.5588)
			(end 1.143 0.5588)
			(stroke
				(width 0.1)
				(type default)
			)
			(layer "F.SilkS")
		)
		(fp_line
			(start 1.143 0.5588)
			(end 1.143 -0.5588)
			(stroke
				(width 0.1)
				(type default)
			)
			(layer "F.SilkS")
		)
		(fp_line
			(start -1.143 -0.5588)
			(end -1.143 0.5588)
			(stroke
				(width 0.1)
				(type default)
			)
			(layer "F.SilkS")
		)
		(fp_line
			(start 1.143 -0.5588)
			(end -1.143 -0.5588)
			(stroke
				(width 0.1)
				(type default)
			)
			(layer "F.SilkS")
		)
		(fp_rect
			(start -1.143 -0.5588)
			(end 1.143 0.5588)
			(stroke
				(width 0)
				(type default)
			)
			(fill no)
			(layer "F.CrtYd")
		)
		(fp_line
			(start -0.508 0.3048)
			(end 0.508 0.3048)
			(stroke
				(width 0.1)
				(type default)
			)
			(layer "F.Fab")
		)
		(fp_line
			(start 0.508 0.3048)
			(end 0.508 -0.3048)
			(stroke
				(width 0.1)
				(type default)
			)
			(layer "F.Fab")
		)
		(fp_line
			(start -0.508 -0.3048)
			(end -0.508 0.3048)
			(stroke
				(width 0.1)
				(type default)
			)
			(layer "F.Fab")
		)
		(fp_line
			(start 0.508 -0.3048)
			(end -0.508 -0.3048)
			(stroke
				(width 0.1)
				(type default)
			)
			(layer "F.Fab")
		)
		(pad "1" smd rect
			(at -0.5334 0 270)
			(size 0.7112 0.6096)
			(layers "F.Cu" "F.Mask" "F.Paste")
			(net "XP5R0V")
		)
		(pad "2" smd rect
			(at 0.5334 0 270)
			(size 0.7112 0.6096)
			(layers "F.Cu" "F.Mask" "F.Paste")
			(net "UNNAMED_516_CAPACITOR_I29_1")
		)
		(zone
			(layer "F.Cu")
			(hatch none 0.5)
			(connect_pads
				(clearance 0)
			)
			(min_thickness 0.25)
			(keepout
				(tracks allowed)
				(vias not_allowed)
				(pads allowed)
				(copperpour not_allowed)
				(footprints allowed)
			)
			(placement
				(enabled no)
				(sheetname "")
			)
			(fill
				(thermal_gap 0.5)
				(thermal_bridge_width 0.5)
				(island_removal_mode 0)
			)
			(polygon
				(pts
					(xy 35.4838 -104.3432) (xy 34.8742 -104.3432) (xy 34.8742 -104.1908) (xy 35.4838 -104.1908)
				)
			)
		)
	)
	(footprint ""
		(layer "F.Cu")
		(at 84.709 -64.3128 -90)
		(property "Reference" "R304"
			(at -13.4112 9.99363 90)
			(unlocked yes)
			(layer "F.SilkS")
			(effects
				(font
					(size 0.7874 0.5842)
					(thickness 0.1524)
				)
			)
		)
		(property "Value" "VAL*"
			(at 0.02032 2.13233 270)
			(unlocked yes)
			(layer "F.Fab")
			(hide yes)
			(effects
				(font
					(size 0.7874 0.5842)
					(thickness 0.1524)
				)
			)
		)
		(property "Device Type" "RESISTOR-G155-14701-01,4.7KOHMA"
			(at 0.008382 1.210564 270)
			(unlocked yes)
			(layer "F.Fab")
			(hide yes)
			(effects
				(font
					(size 0.7874 0.5842)
					(thickness 0.1524)
				)
			)
		)
		(property "User Part Number" "PARTNUM*"
			(at 0.02032 4.024884 270)
			(unlocked yes)
			(layer "Cmts.User")
			(hide yes)
			(effects
				(font
					(size 0.7874 0.5842)
					(thickness 0.1524)
				)
			)
		)
		(property "Tolerance" "TOL*"
			(at 0.044704 3.05435 270)
			(unlocked yes)
			(layer "Cmts.User")
			(hide yes)
			(effects
				(font
					(size 0.7874 0.5842)
					(thickness 0.1524)
				)
			)
		)
		(duplicate_pad_numbers_are_jumpers no)
		(fp_line
			(start -1.143 0.5588)
			(end 1.143 0.5588)
			(stroke
				(width 0.1)
				(type default)
			)
			(layer "F.SilkS")
		)
		(fp_line
			(start 1.143 0.5588)
			(end 1.143 -0.5588)
			(stroke
				(width 0.1)
				(type default)
			)
			(layer "F.SilkS")
		)
		(fp_line
			(start -1.143 -0.5588)
			(end -1.143 0.5588)
			(stroke
				(width 0.1)
				(type default)
			)
			(layer "F.SilkS")
		)
		(fp_line
			(start 1.143 -0.5588)
			(end -1.143 -0.5588)
			(stroke
				(width 0.1)
				(type default)
			)
			(layer "F.SilkS")
		)
		(fp_rect
			(start 1.143 0.5588)
			(end -1.143 -0.5588)
			(stroke
				(width 0)
				(type default)
			)
			(fill no)
			(layer "F.CrtYd")
		)
		(fp_line
			(start -0.508 0.3048)
			(end 0.508 0.3048)
			(stroke
				(width 0.1)
				(type default)
			)
			(layer "F.Fab")
		)
		(fp_line
			(start 0.508 0.3048)
			(end 0.508 -0.3048)
			(stroke
				(width 0.1)
				(type default)
			)
			(layer "F.Fab")
		)
		(fp_line
			(start -0.508 -0.3048)
			(end -0.508 0.3048)
			(stroke
				(width 0.1)
				(type default)
			)
			(layer "F.Fab")
		)
		(fp_line
			(start 0.508 -0.3048)
			(end -0.508 -0.3048)
			(stroke
				(width 0.1)
				(type default)
			)
			(layer "F.Fab")
		)
		(pad "1" smd rect
			(at -0.5334 0 270)
			(size 0.7112 0.6096)
			(layers "F.Cu" "F.Mask" "F.Paste")
			(net "XP3R3V_FPGA")
		)
		(pad "2" smd rect
			(at 0.5334 0 270)
			(size 0.7112 0.6096)
			(layers "F.Cu" "F.Mask" "F.Paste")
			(net "R_BNO080_BOOT_N")
		)
		(zone
			(layer "F.Cu")
			(hatch none 0.5)
			(connect_pads
				(clearance 0)
			)
			(min_thickness 0.25)
			(keepout
				(tracks allowed)
				(vias not_allowed)
				(pads allowed)
				(copperpour not_allowed)
				(footprints allowed)
			)
			(placement
				(enabled no)
				(sheetname "")
			)
			(fill
				(thermal_gap 0.5)
				(thermal_bridge_width 0.5)
				(island_removal_mode 0)
			)
			(polygon
				(pts
					(xy 84.4042 -64.2366) (xy 85.0138 -64.2366) (xy 85.0138 -64.389) (xy 84.4042 -64.389)
				)
			)
		)
	)
	(footprint ""
		(layer "F.Cu")
		(at 112.776 -61.976 90)
		(property "Reference" "R214"
			(at 3.302 0.42037 90)
			(unlocked yes)
			(layer "F.SilkS")
			(effects
				(font
					(size 0.7874 0.5842)
					(thickness 0.1524)
				)
			)
		)
		(property "Value" "VAL*"
			(at 0.02032 2.13233 90)
			(unlocked yes)
			(layer "F.Fab")
			(hide yes)
			(effects
				(font
					(size 0.7874 0.5842)
					(thickness 0.1524)
				)
			)
		)
		(property "Device Type" "RESISTOR-G155-11001-01,1KOHM,1%"
			(at 0.008382 1.210564 90)
			(unlocked yes)
			(layer "F.Fab")
			(hide yes)
			(effects
				(font
					(size 0.7874 0.5842)
					(thickness 0.1524)
				)
			)
		)
		(property "User Part Number" "PARTNUM*"
			(at 0.02032 4.024884 90)
			(unlocked yes)
			(layer "Cmts.User")
			(hide yes)
			(effects
				(font
					(size 0.7874 0.5842)
					(thickness 0.1524)
				)
			)
		)
		(property "Tolerance" "TOL*"
			(at 0.044704 3.05435 90)
			(unlocked yes)
			(layer "Cmts.User")
			(hide yes)
			(effects
				(font
					(size 0.7874 0.5842)
					(thickness 0.1524)
				)
			)
		)
		(duplicate_pad_numbers_are_jumpers no)
		(fp_line
			(start 1.143 -0.5588)
			(end -1.143 -0.5588)
			(stroke
				(width 0.1)
				(type default)
			)
			(layer "F.SilkS")
		)
		(fp_line
			(start -1.143 -0.5588)
			(end -1.143 0.5588)
			(stroke
				(width 0.1)
				(type default)
			)
			(layer "F.SilkS")
		)
		(fp_line
			(start 1.143 0.5588)
			(end 1.143 -0.5588)
			(stroke
				(width 0.1)
				(type default)
			)
			(layer "F.SilkS")
		)
		(fp_line
			(start -1.143 0.5588)
			(end 1.143 0.5588)
			(stroke
				(width 0.1)
				(type default)
			)
			(layer "F.SilkS")
		)
		(fp_rect
			(start -1.143 0.5588)
			(end 1.143 -0.5588)
			(stroke
				(width 0)
				(type default)
			)
			(fill no)
			(layer "F.CrtYd")
		)
		(fp_line
			(start 0.508 -0.3048)
			(end -0.508 -0.3048)
			(stroke
				(width 0.1)
				(type default)
			)
			(layer "F.Fab")
		)
		(fp_line
			(start -0.508 -0.3048)
			(end -0.508 0.3048)
			(stroke
				(width 0.1)
				(type default)
			)
			(layer "F.Fab")
		)
		(fp_line
			(start 0.508 0.3048)
			(end 0.508 -0.3048)
			(stroke
				(width 0.1)
				(type default)
			)
			(layer "F.Fab")
		)
		(fp_line
			(start -0.508 0.3048)
			(end 0.508 0.3048)
			(stroke
				(width 0.1)
				(type default)
			)
			(layer "F.Fab")
		)
		(pad "1" smd rect
			(at -0.5334 0 90)
			(size 0.7112 0.6096)
			(layers "F.Cu" "F.Mask" "F.Paste")
			(net "FPGA_BRD_REV2")
		)
		(pad "2" smd rect
			(at 0.5334 0 90)
			(size 0.7112 0.6096)
			(layers "F.Cu" "F.Mask" "F.Paste")
			(net "SG")
		)
		(zone
			(layer "F.Cu")
			(hatch none 0.5)
			(connect_pads
				(clearance 0)
			)
			(min_thickness 0.25)
			(keepout
				(tracks allowed)
				(vias not_allowed)
				(pads allowed)
				(copperpour not_allowed)
				(footprints allowed)
			)
			(placement
				(enabled no)
				(sheetname "")
			)
			(fill
				(thermal_gap 0.5)
				(thermal_bridge_width 0.5)
				(island_removal_mode 0)
			)
			(polygon
				(pts
					(xy 113.0808 -61.8998) (xy 113.0808 -62.0522) (xy 112.4712 -62.0522) (xy 112.4712 -61.8998)
				)
			)
		)
	)
	(footprint ""
		(layer "F.Cu")
		(at 33.77438 -17.9832 180)
		(property "Reference" "R184"
			(at -2.80162 -1.38557 0)
			(unlocked yes)
			(layer "F.SilkS")
			(effects
				(font
					(size 0.7874 0.5842)
					(thickness 0.1524)
				)
			)
		)
		(property "Value" "VAL*"
			(at 0.02032 2.13233 180)
			(unlocked yes)
			(layer "F.Fab")
			(hide yes)
			(effects
				(font
					(size 0.7874 0.5842)
					(thickness 0.1524)
				)
			)
		)
		(property "Tolerance" "TOL*"
			(at 0.044704 3.05435 180)
			(unlocked yes)
			(layer "Cmts.User")
			(hide yes)
			(effects
				(font
					(size 0.7874 0.5842)
					(thickness 0.1524)
				)
			)
		)
		(property "User Part Number" "PARTNUM*"
			(at 0.02032 4.024884 180)
			(unlocked yes)
			(layer "Cmts.User")
			(hide yes)
			(effects
				(font
					(size 0.7874 0.5842)
					(thickness 0.1524)
				)
			)
		)
		(property "Device Type" "RESISTOR-G155-133R0-01,33OHM,1%"
			(at 0.008382 1.210564 180)
			(unlocked yes)
			(layer "F.Fab")
			(hide yes)
			(effects
				(font
					(size 0.7874 0.5842)
					(thickness 0.1524)
				)
			)
		)
		(duplicate_pad_numbers_are_jumpers no)
		(fp_line
			(start 1.143 0.5588)
			(end 1.143 -0.5588)
			(stroke
				(width 0.1)
				(type default)
			)
			(layer "F.SilkS")
		)
		(fp_line
			(start 1.143 -0.5588)
			(end -1.143 -0.5588)
			(stroke
				(width 0.1)
				(type default)
			)
			(layer "F.SilkS")
		)
		(fp_line
			(start -1.143 0.5588)
			(end 1.143 0.5588)
			(stroke
				(width 0.1)
				(type default)
			)
			(layer "F.SilkS")
		)
		(fp_line
			(start -1.143 -0.5588)
			(end -1.143 0.5588)
			(stroke
				(width 0.1)
				(type default)
			)
			(layer "F.SilkS")
		)
		(fp_rect
			(start 1.143 -0.5588)
			(end -1.143 0.5588)
			(stroke
				(width 0)
				(type default)
			)
			(fill no)
			(layer "F.CrtYd")
		)
		(fp_line
			(start 0.508 0.3048)
			(end 0.508 -0.3048)
			(stroke
				(width 0.1)
				(type default)
			)
			(layer "F.Fab")
		)
		(fp_line
			(start 0.508 -0.3048)
			(end -0.508 -0.3048)
			(stroke
				(width 0.1)
				(type default)
			)
			(layer "F.Fab")
		)
		(fp_line
			(start -0.508 0.3048)
			(end 0.508 0.3048)
			(stroke
				(width 0.1)
				(type default)
			)
			(layer "F.Fab")
		)
		(fp_line
			(start -0.508 -0.3048)
			(end -0.508 0.3048)
			(stroke
				(width 0.1)
				(type default)
			)
			(layer "F.Fab")
		)
		(pad "1" smd rect
			(at -0.5334 0 180)
			(size 0.7112 0.6096)
			(layers "F.Cu" "F.Mask" "F.Paste")
			(net "EEPROM_I2C_SCL")
		)
		(pad "2" smd rect
			(at 0.5334 0 180)
			(size 0.7112 0.6096)
			(layers "F.Cu" "F.Mask" "F.Paste")
			(net "EEPROM_SCL")
		)
		(zone
			(layer "F.Cu")
			(hatch none 0.5)
			(connect_pads
				(clearance 0)
			)
			(min_thickness 0.25)
			(keepout
				(tracks allowed)
				(vias not_allowed)
				(pads allowed)
				(copperpour not_allowed)
				(footprints allowed)
			)
			(placement
				(enabled no)
				(sheetname "")
			)
			(fill
				(thermal_gap 0.5)
				(thermal_bridge_width 0.5)
				(island_removal_mode 0)
			)
			(polygon
				(pts
					(xy 33.69818 -17.6784) (xy 33.85058 -17.6784) (xy 33.85058 -18.288) (xy 33.69818 -18.288)
				)
			)
		)
	)
	(footprint ""
		(layer "F.Cu")
		(at 122.809 -89.535 -90)
		(property "Reference" "R117"
			(at 3.429 -0.29337 90)
			(unlocked yes)
			(layer "F.SilkS")
			(effects
				(font
					(size 0.7874 0.5842)
					(thickness 0.1524)
				)
			)
		)
		(property "Value" "VAL*"
			(at 0.02032 2.13233 270)
			(unlocked yes)
			(layer "F.Fab")
			(hide yes)
			(effects
				(font
					(size 0.7874 0.5842)
					(thickness 0.1524)
				)
			)
		)
		(property "Device Type" "RESISTOR-G155-133R0-01,33OHM,1%"
			(at 0.008382 1.210564 270)
			(unlocked yes)
			(layer "F.Fab")
			(hide yes)
			(effects
				(font
					(size 0.7874 0.5842)
					(thickness 0.1524)
				)
			)
		)
		(property "User Part Number" "PARTNUM*"
			(at 0.02032 4.024884 270)
			(unlocked yes)
			(layer "Cmts.User")
			(hide yes)
			(effects
				(font
					(size 0.7874 0.5842)
					(thickness 0.1524)
				)
			)
		)
		(property "Tolerance" "TOL*"
			(at 0.044704 3.05435 270)
			(unlocked yes)
			(layer "Cmts.User")
			(hide yes)
			(effects
				(font
					(size 0.7874 0.5842)
					(thickness 0.1524)
				)
			)
		)
		(duplicate_pad_numbers_are_jumpers no)
		(fp_line
			(start -1.143 0.5588)
			(end 1.143 0.5588)
			(stroke
				(width 0.1)
				(type default)
			)
			(layer "F.SilkS")
		)
		(fp_line
			(start 1.143 0.5588)
			(end 1.143 -0.5588)
			(stroke
				(width 0.1)
				(type default)
			)
			(layer "F.SilkS")
		)
		(fp_line
			(start -1.143 -0.5588)
			(end -1.143 0.5588)
			(stroke
				(width 0.1)
				(type default)
			)
			(layer "F.SilkS")
		)
		(fp_line
			(start 1.143 -0.5588)
			(end -1.143 -0.5588)
			(stroke
				(width 0.1)
				(type default)
			)
			(layer "F.SilkS")
		)
		(fp_rect
			(start 1.143 -0.5588)
			(end -1.143 0.5588)
			(stroke
				(width 0)
				(type default)
			)
			(fill no)
			(layer "F.CrtYd")
		)
		(fp_line
			(start -0.508 0.3048)
			(end 0.508 0.3048)
			(stroke
				(width 0.1)
				(type default)
			)
			(layer "F.Fab")
		)
		(fp_line
			(start 0.508 0.3048)
			(end 0.508 -0.3048)
			(stroke
				(width 0.1)
				(type default)
			)
			(layer "F.Fab")
		)
		(fp_line
			(start -0.508 -0.3048)
			(end -0.508 0.3048)
			(stroke
				(width 0.1)
				(type default)
			)
			(layer "F.Fab")
		)
		(fp_line
			(start 0.508 -0.3048)
			(end -0.508 -0.3048)
			(stroke
				(width 0.1)
				(type default)
			)
			(layer "F.Fab")
		)
		(pad "1" smd rect
			(at -0.5334 0 270)
			(size 0.7112 0.6096)
			(layers "F.Cu" "F.Mask" "F.Paste")
			(net "GPSTP1_OUT")
		)
		(pad "2" smd rect
			(at 0.5334 0 270)
			(size 0.7112 0.6096)
			(layers "F.Cu" "F.Mask" "F.Paste")
			(net "FPGA_IN_GPSTP1_OUT")
		)
		(zone
			(layer "F.Cu")
			(hatch none 0.5)
			(connect_pads
				(clearance 0)
			)
			(min_thickness 0.25)
			(keepout
				(tracks allowed)
				(vias not_allowed)
				(pads allowed)
				(copperpour not_allowed)
				(footprints allowed)
			)
			(placement
				(enabled no)
				(sheetname "")
			)
			(fill
				(thermal_gap 0.5)
				(thermal_bridge_width 0.5)
				(island_removal_mode 0)
			)
			(polygon
				(pts
					(xy 123.1138 -89.4588) (xy 123.1138 -89.6112) (xy 122.5042 -89.6112) (xy 122.5042 -89.4588)
				)
			)
		)
	)
	(footprint ""
		(layer "F.Cu")
		(at 14.5034 -98.3488 90)
		(property "Reference" "L20"
			(at -1.1303 -1.25603 90)
			(unlocked yes)
			(layer "F.SilkS")
			(effects
				(font
					(size 0.7874 0.5842)
					(thickness 0.1524)
				)
				(justify left)
			)
		)
		(property "Value" "VAL*"
			(at -0.9398 3.70967 90)
			(unlocked yes)
			(layer "F.Fab")
			(hide yes)
			(effects
				(font
					(size 0.7874 0.5842)
					(thickness 0.1524)
				)
				(justify left)
			)
		)
		(property "Tolerance" "TOL*"
			(at -0.9906 5.00507 90)
			(unlocked yes)
			(layer "Cmts.User")
			(hide yes)
			(effects
				(font
					(size 0.7874 0.5842)
					(thickness 0.1524)
				)
				(justify left)
			)
		)
		(property "User Part Number" "PARTNUM*"
			(at -2.54 2.46507 90)
			(unlocked yes)
			(layer "Cmts.User")
			(hide yes)
			(effects
				(font
					(size 0.7874 0.5842)
					(thickness 0.1524)
				)
				(justify left)
			)
		)
		(property "Device Type" "FERRITEBEAD-G191-10101-01,26OHA"
			(at -0.9906 1.22047 90)
			(unlocked yes)
			(layer "F.Fab")
			(hide yes)
			(effects
				(font
					(size 0.7874 0.5842)
					(thickness 0.1524)
				)
				(justify left)
			)
		)
		(duplicate_pad_numbers_are_jumpers no)
		(fp_line
			(start 1.3208 -0.7112)
			(end 1.3208 0.7112)
			(stroke
				(width 0.1)
				(type default)
			)
			(layer "F.SilkS")
		)
		(fp_line
			(start -1.3208 -0.7112)
			(end 1.3208 -0.7112)
			(stroke
				(width 0.1)
				(type default)
			)
			(layer "F.SilkS")
		)
		(fp_line
			(start 1.3208 0.7112)
			(end -1.3208 0.7112)
			(stroke
				(width 0.1)
				(type default)
			)
			(layer "F.SilkS")
		)
		(fp_line
			(start -1.3208 0.7112)
			(end -1.3208 -0.7112)
			(stroke
				(width 0.1)
				(type default)
			)
			(layer "F.SilkS")
		)
		(fp_rect
			(start -1.3208 0.7112)
			(end 1.3208 -0.7112)
			(stroke
				(width 0)
				(type default)
			)
			(fill no)
			(layer "F.CrtYd")
		)
		(fp_line
			(start 0.8128 -0.4572)
			(end 0.8128 0.4572)
			(stroke
				(width 0.1)
				(type default)
			)
			(layer "F.Fab")
		)
		(fp_line
			(start -0.8128 -0.4572)
			(end 0.8128 -0.4572)
			(stroke
				(width 0.1)
				(type default)
			)
			(layer "F.Fab")
		)
		(fp_line
			(start 0.8128 0.4572)
			(end -0.8128 0.4572)
			(stroke
				(width 0.1)
				(type default)
			)
			(layer "F.Fab")
		)
		(fp_line
			(start -0.8128 0.4572)
			(end -0.8128 -0.4572)
			(stroke
				(width 0.1)
				(type default)
			)
			(layer "F.Fab")
		)
		(pad "1" smd rect
			(at -0.6858 0 90)
			(size 0.762 0.8636)
			(layers "F.Cu" "F.Mask" "F.Paste")
			(net "XP12R0V_PCIE")
		)
		(pad "2" smd rect
			(at 0.6858 0 90)
			(size 0.762 0.8636)
			(layers "F.Cu" "F.Mask" "F.Paste")
			(net "XP12R0V_IN")
		)
		(zone
			(layer "F.Cu")
			(hatch none 0.5)
			(connect_pads
				(clearance 0)
			)
			(min_thickness 0.25)
			(keepout
				(tracks not_allowed)
				(vias allowed)
				(pads allowed)
				(copperpour not_allowed)
				(footprints allowed)
			)
			(placement
				(enabled no)
				(sheetname "")
			)
			(fill
				(thermal_gap 0.5)
				(thermal_bridge_width 0.5)
				(island_removal_mode 0)
			)
			(polygon
				(pts
					(xy 14.9606 -98.1964) (xy 14.9606 -98.5012) (xy 14.0462 -98.5012) (xy 14.0462 -98.1964)
				)
			)
		)
		(zone
			(layer "F.Cu")
			(hatch none 0.5)
			(connect_pads
				(clearance 0)
			)
			(min_thickness 0.25)
			(keepout
				(tracks allowed)
				(vias not_allowed)
				(pads allowed)
				(copperpour not_allowed)
				(footprints allowed)
			)
			(placement
				(enabled no)
				(sheetname "")
			)
			(fill
				(thermal_gap 0.5)
				(thermal_bridge_width 0.5)
				(island_removal_mode 0)
			)
			(polygon
				(pts
					(xy 14.9606 -98.1964) (xy 14.9606 -98.5012) (xy 14.0462 -98.5012) (xy 14.0462 -98.1964)
				)
			)
		)
	)
	(footprint ""
		(layer "F.Cu")
		(at 108.0516 -58.3184)
		(property "Reference" "TP188"
			(at 2.85115 2.1082 90)
			(unlocked yes)
			(layer "F.SilkS")
			(effects
				(font
					(size 0.635 0.4064)
					(thickness 0.1524)
				)
				(justify left)
			)
		)
		(property "Value" ""
			(at 0 0 0)
			(layer "F.Fab")
			(effects
				(font
					(size 1.27 1.27)
				)
			)
		)
		(property "Device Type" "TP_PIONT-TP010CT020B030_PTH-TPA"
			(at -1.341882 0.996696 0)
			(unlocked yes)
			(layer "F.Fab")
			(hide yes)
			(effects
				(font
					(size 0.7874 0.5842)
					(thickness 0.1524)
				)
				(justify left)
			)
		)
		(duplicate_pad_numbers_are_jumpers no)
		(fp_poly
			(pts
				(arc
					(start 0.889 0)
					(mid -0.889 0)
					(end 0.889 0)
				)
			)
			(stroke
				(width 0)
				(type default)
			)
			(fill no)
			(layer "B.CrtYd")
		)
		(fp_poly
			(pts
				(arc
					(start 0.889 0)
					(mid -0.889 0)
					(end 0.889 0)
				)
			)
			(stroke
				(width 0)
				(type default)
			)
			(fill no)
			(layer "F.CrtYd")
		)
		(pad "1" thru_hole circle
			(at 0 0)
			(size 0.508 0.508)
			(drill 0.254)
			(layers "*.Cu" "*.Mask")
			(remove_unused_layers no)
			(net "IO_L24N_16")
			(clearance 0.1016)
			(padstack
				(mode front_inner_back)
				(layer "Inner"
					(shape circle)
					(size 0.508 0.508)
					(clearance 0.1016)
				)
				(layer "B.Cu"
					(shape circle)
					(size 0.762 0.762)
					(clearance -0.0254)
				)
			)
		)
	)
	(footprint ""
		(layer "F.Cu")
		(at 46.101 -82.804)
		(property "Reference" "C284"
			(at 0.127 -2.24663 0)
			(unlocked yes)
			(layer "F.SilkS")
			(effects
				(font
					(size 0.7874 0.5842)
					(thickness 0.1524)
				)
			)
		)
		(property "Value" "VAL*"
			(at 0.0762 3.134106 0)
			(unlocked yes)
			(layer "F.Fab")
			(hide yes)
			(effects
				(font
					(size 0.7874 0.5842)
					(thickness 0.1524)
				)
			)
		)
		(property "Tolerance" "TOL*"
			(at 0.0762 4.048506 0)
			(unlocked yes)
			(layer "Cmts.User")
			(hide yes)
			(effects
				(font
					(size 0.7874 0.5842)
					(thickness 0.1524)
				)
			)
		)
		(property "User Part Number" "PARTNUM*"
			(at 0.1016 5.013706 0)
			(unlocked yes)
			(layer "Cmts.User")
			(hide yes)
			(effects
				(font
					(size 0.7874 0.5842)
					(thickness 0.1524)
				)
			)
		)
		(property "Device Type" "CAPACITOR-G107-0F226-CM,22UF,2A"
			(at 0.0508 2.194306 0)
			(unlocked yes)
			(layer "F.Fab")
			(hide yes)
			(effects
				(font
					(size 0.7874 0.5842)
					(thickness 0.1524)
				)
			)
		)
		(duplicate_pad_numbers_are_jumpers no)
		(fp_line
			(start -1.5748 -0.9398)
			(end -1.5748 0.9398)
			(stroke
				(width 0.1)
				(type default)
			)
			(layer "F.SilkS")
		)
		(fp_line
			(start -1.5748 0.9398)
			(end 1.5748 0.9398)
			(stroke
				(width 0.1)
				(type default)
			)
			(layer "F.SilkS")
		)
		(fp_line
			(start 1.5748 -0.9398)
			(end -1.5748 -0.9398)
			(stroke
				(width 0.1)
				(type default)
			)
			(layer "F.SilkS")
		)
		(fp_line
			(start 1.5748 0.9398)
			(end 1.5748 -0.9398)
			(stroke
				(width 0.1)
				(type default)
			)
			(layer "F.SilkS")
		)
		(fp_poly
			(pts
				(xy -1.5748 0.9398) (xy 1.5748 0.9398) (xy 1.5748 -0.9398) (xy -1.5748 -0.9398)
			)
			(stroke
				(width 0)
				(type default)
			)
			(fill no)
			(layer "F.CrtYd")
		)
		(fp_line
			(start -1.016 -0.635)
			(end -1.016 0.635)
			(stroke
				(width 0.1)
				(type default)
			)
			(layer "F.Fab")
		)
		(fp_line
			(start -1.016 0.635)
			(end 1.016 0.635)
			(stroke
				(width 0.1)
				(type default)
			)
			(layer "F.Fab")
		)
		(fp_line
			(start 1.016 -0.635)
			(end -1.016 -0.635)
			(stroke
				(width 0.1)
				(type default)
			)
			(layer "F.Fab")
		)
		(fp_line
			(start 1.016 0.635)
			(end 1.016 -0.635)
			(stroke
				(width 0.1)
				(type default)
			)
			(layer "F.Fab")
		)
		(pad "1" smd rect
			(at -0.8382 0)
			(size 0.9652 1.3716)
			(layers "F.Cu" "F.Mask" "F.Paste")
			(net "UNNAMED_525_CAPACITOR_I7_1")
		)
		(pad "2" smd rect
			(at 0.8382 0)
			(size 0.9652 1.3716)
			(layers "F.Cu" "F.Mask" "F.Paste")
			(net "SG")
		)
		(zone
			(layer "F.Cu")
			(hatch none 0.5)
			(connect_pads
				(clearance 0)
			)
			(min_thickness 0.25)
			(keepout
				(tracks not_allowed)
				(vias allowed)
				(pads allowed)
				(copperpour not_allowed)
				(footprints allowed)
			)
			(placement
				(enabled no)
				(sheetname "")
			)
			(fill
				(thermal_gap 0.5)
				(thermal_bridge_width 0.5)
				(island_removal_mode 0)
			)
			(polygon
				(pts
					(xy 45.8724 -82.169) (xy 46.3296 -82.169) (xy 46.3296 -83.439) (xy 45.8724 -83.439)
				)
			)
		)
		(zone
			(layer "F.Cu")
			(hatch none 0.5)
			(connect_pads
				(clearance 0)
			)
			(min_thickness 0.25)
			(keepout
				(tracks allowed)
				(vias not_allowed)
				(pads allowed)
				(copperpour not_allowed)
				(footprints allowed)
			)
			(placement
				(enabled no)
				(sheetname "")
			)
			(fill
				(thermal_gap 0.5)
				(thermal_bridge_width 0.5)
				(island_removal_mode 0)
			)
			(polygon
				(pts
					(xy 45.8724 -82.169) (xy 46.3296 -82.169) (xy 46.3296 -83.439) (xy 45.8724 -83.439)
				)
			)
		)
	)
	(footprint ""
		(layer "F.Cu")
		(at 5.842 -81.534 90)
		(property "Reference" "R425"
			(at -2.667 -0.34163 90)
			(unlocked yes)
			(layer "F.SilkS")
			(effects
				(font
					(size 0.7874 0.5842)
					(thickness 0.1524)
				)
			)
		)
		(property "Value" "VAL*"
			(at 0.02032 2.13233 90)
			(unlocked yes)
			(layer "F.Fab")
			(hide yes)
			(effects
				(font
					(size 0.7874 0.5842)
					(thickness 0.1524)
				)
			)
		)
		(property "Device Type" "RESISTOR-G155-11000-01,100OHM,A"
			(at 0.008382 1.210564 90)
			(unlocked yes)
			(layer "F.Fab")
			(hide yes)
			(effects
				(font
					(size 0.7874 0.5842)
					(thickness 0.1524)
				)
			)
		)
		(property "User Part Number" "PARTNUM*"
			(at 0.02032 4.024884 90)
			(unlocked yes)
			(layer "Cmts.User")
			(hide yes)
			(effects
				(font
					(size 0.7874 0.5842)
					(thickness 0.1524)
				)
			)
		)
		(property "Tolerance" "TOL*"
			(at 0.044704 3.05435 90)
			(unlocked yes)
			(layer "Cmts.User")
			(hide yes)
			(effects
				(font
					(size 0.7874 0.5842)
					(thickness 0.1524)
				)
			)
		)
		(duplicate_pad_numbers_are_jumpers no)
		(fp_line
			(start 1.143 -0.5588)
			(end -1.143 -0.5588)
			(stroke
				(width 0.1)
				(type default)
			)
			(layer "F.SilkS")
		)
		(fp_line
			(start -1.143 -0.5588)
			(end -1.143 0.5588)
			(stroke
				(width 0.1)
				(type default)
			)
			(layer "F.SilkS")
		)
		(fp_line
			(start 1.143 0.5588)
			(end 1.143 -0.5588)
			(stroke
				(width 0.1)
				(type default)
			)
			(layer "F.SilkS")
		)
		(fp_line
			(start -1.143 0.5588)
			(end 1.143 0.5588)
			(stroke
				(width 0.1)
				(type default)
			)
			(layer "F.SilkS")
		)
		(fp_poly
			(pts
				(xy -1.143 0.5588) (xy 1.143 0.5588) (xy 1.143 -0.5588) (xy -1.143 -0.5588)
			)
			(stroke
				(width 0)
				(type default)
			)
			(fill no)
			(layer "F.CrtYd")
		)
		(fp_line
			(start 0.508 -0.3048)
			(end -0.508 -0.3048)
			(stroke
				(width 0.1)
				(type default)
			)
			(layer "F.Fab")
		)
		(fp_line
			(start -0.508 -0.3048)
			(end -0.508 0.3048)
			(stroke
				(width 0.1)
				(type default)
			)
			(layer "F.Fab")
		)
		(fp_line
			(start 0.508 0.3048)
			(end 0.508 -0.3048)
			(stroke
				(width 0.1)
				(type default)
			)
			(layer "F.Fab")
		)
		(fp_line
			(start -0.508 0.3048)
			(end 0.508 0.3048)
			(stroke
				(width 0.1)
				(type default)
			)
			(layer "F.Fab")
		)
		(pad "1" smd rect
			(at -0.5334 0 90)
			(size 0.7112 0.6096)
			(layers "F.Cu" "F.Mask" "F.Paste")
			(net "FPGA_OUT_GPS_LED_BLUE_N")
		)
		(pad "2" smd rect
			(at 0.5334 0 90)
			(size 0.7112 0.6096)
			(layers "F.Cu" "F.Mask" "F.Paste")
			(net "UNNAMED_14_LED4PV14_I269_1")
		)
		(zone
			(layer "F.Cu")
			(hatch none 0.5)
			(connect_pads
				(clearance 0)
			)
			(min_thickness 0.25)
			(keepout
				(tracks not_allowed)
				(vias allowed)
				(pads allowed)
				(copperpour not_allowed)
				(footprints allowed)
			)
			(placement
				(enabled no)
				(sheetname "")
			)
			(fill
				(thermal_gap 0.5)
				(thermal_bridge_width 0.5)
				(island_removal_mode 0)
			)
			(polygon
				(pts
					(xy 6.1468 -81.4578) (xy 6.1468 -81.6102) (xy 5.5372 -81.6102) (xy 5.5372 -81.4578)
				)
			)
		)
		(zone
			(layer "F.Cu")
			(hatch none 0.5)
			(connect_pads
				(clearance 0)
			)
			(min_thickness 0.25)
			(keepout
				(tracks allowed)
				(vias not_allowed)
				(pads allowed)
				(copperpour not_allowed)
				(footprints allowed)
			)
			(placement
				(enabled no)
				(sheetname "")
			)
			(fill
				(thermal_gap 0.5)
				(thermal_bridge_width 0.5)
				(island_removal_mode 0)
			)
			(polygon
				(pts
					(xy 6.1468 -81.4578) (xy 6.1468 -81.6102) (xy 5.5372 -81.6102) (xy 5.5372 -81.4578)
				)
			)
		)
	)
	(footprint ""
		(layer "F.Cu")
		(at 42.164 -133.223)
		(property "Reference" "SP21"
			(at 0 0 0)
			(layer "F.SilkS")
			(hide yes)
			(effects
				(font
					(size 1.27 1.27)
				)
			)
		)
		(property "Value" ""
			(at 0 0 0)
			(layer "F.Fab")
			(effects
				(font
					(size 1.27 1.27)
				)
			)
		)
		(duplicate_pad_numbers_are_jumpers no)
	)
	(footprint ""
		(layer "F.Cu")
		(at 92.837 -70.993 90)
		(property "Reference" "TP55"
			(at 0.8636 -0.34925 90)
			(unlocked yes)
			(layer "F.SilkS")
			(effects
				(font
					(size 0.635 0.4064)
					(thickness 0.1524)
				)
				(justify left)
			)
		)
		(property "Value" ""
			(at 0 0 90)
			(layer "F.Fab")
			(effects
				(font
					(size 1.27 1.27)
				)
			)
		)
		(property "Device Type" "TP_PIONT-TP010CT020B030_PTH-TPA"
			(at -1.341882 0.996696 90)
			(unlocked yes)
			(layer "F.Fab")
			(hide yes)
			(effects
				(font
					(size 0.7874 0.5842)
					(thickness 0.1524)
				)
				(justify left)
			)
		)
		(duplicate_pad_numbers_are_jumpers no)
		(fp_poly
			(pts
				(arc
					(start 0 0.889)
					(mid 0 -0.889)
					(end 0 0.889)
				)
			)
			(stroke
				(width 0)
				(type default)
			)
			(fill no)
			(layer "B.CrtYd")
		)
		(fp_poly
			(pts
				(arc
					(start 0 0.889)
					(mid 0 -0.889)
					(end 0 0.889)
				)
			)
			(stroke
				(width 0)
				(type default)
			)
			(fill no)
			(layer "F.CrtYd")
		)
		(pad "1" thru_hole circle
			(at 0 0 90)
			(size 0.508 0.508)
			(drill 0.254)
			(layers "*.Cu" "*.Mask")
			(remove_unused_layers no)
			(net "XP1R2V_FPGA")
			(clearance 0.1016)
			(padstack
				(mode front_inner_back)
				(layer "Inner"
					(shape circle)
					(size 0.508 0.508)
					(clearance 0.1016)
				)
				(layer "B.Cu"
					(shape circle)
					(size 0.762 0.762)
					(clearance -0.0254)
				)
			)
		)
	)
	(footprint ""
		(layer "F.Cu")
		(at 88.392 -93.599 90)
		(property "Reference" "C20"
			(at -3.81 -5.80263 90)
			(unlocked yes)
			(layer "F.SilkS")
			(effects
				(font
					(size 0.7874 0.5842)
					(thickness 0.1524)
				)
			)
		)
		(property "Value" "VAL*"
			(at 0.0762 3.134106 90)
			(unlocked yes)
			(layer "F.Fab")
			(hide yes)
			(effects
				(font
					(size 0.7874 0.5842)
					(thickness 0.1524)
				)
			)
		)
		(property "Tolerance" "TOL*"
			(at 0.0762 4.048506 90)
			(unlocked yes)
			(layer "Cmts.User")
			(hide yes)
			(effects
				(font
					(size 0.7874 0.5842)
					(thickness 0.1524)
				)
			)
		)
		(property "User Part Number" "PARTNUM*"
			(at 0.1016 5.013706 90)
			(unlocked yes)
			(layer "Cmts.User")
			(hide yes)
			(effects
				(font
					(size 0.7874 0.5842)
					(thickness 0.1524)
				)
			)
		)
		(property "Device Type" "CAPACITOR-G107-0F226-CM,22UF,2A"
			(at 0.0508 2.194306 90)
			(unlocked yes)
			(layer "F.Fab")
			(hide yes)
			(effects
				(font
					(size 0.7874 0.5842)
					(thickness 0.1524)
				)
			)
		)
		(duplicate_pad_numbers_are_jumpers no)
		(fp_line
			(start 1.5748 -0.9398)
			(end -1.5748 -0.9398)
			(stroke
				(width 0.1)
				(type default)
			)
			(layer "F.SilkS")
		)
		(fp_line
			(start -1.5748 -0.9398)
			(end -1.5748 0.9398)
			(stroke
				(width 0.1)
				(type default)
			)
			(layer "F.SilkS")
		)
		(fp_line
			(start 1.5748 0.9398)
			(end 1.5748 -0.9398)
			(stroke
				(width 0.1)
				(type default)
			)
			(layer "F.SilkS")
		)
		(fp_line
			(start -1.5748 0.9398)
			(end 1.5748 0.9398)
			(stroke
				(width 0.1)
				(type default)
			)
			(layer "F.SilkS")
		)
		(fp_rect
			(start 1.5748 0.9398)
			(end -1.5748 -0.9398)
			(stroke
				(width 0)
				(type default)
			)
			(fill no)
			(layer "F.CrtYd")
		)
		(fp_line
			(start 1.016 -0.635)
			(end -1.016 -0.635)
			(stroke
				(width 0.1)
				(type default)
			)
			(layer "F.Fab")
		)
		(fp_line
			(start -1.016 -0.635)
			(end -1.016 0.635)
			(stroke
				(width 0.1)
				(type default)
			)
			(layer "F.Fab")
		)
		(fp_line
			(start 1.016 0.635)
			(end 1.016 -0.635)
			(stroke
				(width 0.1)
				(type default)
			)
			(layer "F.Fab")
		)
		(fp_line
			(start -1.016 0.635)
			(end 1.016 0.635)
			(stroke
				(width 0.1)
				(type default)
			)
			(layer "F.Fab")
		)
		(pad "1" smd rect
			(at -0.8382 0 90)
			(size 0.9652 1.3716)
			(layers "F.Cu" "F.Mask" "F.Paste")
			(net "XP3R3V")
		)
		(pad "2" smd rect
			(at 0.8382 0 90)
			(size 0.9652 1.3716)
			(layers "F.Cu" "F.Mask" "F.Paste")
			(net "SG")
		)
		(zone
			(layer "F.Cu")
			(hatch none 0.5)
			(connect_pads
				(clearance 0)
			)
			(min_thickness 0.25)
			(keepout
				(tracks allowed)
				(vias not_allowed)
				(pads allowed)
				(copperpour not_allowed)
				(footprints allowed)
			)
			(placement
				(enabled no)
				(sheetname "")
			)
			(fill
				(thermal_gap 0.5)
				(thermal_bridge_width 0.5)
				(island_removal_mode 0)
			)
			(polygon
				(pts
					(xy 89.027 -93.8276) (xy 87.757 -93.8276) (xy 87.757 -93.3704) (xy 89.027 -93.3704)
				)
			)
		)
	)
	(footprint ""
		(layer "F.Cu")
		(at 101.4476 -82.2706)
		(property "Reference" "R462"
			(at -2.6416 0.77597 0)
			(unlocked yes)
			(layer "F.SilkS")
			(effects
				(font
					(size 0.7874 0.5842)
					(thickness 0.1524)
				)
			)
		)
		(property "Value" "VAL*"
			(at 0.02032 2.13233 0)
			(unlocked yes)
			(layer "F.Fab")
			(hide yes)
			(effects
				(font
					(size 0.7874 0.5842)
					(thickness 0.1524)
				)
			)
		)
		(property "Tolerance" "TOL*"
			(at 0.044704 3.05435 0)
			(unlocked yes)
			(layer "Cmts.User")
			(hide yes)
			(effects
				(font
					(size 0.7874 0.5842)
					(thickness 0.1524)
				)
			)
		)
		(property "User Part Number" "PARTNUM*"
			(at 0.02032 4.024884 0)
			(unlocked yes)
			(layer "Cmts.User")
			(hide yes)
			(effects
				(font
					(size 0.7874 0.5842)
					(thickness 0.1524)
				)
			)
		)
		(property "Device Type" "RESISTOR-G155-133R0-01,33OHM,1%"
			(at 0.008382 1.210564 0)
			(unlocked yes)
			(layer "F.Fab")
			(hide yes)
			(effects
				(font
					(size 0.7874 0.5842)
					(thickness 0.1524)
				)
			)
		)
		(duplicate_pad_numbers_are_jumpers no)
		(fp_line
			(start -1.143 -0.5588)
			(end -1.143 0.5588)
			(stroke
				(width 0.1)
				(type default)
			)
			(layer "F.SilkS")
		)
		(fp_line
			(start -1.143 0.5588)
			(end 1.143 0.5588)
			(stroke
				(width 0.1)
				(type default)
			)
			(layer "F.SilkS")
		)
		(fp_line
			(start 1.143 -0.5588)
			(end -1.143 -0.5588)
			(stroke
				(width 0.1)
				(type default)
			)
			(layer "F.SilkS")
		)
		(fp_line
			(start 1.143 0.5588)
			(end 1.143 -0.5588)
			(stroke
				(width 0.1)
				(type default)
			)
			(layer "F.SilkS")
		)
		(fp_poly
			(pts
				(xy -1.143 0.5588) (xy 1.143 0.5588) (xy 1.143 -0.5588) (xy -1.143 -0.5588)
			)
			(stroke
				(width 0)
				(type default)
			)
			(fill no)
			(layer "F.CrtYd")
		)
		(fp_line
			(start -0.508 -0.3048)
			(end -0.508 0.3048)
			(stroke
				(width 0.1)
				(type default)
			)
			(layer "F.Fab")
		)
		(fp_line
			(start -0.508 0.3048)
			(end 0.508 0.3048)
			(stroke
				(width 0.1)
				(type default)
			)
			(layer "F.Fab")
		)
		(fp_line
			(start 0.508 -0.3048)
			(end -0.508 -0.3048)
			(stroke
				(width 0.1)
				(type default)
			)
			(layer "F.Fab")
		)
		(fp_line
			(start 0.508 0.3048)
			(end 0.508 -0.3048)
			(stroke
				(width 0.1)
				(type default)
			)
			(layer "F.Fab")
		)
		(pad "1" smd rect
			(at -0.5334 0)
			(size 0.7112 0.6096)
			(layers "F.Cu" "F.Mask" "F.Paste")
			(net "FT4232_MUX2_SEL")
		)
		(pad "2" smd rect
			(at 0.5334 0)
			(size 0.7112 0.6096)
			(layers "F.Cu" "F.Mask" "F.Paste")
			(net "MUX2_SEL")
		)
		(zone
			(layer "F.Cu")
			(hatch none 0.5)
			(connect_pads
				(clearance 0)
			)
			(min_thickness 0.25)
			(keepout
				(tracks allowed)
				(vias not_allowed)
				(pads allowed)
				(copperpour not_allowed)
				(footprints allowed)
			)
			(placement
				(enabled no)
				(sheetname "")
			)
			(fill
				(thermal_gap 0.5)
				(thermal_bridge_width 0.5)
				(island_removal_mode 0)
			)
			(polygon
				(pts
					(xy 101.3714 -81.9658) (xy 101.5238 -81.9658) (xy 101.5238 -82.5754) (xy 101.3714 -82.5754)
				)
			)
		)
		(zone
			(layer "F.Cu")
			(hatch none 0.5)
			(connect_pads
				(clearance 0)
			)
			(min_thickness 0.25)
			(keepout
				(tracks not_allowed)
				(vias allowed)
				(pads allowed)
				(copperpour not_allowed)
				(footprints allowed)
			)
			(placement
				(enabled no)
				(sheetname "")
			)
			(fill
				(thermal_gap 0.5)
				(thermal_bridge_width 0.5)
				(island_removal_mode 0)
			)
			(polygon
				(pts
					(xy 101.3714 -81.9658) (xy 101.5238 -81.9658) (xy 101.5238 -82.5754) (xy 101.3714 -82.5754)
				)
			)
		)
	)
	(footprint ""
		(layer "F.Cu")
		(at 120.346978 -39.323264 90)
		(property "Reference" "TP132"
			(at 0 0 90)
			(layer "F.SilkS")
			(hide yes)
			(effects
				(font
					(size 1.27 1.27)
				)
			)
		)
		(property "Value" ""
			(at 0 0 90)
			(layer "F.Fab")
			(effects
				(font
					(size 1.27 1.27)
				)
			)
		)
		(property "Device Type" "TP_PIONT-TP010CT020B030_PTH-TPA"
			(at -1.341882 0.996696 90)
			(unlocked yes)
			(layer "F.Fab")
			(hide yes)
			(effects
				(font
					(size 0.7874 0.5842)
					(thickness 0.1524)
				)
				(justify left)
			)
		)
		(duplicate_pad_numbers_are_jumpers no)
		(fp_poly
			(pts
				(arc
					(start 0 0.889)
					(mid 0 -0.889)
					(end 0 0.889)
				)
			)
			(stroke
				(width 0)
				(type default)
			)
			(fill no)
			(layer "B.CrtYd")
		)
		(fp_poly
			(pts
				(arc
					(start 0 0.889)
					(mid 0 -0.889)
					(end 0 0.889)
				)
			)
			(stroke
				(width 0)
				(type default)
			)
			(fill no)
			(layer "F.CrtYd")
		)
		(pad "1" thru_hole circle
			(at 0 0 90)
			(size 0.508 0.508)
			(drill 0.254)
			(layers "*.Cu" "*.Mask")
			(remove_unused_layers no)
			(net "IO_L20P_34")
			(clearance 0.1016)
			(padstack
				(mode front_inner_back)
				(layer "Inner"
					(shape circle)
					(size 0.508 0.508)
					(clearance 0.1016)
				)
				(layer "B.Cu"
					(shape circle)
					(size 0.762 0.762)
					(clearance -0.0254)
				)
			)
		)
	)
	(footprint ""
		(layer "F.Cu")
		(at 42.9514 -97.5614)
		(property "Reference" "C41"
			(at 0.635 4.58597 0)
			(unlocked yes)
			(layer "F.SilkS")
			(effects
				(font
					(size 0.7874 0.5842)
					(thickness 0.1524)
				)
			)
		)
		(property "Value" "VAL*"
			(at 0.0762 2.067306 0)
			(unlocked yes)
			(layer "F.Fab")
			(hide yes)
			(effects
				(font
					(size 0.7874 0.5842)
					(thickness 0.1524)
				)
			)
		)
		(property "Device Type" "CAPACITOR-G105-0B104-EK,0.1UF,A"
			(at 0.0508 1.127506 0)
			(unlocked yes)
			(layer "F.Fab")
			(hide yes)
			(effects
				(font
					(size 0.7874 0.5842)
					(thickness 0.1524)
				)
			)
		)
		(property "User Part Number" "PARTNUM*"
			(at 0.1016 4.023106 0)
			(unlocked yes)
			(layer "Cmts.User")
			(hide yes)
			(effects
				(font
					(size 0.7874 0.5842)
					(thickness 0.1524)
				)
			)
		)
		(property "Tolerance" "TOL*"
			(at 0.0762 3.032506 0)
			(unlocked yes)
			(layer "Cmts.User")
			(hide yes)
			(effects
				(font
					(size 0.7874 0.5842)
					(thickness 0.1524)
				)
			)
		)
		(duplicate_pad_numbers_are_jumpers no)
		(fp_line
			(start -1.143 -0.5588)
			(end -1.143 0.5588)
			(stroke
				(width 0.1)
				(type default)
			)
			(layer "F.SilkS")
		)
		(fp_line
			(start -1.143 0.5588)
			(end 1.143 0.5588)
			(stroke
				(width 0.1)
				(type default)
			)
			(layer "F.SilkS")
		)
		(fp_line
			(start 1.143 -0.5588)
			(end -1.143 -0.5588)
			(stroke
				(width 0.1)
				(type default)
			)
			(layer "F.SilkS")
		)
		(fp_line
			(start 1.143 0.5588)
			(end 1.143 -0.5588)
			(stroke
				(width 0.1)
				(type default)
			)
			(layer "F.SilkS")
		)
		(fp_rect
			(start 1.143 -0.5588)
			(end -1.143 0.5588)
			(stroke
				(width 0)
				(type default)
			)
			(fill no)
			(layer "F.CrtYd")
		)
		(fp_line
			(start -0.508 -0.3048)
			(end -0.508 0.3048)
			(stroke
				(width 0.1)
				(type default)
			)
			(layer "F.Fab")
		)
		(fp_line
			(start -0.508 0.3048)
			(end 0.508 0.3048)
			(stroke
				(width 0.1)
				(type default)
			)
			(layer "F.Fab")
		)
		(fp_line
			(start 0.508 -0.3048)
			(end -0.508 -0.3048)
			(stroke
				(width 0.1)
				(type default)
			)
			(layer "F.Fab")
		)
		(fp_line
			(start 0.508 0.3048)
			(end 0.508 -0.3048)
			(stroke
				(width 0.1)
				(type default)
			)
			(layer "F.Fab")
		)
		(pad "1" smd rect
			(at -0.5334 0)
			(size 0.7112 0.6096)
			(layers "F.Cu" "F.Mask" "F.Paste")
			(net "VIN_XP5R0V")
		)
		(pad "2" smd rect
			(at 0.5334 0)
			(size 0.7112 0.6096)
			(layers "F.Cu" "F.Mask" "F.Paste")
			(net "SG")
		)
		(zone
			(layer "F.Cu")
			(hatch none 0.5)
			(connect_pads
				(clearance 0)
			)
			(min_thickness 0.25)
			(keepout
				(tracks allowed)
				(vias not_allowed)
				(pads allowed)
				(copperpour not_allowed)
				(footprints allowed)
			)
			(placement
				(enabled no)
				(sheetname "")
			)
			(fill
				(thermal_gap 0.5)
				(thermal_bridge_width 0.5)
				(island_removal_mode 0)
			)
			(polygon
				(pts
					(xy 43.0276 -97.8662) (xy 42.8752 -97.8662) (xy 42.8752 -97.2566) (xy 43.0276 -97.2566)
				)
			)
		)
	)
	(footprint ""
		(layer "F.Cu")
		(at 98.044 -64.2874 -90)
		(property "Reference" "R283"
			(at 2.6924 -0.80137 90)
			(unlocked yes)
			(layer "F.SilkS")
			(effects
				(font
					(size 0.7874 0.5842)
					(thickness 0.1524)
				)
			)
		)
		(property "Value" "VAL*"
			(at 0.02032 2.13233 270)
			(unlocked yes)
			(layer "F.Fab")
			(hide yes)
			(effects
				(font
					(size 0.7874 0.5842)
					(thickness 0.1524)
				)
			)
		)
		(property "Tolerance" "TOL*"
			(at 0.044704 3.05435 270)
			(unlocked yes)
			(layer "Cmts.User")
			(hide yes)
			(effects
				(font
					(size 0.7874 0.5842)
					(thickness 0.1524)
				)
			)
		)
		(property "User Part Number" "PARTNUM*"
			(at 0.02032 4.024884 270)
			(unlocked yes)
			(layer "Cmts.User")
			(hide yes)
			(effects
				(font
					(size 0.7874 0.5842)
					(thickness 0.1524)
				)
			)
		)
		(property "Device Type" "RESISTOR-G155-11002-01,10KOHM,A"
			(at 0.008382 1.210564 270)
			(unlocked yes)
			(layer "F.Fab")
			(hide yes)
			(effects
				(font
					(size 0.7874 0.5842)
					(thickness 0.1524)
				)
			)
		)
		(duplicate_pad_numbers_are_jumpers no)
		(fp_line
			(start -1.143 0.5588)
			(end 1.143 0.5588)
			(stroke
				(width 0.1)
				(type default)
			)
			(layer "F.SilkS")
		)
		(fp_line
			(start 1.143 0.5588)
			(end 1.143 -0.5588)
			(stroke
				(width 0.1)
				(type default)
			)
			(layer "F.SilkS")
		)
		(fp_line
			(start -1.143 -0.5588)
			(end -1.143 0.5588)
			(stroke
				(width 0.1)
				(type default)
			)
			(layer "F.SilkS")
		)
		(fp_line
			(start 1.143 -0.5588)
			(end -1.143 -0.5588)
			(stroke
				(width 0.1)
				(type default)
			)
			(layer "F.SilkS")
		)
		(fp_poly
			(pts
				(xy -1.143 0.5588) (xy 1.143 0.5588) (xy 1.143 -0.5588) (xy -1.143 -0.5588)
			)
			(stroke
				(width 0)
				(type default)
			)
			(fill no)
			(layer "F.CrtYd")
		)
		(fp_line
			(start -0.508 0.3048)
			(end 0.508 0.3048)
			(stroke
				(width 0.1)
				(type default)
			)
			(layer "F.Fab")
		)
		(fp_line
			(start 0.508 0.3048)
			(end 0.508 -0.3048)
			(stroke
				(width 0.1)
				(type default)
			)
			(layer "F.Fab")
		)
		(fp_line
			(start -0.508 -0.3048)
			(end -0.508 0.3048)
			(stroke
				(width 0.1)
				(type default)
			)
			(layer "F.Fab")
		)
		(fp_line
			(start 0.508 -0.3048)
			(end -0.508 -0.3048)
			(stroke
				(width 0.1)
				(type default)
			)
			(layer "F.Fab")
		)
		(pad "1" smd rect
			(at -0.5334 0 270)
			(size 0.7112 0.6096)
			(layers "F.Cu" "F.Mask" "F.Paste")
			(net "XP3R3V_FPGA")
		)
		(pad "2" smd rect
			(at 0.5334 0 270)
			(size 0.7112 0.6096)
			(layers "F.Cu" "F.Mask" "F.Paste")
			(net "FPGA_IO_2")
		)
		(zone
			(layer "F.Cu")
			(hatch none 0.5)
			(connect_pads
				(clearance 0)
			)
			(min_thickness 0.25)
			(keepout
				(tracks allowed)
				(vias not_allowed)
				(pads allowed)
				(copperpour not_allowed)
				(footprints allowed)
			)
			(placement
				(enabled no)
				(sheetname "")
			)
			(fill
				(thermal_gap 0.5)
				(thermal_bridge_width 0.5)
				(island_removal_mode 0)
			)
			(polygon
				(pts
					(xy 97.7392 -64.3636) (xy 97.7392 -64.2112) (xy 98.3488 -64.2112) (xy 98.3488 -64.3636)
				)
			)
		)
		(zone
			(layer "F.Cu")
			(hatch none 0.5)
			(connect_pads
				(clearance 0)
			)
			(min_thickness 0.25)
			(keepout
				(tracks not_allowed)
				(vias allowed)
				(pads allowed)
				(copperpour not_allowed)
				(footprints allowed)
			)
			(placement
				(enabled no)
				(sheetname "")
			)
			(fill
				(thermal_gap 0.5)
				(thermal_bridge_width 0.5)
				(island_removal_mode 0)
			)
			(polygon
				(pts
					(xy 97.7392 -64.3636) (xy 97.7392 -64.2112) (xy 98.3488 -64.2112) (xy 98.3488 -64.3636)
				)
			)
		)
	)
	(footprint ""
		(layer "F.Cu")
		(at 23.622 -69.2912)
		(property "Reference" "C277"
			(at 3.302 -0.13843 0)
			(unlocked yes)
			(layer "F.SilkS")
			(effects
				(font
					(size 0.7874 0.5842)
					(thickness 0.1524)
				)
			)
		)
		(property "Value" "VAL*"
			(at 0.0762 2.067306 0)
			(unlocked yes)
			(layer "F.Fab")
			(hide yes)
			(effects
				(font
					(size 0.7874 0.5842)
					(thickness 0.1524)
				)
			)
		)
		(property "Tolerance" "TOL*"
			(at 0.0762 3.032506 0)
			(unlocked yes)
			(layer "Cmts.User")
			(hide yes)
			(effects
				(font
					(size 0.7874 0.5842)
					(thickness 0.1524)
				)
			)
		)
		(property "User Part Number" "PARTNUM*"
			(at 0.1016 4.023106 0)
			(unlocked yes)
			(layer "Cmts.User")
			(hide yes)
			(effects
				(font
					(size 0.7874 0.5842)
					(thickness 0.1524)
				)
			)
		)
		(property "Device Type" "CAPACITOR-G105-0C106-BM,10UF,2A"
			(at 0.0508 1.127506 0)
			(unlocked yes)
			(layer "F.Fab")
			(hide yes)
			(effects
				(font
					(size 0.7874 0.5842)
					(thickness 0.1524)
				)
			)
		)
		(duplicate_pad_numbers_are_jumpers no)
		(fp_line
			(start -1.143 -0.5588)
			(end -1.143 0.5588)
			(stroke
				(width 0.1)
				(type default)
			)
			(layer "F.SilkS")
		)
		(fp_line
			(start -1.143 0.5588)
			(end 1.143 0.5588)
			(stroke
				(width 0.1)
				(type default)
			)
			(layer "F.SilkS")
		)
		(fp_line
			(start 1.143 -0.5588)
			(end -1.143 -0.5588)
			(stroke
				(width 0.1)
				(type default)
			)
			(layer "F.SilkS")
		)
		(fp_line
			(start 1.143 0.5588)
			(end 1.143 -0.5588)
			(stroke
				(width 0.1)
				(type default)
			)
			(layer "F.SilkS")
		)
		(fp_poly
			(pts
				(xy -1.143 -0.5588) (xy -1.143 0.5588) (xy 1.143 0.5588) (xy 1.143 -0.5588)
			)
			(stroke
				(width 0)
				(type default)
			)
			(fill no)
			(layer "F.CrtYd")
		)
		(fp_line
			(start -0.508 -0.3048)
			(end -0.508 0.3048)
			(stroke
				(width 0.1)
				(type default)
			)
			(layer "F.Fab")
		)
		(fp_line
			(start -0.508 0.3048)
			(end 0.508 0.3048)
			(stroke
				(width 0.1)
				(type default)
			)
			(layer "F.Fab")
		)
		(fp_line
			(start 0.508 -0.3048)
			(end -0.508 -0.3048)
			(stroke
				(width 0.1)
				(type default)
			)
			(layer "F.Fab")
		)
		(fp_line
			(start 0.508 0.3048)
			(end 0.508 -0.3048)
			(stroke
				(width 0.1)
				(type default)
			)
			(layer "F.Fab")
		)
		(pad "1" smd rect
			(at -0.5334 0)
			(size 0.7112 0.6096)
			(layers "F.Cu" "F.Mask" "F.Paste")
			(net "XP1R8V_ICP10100")
		)
		(pad "2" smd rect
			(at 0.5334 0)
			(size 0.7112 0.6096)
			(layers "F.Cu" "F.Mask" "F.Paste")
			(net "SG")
		)
		(zone
			(layer "F.Cu")
			(hatch none 0.5)
			(connect_pads
				(clearance 0)
			)
			(min_thickness 0.25)
			(keepout
				(tracks allowed)
				(vias not_allowed)
				(pads allowed)
				(copperpour not_allowed)
				(footprints allowed)
			)
			(placement
				(enabled no)
				(sheetname "")
			)
			(fill
				(thermal_gap 0.5)
				(thermal_bridge_width 0.5)
				(island_removal_mode 0)
			)
			(polygon
				(pts
					(xy 23.5458 -69.596) (xy 23.5458 -68.9864) (xy 23.6982 -68.9864) (xy 23.6982 -69.596)
				)
			)
		)
	)
	(footprint ""
		(layer "F.Cu")
		(at 144.050004 -107.849924 -90)
		(property "Reference" "DS3"
			(at 0.534924 1.448054 90)
			(unlocked yes)
			(layer "F.SilkS")
			(effects
				(font
					(size 0.635 0.4064)
					(thickness 0.1524)
				)
			)
		)
		(property "Value" ""
			(at 0 0 270)
			(layer "F.Fab")
			(effects
				(font
					(size 1.27 1.27)
				)
			)
		)
		(property "User Part Number" "PARTNUM*"
			(at 0.1778 2.422881 270)
			(unlocked yes)
			(layer "Cmts.User")
			(hide yes)
			(effects
				(font
					(size 0.786892 0.583946)
					(thickness 0.000001)
				)
			)
		)
		(property "Device Type" "OPTICAL-G170-10143-01"
			(at 0.1778 1.483081 270)
			(unlocked yes)
			(layer "F.Fab")
			(hide yes)
			(effects
				(font
					(size 0.786892 0.583946)
					(thickness 0.000001)
				)
			)
		)
		(duplicate_pad_numbers_are_jumpers no)
		(fp_line
			(start -1.3208 1.2192)
			(end -2.5908 1.2192)
			(stroke
				(width 0.1)
				(type default)
			)
			(layer "F.SilkS")
		)
		(fp_line
			(start -1.397508 0.704088)
			(end -1.397508 -0.704088)
			(stroke
				(width 0.1)
				(type default)
			)
			(layer "F.SilkS")
		)
		(fp_line
			(start 1.397508 0.704088)
			(end -1.397508 0.704088)
			(stroke
				(width 0.1)
				(type default)
			)
			(layer "F.SilkS")
		)
		(fp_line
			(start -1.9558 0.5842)
			(end -1.9558 1.8542)
			(stroke
				(width 0.1)
				(type default)
			)
			(layer "F.SilkS")
		)
		(fp_line
			(start -1.397508 -0.704088)
			(end 1.397508 -0.704088)
			(stroke
				(width 0.1)
				(type default)
			)
			(layer "F.SilkS")
		)
		(fp_line
			(start 1.397508 -0.704088)
			(end 1.397508 0.704088)
			(stroke
				(width 0.1)
				(type default)
			)
			(layer "F.SilkS")
		)
		(fp_rect
			(start 1.905508 0.704088)
			(end 1.397508 -0.704088)
			(stroke
				(width 0)
				(type default)
			)
			(fill yes)
			(layer "F.SilkS")
		)
		(fp_rect
			(start 1.905508 0.958088)
			(end -1.651508 -0.958088)
			(stroke
				(width 0)
				(type default)
			)
			(fill no)
			(layer "F.CrtYd")
		)
		(fp_line
			(start -1.3208 0.9652)
			(end -2.5908 0.9652)
			(stroke
				(width 0.1)
				(type default)
			)
			(layer "F.Fab")
		)
		(fp_line
			(start -0.850138 0.450088)
			(end 0.850138 0.450088)
			(stroke
				(width 0.1)
				(type default)
			)
			(layer "F.Fab")
		)
		(fp_line
			(start 0.850138 0.450088)
			(end 0.850138 -0.450088)
			(stroke
				(width 0.1)
				(type default)
			)
			(layer "F.Fab")
		)
		(fp_line
			(start -1.9558 0.3302)
			(end -1.9558 1.6002)
			(stroke
				(width 0.1)
				(type default)
			)
			(layer "F.Fab")
		)
		(fp_line
			(start -0.850138 -0.450088)
			(end -0.850138 0.450088)
			(stroke
				(width 0.1)
				(type default)
			)
			(layer "F.Fab")
		)
		(fp_line
			(start 0.850138 -0.450088)
			(end -0.850138 -0.450088)
			(stroke
				(width 0.1)
				(type default)
			)
			(layer "F.Fab")
		)
		(fp_rect
			(start 0.850138 0.450088)
			(end 0.342138 -0.450088)
			(stroke
				(width 0)
				(type default)
			)
			(fill yes)
			(layer "F.Fab")
		)
		(fp_text user "A"
			(at -1.973326 -0.729996 0)
			(unlocked yes)
			(layer "F.SilkS")
			(effects
				(font
					(size 0.635 0.4064)
					(thickness 0.1524)
				)
			)
		)
		(fp_text user "C"
			(at 1.201674 -1.237996 0)
			(unlocked yes)
			(layer "F.SilkS")
			(effects
				(font
					(size 0.635 0.4064)
					(thickness 0.1524)
				)
			)
		)
		(fp_text user "A"
			(at -1.838706 -0.094996 0)
			(unlocked yes)
			(layer "F.Fab")
			(effects
				(font
					(size 0.7874 0.5842)
					(thickness 0.1524)
				)
			)
		)
		(fp_text user "C"
			(at 0.955294 -0.983996 0)
			(unlocked yes)
			(layer "F.Fab")
			(effects
				(font
					(size 0.7874 0.5842)
					(thickness 0.1524)
				)
			)
		)
		(pad "A" smd rect
			(at -0.749808 0 270)
			(size 0.7874 0.7874)
			(layers "F.Cu" "F.Mask" "F.Paste")
			(net "UNNAMED_14_OPTICAL_I136_A")
		)
		(pad "C" smd rect
			(at 0.749808 0 270)
			(size 0.7874 0.7874)
			(layers "F.Cu" "F.Mask" "F.Paste")
			(net "LED_DATOUT1")
		)
	)
	(footprint ""
		(layer "F.Cu")
		(at 65.000124 -104.650032)
		(property "Reference" "ME1"
			(at -0.801624 4.359402 0)
			(unlocked yes)
			(layer "F.SilkS")
			(effects
				(font
					(size 0.7874 0.5842)
					(thickness 0.1524)
				)
				(justify left)
			)
		)
		(property "Value" ""
			(at 0 0 0)
			(layer "F.Fab")
			(effects
				(font
					(size 1.27 1.27)
				)
			)
		)
		(property "User Part Number" "PARTNUM*"
			(at -3.048 5.242306 0)
			(unlocked yes)
			(layer "Cmts.User")
			(hide yes)
			(effects
				(font
					(size 0.7874 0.5842)
					(thickness 0.1524)
				)
				(justify left)
			)
		)
		(property "Device Type" "NUT-G340-10437-01"
			(at -1.4732 4.226306 0)
			(unlocked yes)
			(layer "F.Fab")
			(hide yes)
			(effects
				(font
					(size 0.7874 0.5842)
					(thickness 0.1524)
				)
				(justify left)
			)
		)
		(duplicate_pad_numbers_are_jumpers no)
		(fp_circle
			(center 0 0)
			(end 3.3528 0)
			(stroke
				(width 0.1)
				(type default)
			)
			(fill no)
			(layer "F.SilkS")
		)
		(fp_poly
			(pts
				(arc
					(start -2.102612 -0.1524)
					(mid -1.490671 -1.490671)
					(end -0.1524 -2.102612)
				)
				(arc
					(start -0.1524 -3.171444)
					(mid -2.245137 -2.245137)
					(end -3.171444 -0.1524)
				)
			)
			(stroke
				(width 0)
				(type default)
			)
			(fill yes)
			(layer "F.Paste")
		)
		(fp_poly
			(pts
				(arc
					(start -0.1524 2.102612)
					(mid -1.490671 1.490671)
					(end -2.102612 0.1524)
				)
				(arc
					(start -3.171444 0.1524)
					(mid -2.245137 2.245137)
					(end -0.1524 3.171444)
				)
			)
			(stroke
				(width 0)
				(type default)
			)
			(fill yes)
			(layer "F.Paste")
		)
		(fp_poly
			(pts
				(arc
					(start 0.1524 -2.102612)
					(mid 1.490671 -1.490671)
					(end 2.102612 -0.1524)
				)
				(arc
					(start 3.171444 -0.1524)
					(mid 2.245137 -2.245137)
					(end 0.1524 -3.171444)
				)
			)
			(stroke
				(width 0)
				(type default)
			)
			(fill yes)
			(layer "F.Paste")
		)
		(fp_poly
			(pts
				(arc
					(start 2.102612 0.1524)
					(mid 1.490671 1.490671)
					(end 0.1524 2.102612)
				)
				(arc
					(start 0.1524 3.171444)
					(mid 2.245137 2.245137)
					(end 3.171444 0.1524)
				)
			)
			(stroke
				(width 0)
				(type default)
			)
			(fill yes)
			(layer "F.Paste")
		)
		(fp_rect
			(start -7.5946 7.5946)
			(end 7.5946 -7.5946)
			(stroke
				(width 0)
				(type default)
			)
			(fill no)
			(layer "B.CrtYd")
		)
		(fp_poly
			(pts
				(arc
					(start 3.6068 0)
					(mid -3.6068 0)
					(end 3.6068 0)
				)
			)
			(stroke
				(width 0)
				(type default)
			)
			(fill no)
			(layer "F.CrtYd")
		)
		(fp_circle
			(center 0 0)
			(end 2.8448 0)
			(stroke
				(width 0.1)
				(type default)
			)
			(fill no)
			(layer "F.Fab")
		)
		(pad "1" thru_hole circle
			(at 0 0)
			(size 6.1976 6.1976)
			(drill 4.2164)
			(layers "*.Cu" "*.Mask")
			(remove_unused_layers no)
			(net "SG")
			(padstack
				(mode front_inner_back)
				(layer "Inner"
					(shape circle)
					(size 5.0292 5.0292)
					(clearance -0.1143)
				)
				(layer "B.Cu"
					(shape circle)
					(size 5.0292 5.0292)
				)
			)
		)
	)
	(footprint ""
		(layer "F.Cu")
		(at 144.145 -60.96)
		(property "Reference" "R254"
			(at -2.286 -3.51663 0)
			(unlocked yes)
			(layer "F.SilkS")
			(effects
				(font
					(size 0.7874 0.5842)
					(thickness 0.1524)
				)
			)
		)
		(property "Value" "VAL*"
			(at 0.02032 2.13233 0)
			(unlocked yes)
			(layer "F.Fab")
			(hide yes)
			(effects
				(font
					(size 0.7874 0.5842)
					(thickness 0.1524)
				)
			)
		)
		(property "Device Type" "RESISTOR-G155-120R0-01,20OHM,1%"
			(at 0.008382 1.210564 0)
			(unlocked yes)
			(layer "F.Fab")
			(hide yes)
			(effects
				(font
					(size 0.7874 0.5842)
					(thickness 0.1524)
				)
			)
		)
		(property "User Part Number" "PARTNUM*"
			(at 0.02032 4.024884 0)
			(unlocked yes)
			(layer "Cmts.User")
			(hide yes)
			(effects
				(font
					(size 0.7874 0.5842)
					(thickness 0.1524)
				)
			)
		)
		(property "Tolerance" "TOL*"
			(at 0.044704 3.05435 0)
			(unlocked yes)
			(layer "Cmts.User")
			(hide yes)
			(effects
				(font
					(size 0.7874 0.5842)
					(thickness 0.1524)
				)
			)
		)
		(duplicate_pad_numbers_are_jumpers no)
		(fp_line
			(start -1.143 -0.5588)
			(end -1.143 0.5588)
			(stroke
				(width 0.1)
				(type default)
			)
			(layer "F.SilkS")
		)
		(fp_line
			(start -1.143 0.5588)
			(end 1.143 0.5588)
			(stroke
				(width 0.1)
				(type default)
			)
			(layer "F.SilkS")
		)
		(fp_line
			(start 1.143 -0.5588)
			(end -1.143 -0.5588)
			(stroke
				(width 0.1)
				(type default)
			)
			(layer "F.SilkS")
		)
		(fp_line
			(start 1.143 0.5588)
			(end 1.143 -0.5588)
			(stroke
				(width 0.1)
				(type default)
			)
			(layer "F.SilkS")
		)
		(fp_rect
			(start 1.143 -0.5588)
			(end -1.143 0.5588)
			(stroke
				(width 0)
				(type default)
			)
			(fill no)
			(layer "F.CrtYd")
		)
		(fp_line
			(start -0.508 -0.3048)
			(end -0.508 0.3048)
			(stroke
				(width 0.1)
				(type default)
			)
			(layer "F.Fab")
		)
		(fp_line
			(start -0.508 0.3048)
			(end 0.508 0.3048)
			(stroke
				(width 0.1)
				(type default)
			)
			(layer "F.Fab")
		)
		(fp_line
			(start 0.508 -0.3048)
			(end -0.508 -0.3048)
			(stroke
				(width 0.1)
				(type default)
			)
			(layer "F.Fab")
		)
		(fp_line
			(start 0.508 0.3048)
			(end 0.508 -0.3048)
			(stroke
				(width 0.1)
				(type default)
			)
			(layer "F.Fab")
		)
		(pad "1" smd rect
			(at -0.5334 0)
			(size 0.7112 0.6096)
			(layers "F.Cu" "F.Mask" "F.Paste")
			(net "XP1R0V_FPGA")
		)
		(pad "2" smd rect
			(at 0.5334 0)
			(size 0.7112 0.6096)
			(layers "F.Cu" "F.Mask" "F.Paste")
			(net "UNNAMED_523_CAPACITOR_I28_1")
		)
		(zone
			(layer "F.Cu")
			(hatch none 0.5)
			(connect_pads
				(clearance 0)
			)
			(min_thickness 0.25)
			(keepout
				(tracks allowed)
				(vias not_allowed)
				(pads allowed)
				(copperpour not_allowed)
				(footprints allowed)
			)
			(placement
				(enabled no)
				(sheetname "")
			)
			(fill
				(thermal_gap 0.5)
				(thermal_bridge_width 0.5)
				(island_removal_mode 0)
			)
			(polygon
				(pts
					(xy 144.2212 -61.2648) (xy 144.0688 -61.2648) (xy 144.0688 -60.6552) (xy 144.2212 -60.6552)
				)
			)
		)
	)
	(footprint ""
		(layer "F.Cu")
		(at 80.772 -54.9656 180)
		(property "Reference" "R302"
			(at 10.16 18.78203 0)
			(unlocked yes)
			(layer "F.SilkS")
			(effects
				(font
					(size 0.7874 0.5842)
					(thickness 0.1524)
				)
			)
		)
		(property "Value" "VAL*"
			(at 0.02032 2.13233 180)
			(unlocked yes)
			(layer "F.Fab")
			(hide yes)
			(effects
				(font
					(size 0.7874 0.5842)
					(thickness 0.1524)
				)
			)
		)
		(property "Tolerance" "TOL*"
			(at 0.044704 3.05435 180)
			(unlocked yes)
			(layer "Cmts.User")
			(hide yes)
			(effects
				(font
					(size 0.7874 0.5842)
					(thickness 0.1524)
				)
			)
		)
		(property "User Part Number" "PARTNUM*"
			(at 0.02032 4.024884 180)
			(unlocked yes)
			(layer "Cmts.User")
			(hide yes)
			(effects
				(font
					(size 0.7874 0.5842)
					(thickness 0.1524)
				)
			)
		)
		(property "Device Type" "RESISTOR-G155-11001-01,1KOHM,1%"
			(at 0.008382 1.210564 180)
			(unlocked yes)
			(layer "F.Fab")
			(hide yes)
			(effects
				(font
					(size 0.7874 0.5842)
					(thickness 0.1524)
				)
			)
		)
		(duplicate_pad_numbers_are_jumpers no)
		(fp_line
			(start 1.143 0.5588)
			(end 1.143 -0.5588)
			(stroke
				(width 0.1)
				(type default)
			)
			(layer "F.SilkS")
		)
		(fp_line
			(start 1.143 -0.5588)
			(end -1.143 -0.5588)
			(stroke
				(width 0.1)
				(type default)
			)
			(layer "F.SilkS")
		)
		(fp_line
			(start -1.143 0.5588)
			(end 1.143 0.5588)
			(stroke
				(width 0.1)
				(type default)
			)
			(layer "F.SilkS")
		)
		(fp_line
			(start -1.143 -0.5588)
			(end -1.143 0.5588)
			(stroke
				(width 0.1)
				(type default)
			)
			(layer "F.SilkS")
		)
		(fp_rect
			(start 1.143 0.5588)
			(end -1.143 -0.5588)
			(stroke
				(width 0)
				(type default)
			)
			(fill no)
			(layer "F.CrtYd")
		)
		(fp_line
			(start 0.508 0.3048)
			(end 0.508 -0.3048)
			(stroke
				(width 0.1)
				(type default)
			)
			(layer "F.Fab")
		)
		(fp_line
			(start 0.508 -0.3048)
			(end -0.508 -0.3048)
			(stroke
				(width 0.1)
				(type default)
			)
			(layer "F.Fab")
		)
		(fp_line
			(start -0.508 0.3048)
			(end 0.508 0.3048)
			(stroke
				(width 0.1)
				(type default)
			)
			(layer "F.Fab")
		)
		(fp_line
			(start -0.508 -0.3048)
			(end -0.508 0.3048)
			(stroke
				(width 0.1)
				(type default)
			)
			(layer "F.Fab")
		)
		(pad "1" smd rect
			(at -0.5334 0 180)
			(size 0.7112 0.6096)
			(layers "F.Cu" "F.Mask" "F.Paste")
			(net "BNO080_SA0")
		)
		(pad "2" smd rect
			(at 0.5334 0 180)
			(size 0.7112 0.6096)
			(layers "F.Cu" "F.Mask" "F.Paste")
			(net "SG")
		)
		(zone
			(layer "F.Cu")
			(hatch none 0.5)
			(connect_pads
				(clearance 0)
			)
			(min_thickness 0.25)
			(keepout
				(tracks allowed)
				(vias not_allowed)
				(pads allowed)
				(copperpour not_allowed)
				(footprints allowed)
			)
			(placement
				(enabled no)
				(sheetname "")
			)
			(fill
				(thermal_gap 0.5)
				(thermal_bridge_width 0.5)
				(island_removal_mode 0)
			)
			(polygon
				(pts
					(xy 80.6958 -55.2704) (xy 80.6958 -54.6608) (xy 80.8482 -54.6608) (xy 80.8482 -55.2704)
				)
			)
		)
	)
	(footprint ""
		(layer "F.Cu")
		(at 46.736 -123.825)
		(property "Reference" "SP24"
			(at 0 0 0)
			(layer "F.SilkS")
			(hide yes)
			(effects
				(font
					(size 1.27 1.27)
				)
			)
		)
		(property "Value" ""
			(at 0 0 0)
			(layer "F.Fab")
			(effects
				(font
					(size 1.27 1.27)
				)
			)
		)
		(duplicate_pad_numbers_are_jumpers no)
	)
	(footprint ""
		(layer "F.Cu")
		(at 95.504 -61.087 90)
		(property "Reference" "R164"
			(at -2.667 -0.08763 90)
			(unlocked yes)
			(layer "F.SilkS")
			(effects
				(font
					(size 0.7874 0.5842)
					(thickness 0.1524)
				)
			)
		)
		(property "Value" "VAL*"
			(at 0.02032 2.13233 90)
			(unlocked yes)
			(layer "F.Fab")
			(hide yes)
			(effects
				(font
					(size 0.7874 0.5842)
					(thickness 0.1524)
				)
			)
		)
		(property "Tolerance" "TOL*"
			(at 0.044704 3.05435 90)
			(unlocked yes)
			(layer "Cmts.User")
			(hide yes)
			(effects
				(font
					(size 0.7874 0.5842)
					(thickness 0.1524)
				)
			)
		)
		(property "User Part Number" "PARTNUM*"
			(at 0.02032 4.024884 90)
			(unlocked yes)
			(layer "Cmts.User")
			(hide yes)
			(effects
				(font
					(size 0.7874 0.5842)
					(thickness 0.1524)
				)
			)
		)
		(property "Device Type" "RESISTOR-G155-11003-01,100KOHMA"
			(at 0.008382 1.210564 90)
			(unlocked yes)
			(layer "F.Fab")
			(hide yes)
			(effects
				(font
					(size 0.7874 0.5842)
					(thickness 0.1524)
				)
			)
		)
		(duplicate_pad_numbers_are_jumpers no)
		(fp_line
			(start 1.143 -0.5588)
			(end -1.143 -0.5588)
			(stroke
				(width 0.1)
				(type default)
			)
			(layer "F.SilkS")
		)
		(fp_line
			(start -1.143 -0.5588)
			(end -1.143 0.5588)
			(stroke
				(width 0.1)
				(type default)
			)
			(layer "F.SilkS")
		)
		(fp_line
			(start 1.143 0.5588)
			(end 1.143 -0.5588)
			(stroke
				(width 0.1)
				(type default)
			)
			(layer "F.SilkS")
		)
		(fp_line
			(start -1.143 0.5588)
			(end 1.143 0.5588)
			(stroke
				(width 0.1)
				(type default)
			)
			(layer "F.SilkS")
		)
		(fp_poly
			(pts
				(xy -1.143 0.5588) (xy 1.143 0.5588) (xy 1.143 -0.5588) (xy -1.143 -0.5588)
			)
			(stroke
				(width 0)
				(type default)
			)
			(fill no)
			(layer "F.CrtYd")
		)
		(fp_line
			(start 0.508 -0.3048)
			(end -0.508 -0.3048)
			(stroke
				(width 0.1)
				(type default)
			)
			(layer "F.Fab")
		)
		(fp_line
			(start -0.508 -0.3048)
			(end -0.508 0.3048)
			(stroke
				(width 0.1)
				(type default)
			)
			(layer "F.Fab")
		)
		(fp_line
			(start 0.508 0.3048)
			(end 0.508 -0.3048)
			(stroke
				(width 0.1)
				(type default)
			)
			(layer "F.Fab")
		)
		(fp_line
			(start -0.508 0.3048)
			(end 0.508 0.3048)
			(stroke
				(width 0.1)
				(type default)
			)
			(layer "F.Fab")
		)
		(pad "1" smd rect
			(at -0.5334 0 90)
			(size 0.7112 0.6096)
			(layers "F.Cu" "F.Mask" "F.Paste")
			(net "XP3R3V_FPGA")
		)
		(pad "2" smd rect
			(at 0.5334 0 90)
			(size 0.7112 0.6096)
			(layers "F.Cu" "F.Mask" "F.Paste")
			(net "UNNAMED_3_RESISTOR_I151_2")
		)
		(zone
			(layer "F.Cu")
			(hatch none 0.5)
			(connect_pads
				(clearance 0)
			)
			(min_thickness 0.25)
			(keepout
				(tracks allowed)
				(vias not_allowed)
				(pads allowed)
				(copperpour not_allowed)
				(footprints allowed)
			)
			(placement
				(enabled no)
				(sheetname "")
			)
			(fill
				(thermal_gap 0.5)
				(thermal_bridge_width 0.5)
				(island_removal_mode 0)
			)
			(polygon
				(pts
					(xy 95.8088 -61.0108) (xy 95.8088 -61.1632) (xy 95.1992 -61.1632) (xy 95.1992 -61.0108)
				)
			)
		)
		(zone
			(layer "F.Cu")
			(hatch none 0.5)
			(connect_pads
				(clearance 0)
			)
			(min_thickness 0.25)
			(keepout
				(tracks not_allowed)
				(vias allowed)
				(pads allowed)
				(copperpour not_allowed)
				(footprints allowed)
			)
			(placement
				(enabled no)
				(sheetname "")
			)
			(fill
				(thermal_gap 0.5)
				(thermal_bridge_width 0.5)
				(island_removal_mode 0)
			)
			(polygon
				(pts
					(xy 95.8088 -61.0108) (xy 95.8088 -61.1632) (xy 95.1992 -61.1632) (xy 95.1992 -61.0108)
				)
			)
		)
	)
	(footprint ""
		(layer "F.Cu")
		(at 138.43 -53.594 -90)
		(property "Reference" "C261"
			(at 0.508 3.26263 90)
			(unlocked yes)
			(layer "F.SilkS")
			(effects
				(font
					(size 0.7874 0.5842)
					(thickness 0.1524)
				)
			)
		)
		(property "Value" "VAL*"
			(at 0.0762 2.067306 270)
			(unlocked yes)
			(layer "F.Fab")
			(hide yes)
			(effects
				(font
					(size 0.7874 0.5842)
					(thickness 0.1524)
				)
			)
		)
		(property "Device Type" "CAPACITOR-G105-0B104-EK,0.1UF,A"
			(at 0.0508 1.127506 270)
			(unlocked yes)
			(layer "F.Fab")
			(hide yes)
			(effects
				(font
					(size 0.7874 0.5842)
					(thickness 0.1524)
				)
			)
		)
		(property "User Part Number" "PARTNUM*"
			(at 0.1016 4.023106 270)
			(unlocked yes)
			(layer "Cmts.User")
			(hide yes)
			(effects
				(font
					(size 0.7874 0.5842)
					(thickness 0.1524)
				)
			)
		)
		(property "Tolerance" "TOL*"
			(at 0.0762 3.032506 270)
			(unlocked yes)
			(layer "Cmts.User")
			(hide yes)
			(effects
				(font
					(size 0.7874 0.5842)
					(thickness 0.1524)
				)
			)
		)
		(duplicate_pad_numbers_are_jumpers no)
		(fp_line
			(start -1.143 0.5588)
			(end 1.143 0.5588)
			(stroke
				(width 0.1)
				(type default)
			)
			(layer "F.SilkS")
		)
		(fp_line
			(start 1.143 0.5588)
			(end 1.143 -0.5588)
			(stroke
				(width 0.1)
				(type default)
			)
			(layer "F.SilkS")
		)
		(fp_line
			(start -1.143 -0.5588)
			(end -1.143 0.5588)
			(stroke
				(width 0.1)
				(type default)
			)
			(layer "F.SilkS")
		)
		(fp_line
			(start 1.143 -0.5588)
			(end -1.143 -0.5588)
			(stroke
				(width 0.1)
				(type default)
			)
			(layer "F.SilkS")
		)
		(fp_rect
			(start 1.143 0.5588)
			(end -1.143 -0.5588)
			(stroke
				(width 0)
				(type default)
			)
			(fill no)
			(layer "F.CrtYd")
		)
		(fp_line
			(start -0.508 0.3048)
			(end 0.508 0.3048)
			(stroke
				(width 0.1)
				(type default)
			)
			(layer "F.Fab")
		)
		(fp_line
			(start 0.508 0.3048)
			(end 0.508 -0.3048)
			(stroke
				(width 0.1)
				(type default)
			)
			(layer "F.Fab")
		)
		(fp_line
			(start -0.508 -0.3048)
			(end -0.508 0.3048)
			(stroke
				(width 0.1)
				(type default)
			)
			(layer "F.Fab")
		)
		(fp_line
			(start 0.508 -0.3048)
			(end -0.508 -0.3048)
			(stroke
				(width 0.1)
				(type default)
			)
			(layer "F.Fab")
		)
		(pad "1" smd rect
			(at -0.5334 0 270)
			(size 0.7112 0.6096)
			(layers "F.Cu" "F.Mask" "F.Paste")
			(net "VIN_XP1R0V")
		)
		(pad "2" smd rect
			(at 0.5334 0 270)
			(size 0.7112 0.6096)
			(layers "F.Cu" "F.Mask" "F.Paste")
			(net "SG")
		)
		(zone
			(layer "F.Cu")
			(hatch none 0.5)
			(connect_pads
				(clearance 0)
			)
			(min_thickness 0.25)
			(keepout
				(tracks allowed)
				(vias not_allowed)
				(pads allowed)
				(copperpour not_allowed)
				(footprints allowed)
			)
			(placement
				(enabled no)
				(sheetname "")
			)
			(fill
				(thermal_gap 0.5)
				(thermal_bridge_width 0.5)
				(island_removal_mode 0)
			)
			(polygon
				(pts
					(xy 138.1252 -53.5178) (xy 138.7348 -53.5178) (xy 138.7348 -53.6702) (xy 138.1252 -53.6702)
				)
			)
		)
	)
	(footprint ""
		(layer "F.Cu")
		(at 123.19 -39.116)
		(property "Reference" "TP136"
			(at -0.73025 0.8128 90)
			(unlocked yes)
			(layer "F.SilkS")
			(effects
				(font
					(size 0.635 0.4064)
					(thickness 0.1524)
				)
				(justify left)
			)
		)
		(property "Value" ""
			(at 0 0 0)
			(layer "F.Fab")
			(effects
				(font
					(size 1.27 1.27)
				)
			)
		)
		(property "Device Type" "TP_PIONT-TP010CT020B030_PTH-TPA"
			(at -1.341882 0.996696 0)
			(unlocked yes)
			(layer "F.Fab")
			(hide yes)
			(effects
				(font
					(size 0.7874 0.5842)
					(thickness 0.1524)
				)
				(justify left)
			)
		)
		(duplicate_pad_numbers_are_jumpers no)
		(fp_poly
			(pts
				(arc
					(start 0.889 0)
					(mid -0.889 0)
					(end 0.889 0)
				)
			)
			(stroke
				(width 0)
				(type default)
			)
			(fill no)
			(layer "B.CrtYd")
		)
		(fp_poly
			(pts
				(arc
					(start 0.889 0)
					(mid -0.889 0)
					(end 0.889 0)
				)
			)
			(stroke
				(width 0)
				(type default)
			)
			(fill no)
			(layer "F.CrtYd")
		)
		(pad "1" thru_hole circle
			(at 0 0)
			(size 0.508 0.508)
			(drill 0.254)
			(layers "*.Cu" "*.Mask")
			(remove_unused_layers no)
			(net "IO_L22P_34")
			(clearance 0.1016)
			(padstack
				(mode front_inner_back)
				(layer "Inner"
					(shape circle)
					(size 0.508 0.508)
					(clearance 0.1016)
				)
				(layer "B.Cu"
					(shape circle)
					(size 0.762 0.762)
					(clearance -0.0254)
				)
			)
		)
	)
	(footprint ""
		(layer "F.Cu")
		(at 133.223 -34.163)
		(property "Reference" "C176"
			(at 4.445 1.94437 0)
			(unlocked yes)
			(layer "F.SilkS")
			(effects
				(font
					(size 0.7874 0.5842)
					(thickness 0.1524)
				)
			)
		)
		(property "Value" "VAL*"
			(at 0.1016 3.769106 0)
			(unlocked yes)
			(layer "F.Fab")
			(hide yes)
			(effects
				(font
					(size 0.7874 0.5842)
					(thickness 0.1524)
				)
			)
		)
		(property "Tolerance" "TOL*"
			(at 0.127 4.734306 0)
			(unlocked yes)
			(layer "Cmts.User")
			(hide yes)
			(effects
				(font
					(size 0.7874 0.5842)
					(thickness 0.1524)
				)
			)
		)
		(property "User Part Number" "PARTNUM*"
			(at 0.2032 5.801106 0)
			(unlocked yes)
			(layer "Cmts.User")
			(hide yes)
			(effects
				(font
					(size 0.7874 0.5842)
					(thickness 0.1524)
				)
			)
		)
		(property "Device Type" "CAPACITOR-G109-0G107-BM,100UF,A"
			(at 0.0762 2.829306 0)
			(unlocked yes)
			(layer "F.Fab")
			(hide yes)
			(effects
				(font
					(size 0.7874 0.5842)
					(thickness 0.1524)
				)
			)
		)
		(duplicate_pad_numbers_are_jumpers no)
		(fp_line
			(start -2.159 -1.5748)
			(end 2.159 -1.5748)
			(stroke
				(width 0.1)
				(type default)
			)
			(layer "F.SilkS")
		)
		(fp_line
			(start -2.159 1.5748)
			(end -2.159 -1.5748)
			(stroke
				(width 0.1)
				(type default)
			)
			(layer "F.SilkS")
		)
		(fp_line
			(start 2.159 -1.5748)
			(end 2.159 1.5748)
			(stroke
				(width 0.1)
				(type default)
			)
			(layer "F.SilkS")
		)
		(fp_line
			(start 2.159 1.5748)
			(end -2.159 1.5748)
			(stroke
				(width 0.1)
				(type default)
			)
			(layer "F.SilkS")
		)
		(fp_rect
			(start 2.159 1.5748)
			(end -2.159 -1.5748)
			(stroke
				(width 0)
				(type default)
			)
			(fill no)
			(layer "F.CrtYd")
		)
		(fp_line
			(start -1.6002 -1.2446)
			(end -1.6002 1.2446)
			(stroke
				(width 0.1)
				(type default)
			)
			(layer "F.Fab")
		)
		(fp_line
			(start -1.6002 1.2446)
			(end 1.6002 1.2446)
			(stroke
				(width 0.1)
				(type default)
			)
			(layer "F.Fab")
		)
		(fp_line
			(start 1.6002 -1.2446)
			(end -1.6002 -1.2446)
			(stroke
				(width 0.1)
				(type default)
			)
			(layer "F.Fab")
		)
		(fp_line
			(start 1.6002 1.2446)
			(end 1.6002 -1.2446)
			(stroke
				(width 0.1)
				(type default)
			)
			(layer "F.Fab")
		)
		(pad "1" smd rect
			(at -1.3335 0)
			(size 1.143 2.6416)
			(layers "F.Cu" "F.Mask" "F.Paste")
			(net "XP1R0V_FPGA_VCCINT")
		)
		(pad "2" smd rect
			(at 1.3335 0)
			(size 1.143 2.6416)
			(layers "F.Cu" "F.Mask" "F.Paste")
			(net "SG")
		)
		(zone
			(layer "F.Cu")
			(hatch none 0.5)
			(connect_pads
				(clearance 0)
			)
			(min_thickness 0.25)
			(keepout
				(tracks allowed)
				(vias not_allowed)
				(pads allowed)
				(copperpour not_allowed)
				(footprints allowed)
			)
			(placement
				(enabled no)
				(sheetname "")
			)
			(fill
				(thermal_gap 0.5)
				(thermal_bridge_width 0.5)
				(island_removal_mode 0)
			)
			(polygon
				(pts
					(xy 133.9088 -32.766) (xy 133.9088 -35.56) (xy 132.5372 -35.56) (xy 132.5372 -32.766)
				)
			)
		)
	)
	(footprint ""
		(layer "F.Cu")
		(at 90.9828 -70.6628 -90)
		(property "Reference" "C198"
			(at -18.6182 27.44343 90)
			(unlocked yes)
			(layer "F.SilkS")
			(effects
				(font
					(size 0.7874 0.5842)
					(thickness 0.1524)
				)
			)
		)
		(property "Value" "VAL*"
			(at 0.02032 2.13233 270)
			(unlocked yes)
			(layer "F.Fab")
			(hide yes)
			(effects
				(font
					(size 0.7874 0.5842)
					(thickness 0.1524)
				)
			)
		)
		(property "Tolerance" "TOL*"
			(at 0.044704 3.05435 270)
			(unlocked yes)
			(layer "Cmts.User")
			(hide yes)
			(effects
				(font
					(size 0.7874 0.5842)
					(thickness 0.1524)
				)
			)
		)
		(property "User Part Number" "PARTNUM*"
			(at 0.02032 4.024884 270)
			(unlocked yes)
			(layer "Cmts.User")
			(hide yes)
			(effects
				(font
					(size 0.7874 0.5842)
					(thickness 0.1524)
				)
			)
		)
		(property "Device Type" "CAPACITOR-G105-0F475-BM,4.7UF,A"
			(at 0.008382 1.210564 270)
			(unlocked yes)
			(layer "F.Fab")
			(hide yes)
			(effects
				(font
					(size 0.7874 0.5842)
					(thickness 0.1524)
				)
			)
		)
		(duplicate_pad_numbers_are_jumpers no)
		(fp_line
			(start -1.143 0.5588)
			(end 1.143 0.5588)
			(stroke
				(width 0.1)
				(type default)
			)
			(layer "F.SilkS")
		)
		(fp_line
			(start 1.143 0.5588)
			(end 1.143 -0.5588)
			(stroke
				(width 0.1)
				(type default)
			)
			(layer "F.SilkS")
		)
		(fp_line
			(start -1.143 -0.5588)
			(end -1.143 0.5588)
			(stroke
				(width 0.1)
				(type default)
			)
			(layer "F.SilkS")
		)
		(fp_line
			(start 1.143 -0.5588)
			(end -1.143 -0.5588)
			(stroke
				(width 0.1)
				(type default)
			)
			(layer "F.SilkS")
		)
		(fp_rect
			(start 1.143 0.5588)
			(end -1.143 -0.5588)
			(stroke
				(width 0)
				(type default)
			)
			(fill no)
			(layer "F.CrtYd")
		)
		(fp_line
			(start -0.508 0.3048)
			(end 0.508 0.3048)
			(stroke
				(width 0.1)
				(type default)
			)
			(layer "F.Fab")
		)
		(fp_line
			(start 0.508 0.3048)
			(end 0.508 -0.3048)
			(stroke
				(width 0.1)
				(type default)
			)
			(layer "F.Fab")
		)
		(fp_line
			(start -0.508 -0.3048)
			(end -0.508 0.3048)
			(stroke
				(width 0.1)
				(type default)
			)
			(layer "F.Fab")
		)
		(fp_line
			(start 0.508 -0.3048)
			(end -0.508 -0.3048)
			(stroke
				(width 0.1)
				(type default)
			)
			(layer "F.Fab")
		)
		(pad "1" smd rect
			(at -0.5334 0 270)
			(size 0.7112 0.6096)
			(layers "F.Cu" "F.Mask" "F.Paste")
			(net "XP3R3V_FPGA")
		)
		(pad "2" smd rect
			(at 0.5334 0 270)
			(size 0.7112 0.6096)
			(layers "F.Cu" "F.Mask" "F.Paste")
			(net "SG")
		)
		(zone
			(layer "F.Cu")
			(hatch none 0.5)
			(connect_pads
				(clearance 0)
			)
			(min_thickness 0.25)
			(keepout
				(tracks allowed)
				(vias not_allowed)
				(pads allowed)
				(copperpour not_allowed)
				(footprints allowed)
			)
			(placement
				(enabled no)
				(sheetname "")
			)
			(fill
				(thermal_gap 0.5)
				(thermal_bridge_width 0.5)
				(island_removal_mode 0)
			)
			(polygon
				(pts
					(xy 90.678 -70.5866) (xy 91.2876 -70.5866) (xy 91.2876 -70.739) (xy 90.678 -70.739)
				)
			)
		)
	)
	(footprint ""
		(layer "F.Cu")
		(at 23.608792 -68.1482)
		(property "Reference" "C278"
			(at 3.315208 -0.01143 0)
			(unlocked yes)
			(layer "F.SilkS")
			(effects
				(font
					(size 0.7874 0.5842)
					(thickness 0.1524)
				)
			)
		)
		(property "Value" "VAL*"
			(at 0.0762 2.067306 0)
			(unlocked yes)
			(layer "F.Fab")
			(hide yes)
			(effects
				(font
					(size 0.7874 0.5842)
					(thickness 0.1524)
				)
			)
		)
		(property "Tolerance" "TOL*"
			(at 0.0762 3.032506 0)
			(unlocked yes)
			(layer "Cmts.User")
			(hide yes)
			(effects
				(font
					(size 0.7874 0.5842)
					(thickness 0.1524)
				)
			)
		)
		(property "User Part Number" "PARTNUM*"
			(at 0.1016 4.023106 0)
			(unlocked yes)
			(layer "Cmts.User")
			(hide yes)
			(effects
				(font
					(size 0.7874 0.5842)
					(thickness 0.1524)
				)
			)
		)
		(property "Device Type" "CAPACITOR-G105-0B104-EK,0.1UF,A"
			(at 0.0508 1.127506 0)
			(unlocked yes)
			(layer "F.Fab")
			(hide yes)
			(effects
				(font
					(size 0.7874 0.5842)
					(thickness 0.1524)
				)
			)
		)
		(duplicate_pad_numbers_are_jumpers no)
		(fp_line
			(start -1.143 -0.5588)
			(end -1.143 0.5588)
			(stroke
				(width 0.1)
				(type default)
			)
			(layer "F.SilkS")
		)
		(fp_line
			(start -1.143 0.5588)
			(end 1.143 0.5588)
			(stroke
				(width 0.1)
				(type default)
			)
			(layer "F.SilkS")
		)
		(fp_line
			(start 1.143 -0.5588)
			(end -1.143 -0.5588)
			(stroke
				(width 0.1)
				(type default)
			)
			(layer "F.SilkS")
		)
		(fp_line
			(start 1.143 0.5588)
			(end 1.143 -0.5588)
			(stroke
				(width 0.1)
				(type default)
			)
			(layer "F.SilkS")
		)
		(fp_rect
			(start -1.143 -0.5588)
			(end 1.143 0.5588)
			(stroke
				(width 0)
				(type default)
			)
			(fill no)
			(layer "F.CrtYd")
		)
		(fp_line
			(start -0.508 -0.3048)
			(end -0.508 0.3048)
			(stroke
				(width 0.1)
				(type default)
			)
			(layer "F.Fab")
		)
		(fp_line
			(start -0.508 0.3048)
			(end 0.508 0.3048)
			(stroke
				(width 0.1)
				(type default)
			)
			(layer "F.Fab")
		)
		(fp_line
			(start 0.508 -0.3048)
			(end -0.508 -0.3048)
			(stroke
				(width 0.1)
				(type default)
			)
			(layer "F.Fab")
		)
		(fp_line
			(start 0.508 0.3048)
			(end 0.508 -0.3048)
			(stroke
				(width 0.1)
				(type default)
			)
			(layer "F.Fab")
		)
		(pad "1" smd rect
			(at -0.5334 0)
			(size 0.7112 0.6096)
			(layers "F.Cu" "F.Mask" "F.Paste")
			(net "XP1R8V_ICP10100")
		)
		(pad "2" smd rect
			(at 0.5334 0)
			(size 0.7112 0.6096)
			(layers "F.Cu" "F.Mask" "F.Paste")
			(net "SG")
		)
		(zone
			(layer "F.Cu")
			(hatch none 0.5)
			(connect_pads
				(clearance 0)
			)
			(min_thickness 0.25)
			(keepout
				(tracks allowed)
				(vias not_allowed)
				(pads allowed)
				(copperpour not_allowed)
				(footprints allowed)
			)
			(placement
				(enabled no)
				(sheetname "")
			)
			(fill
				(thermal_gap 0.5)
				(thermal_bridge_width 0.5)
				(island_removal_mode 0)
			)
			(polygon
				(pts
					(xy 23.532592 -68.453) (xy 23.532592 -67.8434) (xy 23.684992 -67.8434) (xy 23.684992 -68.453)
				)
			)
		)
	)
	(footprint ""
		(layer "F.Cu")
		(at 63.881 -135.509)
		(property "Reference" "SP47"
			(at 0 0 0)
			(layer "F.SilkS")
			(hide yes)
			(effects
				(font
					(size 1.27 1.27)
				)
			)
		)
		(property "Value" ""
			(at 0 0 0)
			(layer "F.Fab")
			(effects
				(font
					(size 1.27 1.27)
				)
			)
		)
		(duplicate_pad_numbers_are_jumpers no)
	)
	(footprint ""
		(layer "F.Cu")
		(at 54.0512 -74.9808 90)
		(property "Reference" "R412"
			(at -0.5588 4.40817 90)
			(unlocked yes)
			(layer "F.SilkS")
			(effects
				(font
					(size 0.7874 0.5842)
					(thickness 0.1524)
				)
			)
		)
		(property "Value" "VAL*"
			(at 0.02032 2.13233 90)
			(unlocked yes)
			(layer "F.Fab")
			(hide yes)
			(effects
				(font
					(size 0.7874 0.5842)
					(thickness 0.1524)
				)
			)
		)
		(property "Device Type" "RESISTOR-G155-14701-01,4.7KOHMA"
			(at 0.008382 1.210564 90)
			(unlocked yes)
			(layer "F.Fab")
			(hide yes)
			(effects
				(font
					(size 0.7874 0.5842)
					(thickness 0.1524)
				)
			)
		)
		(property "User Part Number" "PARTNUM*"
			(at 0.02032 4.024884 90)
			(unlocked yes)
			(layer "Cmts.User")
			(hide yes)
			(effects
				(font
					(size 0.7874 0.5842)
					(thickness 0.1524)
				)
			)
		)
		(property "Tolerance" "TOL*"
			(at 0.044704 3.05435 90)
			(unlocked yes)
			(layer "Cmts.User")
			(hide yes)
			(effects
				(font
					(size 0.7874 0.5842)
					(thickness 0.1524)
				)
			)
		)
		(duplicate_pad_numbers_are_jumpers no)
		(fp_line
			(start 1.143 -0.5588)
			(end -1.143 -0.5588)
			(stroke
				(width 0.1)
				(type default)
			)
			(layer "F.SilkS")
		)
		(fp_line
			(start -1.143 -0.5588)
			(end -1.143 0.5588)
			(stroke
				(width 0.1)
				(type default)
			)
			(layer "F.SilkS")
		)
		(fp_line
			(start 1.143 0.5588)
			(end 1.143 -0.5588)
			(stroke
				(width 0.1)
				(type default)
			)
			(layer "F.SilkS")
		)
		(fp_line
			(start -1.143 0.5588)
			(end 1.143 0.5588)
			(stroke
				(width 0.1)
				(type default)
			)
			(layer "F.SilkS")
		)
		(fp_rect
			(start -1.143 0.5588)
			(end 1.143 -0.5588)
			(stroke
				(width 0)
				(type default)
			)
			(fill no)
			(layer "F.CrtYd")
		)
		(fp_line
			(start 0.508 -0.3048)
			(end -0.508 -0.3048)
			(stroke
				(width 0.1)
				(type default)
			)
			(layer "F.Fab")
		)
		(fp_line
			(start -0.508 -0.3048)
			(end -0.508 0.3048)
			(stroke
				(width 0.1)
				(type default)
			)
			(layer "F.Fab")
		)
		(fp_line
			(start 0.508 0.3048)
			(end 0.508 -0.3048)
			(stroke
				(width 0.1)
				(type default)
			)
			(layer "F.Fab")
		)
		(fp_line
			(start -0.508 0.3048)
			(end 0.508 0.3048)
			(stroke
				(width 0.1)
				(type default)
			)
			(layer "F.Fab")
		)
		(pad "1" smd rect
			(at -0.5334 0 90)
			(size 0.7112 0.6096)
			(layers "F.Cu" "F.Mask" "F.Paste")
			(net "XP3R3V_FPGA")
		)
		(pad "2" smd rect
			(at 0.5334 0 90)
			(size 0.7112 0.6096)
			(layers "F.Cu" "F.Mask" "F.Paste")
			(net "UNNAMED_6_LM75BDPTSSOP8_I59_A1")
		)
		(zone
			(layer "F.Cu")
			(hatch none 0.5)
			(connect_pads
				(clearance 0)
			)
			(min_thickness 0.25)
			(keepout
				(tracks not_allowed)
				(vias allowed)
				(pads allowed)
				(copperpour not_allowed)
				(footprints allowed)
			)
			(placement
				(enabled no)
				(sheetname "")
			)
			(fill
				(thermal_gap 0.5)
				(thermal_bridge_width 0.5)
				(island_removal_mode 0)
			)
			(polygon
				(pts
					(xy 54.356 -74.9046) (xy 54.356 -75.057) (xy 53.7464 -75.057) (xy 53.7464 -74.9046)
				)
			)
		)
		(zone
			(layer "F.Cu")
			(hatch none 0.5)
			(connect_pads
				(clearance 0)
			)
			(min_thickness 0.25)
			(keepout
				(tracks allowed)
				(vias not_allowed)
				(pads allowed)
				(copperpour not_allowed)
				(footprints allowed)
			)
			(placement
				(enabled no)
				(sheetname "")
			)
			(fill
				(thermal_gap 0.5)
				(thermal_bridge_width 0.5)
				(island_removal_mode 0)
			)
			(polygon
				(pts
					(xy 54.356 -74.9046) (xy 54.356 -75.057) (xy 53.7464 -75.057) (xy 53.7464 -74.9046)
				)
			)
		)
	)
	(footprint ""
		(layer "F.Cu")
		(at 138.811 -59.563 -90)
		(property "Reference" "R245"
			(at -3.048 1.48463 90)
			(unlocked yes)
			(layer "F.SilkS")
			(effects
				(font
					(size 0.7874 0.5842)
					(thickness 0.1524)
				)
			)
		)
		(property "Value" "VAL*"
			(at 0.02032 2.13233 270)
			(unlocked yes)
			(layer "F.Fab")
			(hide yes)
			(effects
				(font
					(size 0.7874 0.5842)
					(thickness 0.1524)
				)
			)
		)
		(property "Device Type" "RESISTOR-G155-100R0-J0,0OHM,-"
			(at 0.008382 1.210564 270)
			(unlocked yes)
			(layer "F.Fab")
			(hide yes)
			(effects
				(font
					(size 0.7874 0.5842)
					(thickness 0.1524)
				)
			)
		)
		(property "User Part Number" "PARTNUM*"
			(at 0.02032 4.024884 270)
			(unlocked yes)
			(layer "Cmts.User")
			(hide yes)
			(effects
				(font
					(size 0.7874 0.5842)
					(thickness 0.1524)
				)
			)
		)
		(property "Tolerance" "TOL*"
			(at 0.044704 3.05435 270)
			(unlocked yes)
			(layer "Cmts.User")
			(hide yes)
			(effects
				(font
					(size 0.7874 0.5842)
					(thickness 0.1524)
				)
			)
		)
		(duplicate_pad_numbers_are_jumpers no)
		(fp_line
			(start -1.143 0.5588)
			(end 1.143 0.5588)
			(stroke
				(width 0.1)
				(type default)
			)
			(layer "F.SilkS")
		)
		(fp_line
			(start 1.143 0.5588)
			(end 1.143 -0.5588)
			(stroke
				(width 0.1)
				(type default)
			)
			(layer "F.SilkS")
		)
		(fp_line
			(start -1.143 -0.5588)
			(end -1.143 0.5588)
			(stroke
				(width 0.1)
				(type default)
			)
			(layer "F.SilkS")
		)
		(fp_line
			(start 1.143 -0.5588)
			(end -1.143 -0.5588)
			(stroke
				(width 0.1)
				(type default)
			)
			(layer "F.SilkS")
		)
		(fp_rect
			(start 1.143 0.5588)
			(end -1.143 -0.5588)
			(stroke
				(width 0)
				(type default)
			)
			(fill no)
			(layer "F.CrtYd")
		)
		(fp_line
			(start -0.508 0.3048)
			(end 0.508 0.3048)
			(stroke
				(width 0.1)
				(type default)
			)
			(layer "F.Fab")
		)
		(fp_line
			(start 0.508 0.3048)
			(end 0.508 -0.3048)
			(stroke
				(width 0.1)
				(type default)
			)
			(layer "F.Fab")
		)
		(fp_line
			(start -0.508 -0.3048)
			(end -0.508 0.3048)
			(stroke
				(width 0.1)
				(type default)
			)
			(layer "F.Fab")
		)
		(fp_line
			(start 0.508 -0.3048)
			(end -0.508 -0.3048)
			(stroke
				(width 0.1)
				(type default)
			)
			(layer "F.Fab")
		)
		(pad "1" smd rect
			(at -0.5334 0 270)
			(size 0.7112 0.6096)
			(layers "F.Cu" "F.Mask" "F.Paste")
			(net "XP1R0V_FPGA_PG")
		)
		(pad "2" smd rect
			(at 0.5334 0 270)
			(size 0.7112 0.6096)
			(layers "F.Cu" "F.Mask" "F.Paste")
			(net "XP1R0V_PG")
		)
		(zone
			(layer "F.Cu")
			(hatch none 0.5)
			(connect_pads
				(clearance 0)
			)
			(min_thickness 0.25)
			(keepout
				(tracks allowed)
				(vias not_allowed)
				(pads allowed)
				(copperpour not_allowed)
				(footprints allowed)
			)
			(placement
				(enabled no)
				(sheetname "")
			)
			(fill
				(thermal_gap 0.5)
				(thermal_bridge_width 0.5)
				(island_removal_mode 0)
			)
			(polygon
				(pts
					(xy 138.5062 -59.4868) (xy 139.1158 -59.4868) (xy 139.1158 -59.6392) (xy 138.5062 -59.6392)
				)
			)
		)
	)
	(footprint ""
		(layer "F.Cu")
		(at 133.858 -23.368)
		(property "Reference" "C92"
			(at -0.635 -4.78663 0)
			(unlocked yes)
			(layer "F.SilkS")
			(effects
				(font
					(size 0.7874 0.5842)
					(thickness 0.1524)
				)
			)
		)
		(property "Value" "VAL*"
			(at 0.0762 2.067306 0)
			(unlocked yes)
			(layer "F.Fab")
			(hide yes)
			(effects
				(font
					(size 0.7874 0.5842)
					(thickness 0.1524)
				)
			)
		)
		(property "Device Type" "CAPACITOR-G105-0B104-EK,0.1UF,A"
			(at 0.0508 1.127506 0)
			(unlocked yes)
			(layer "F.Fab")
			(hide yes)
			(effects
				(font
					(size 0.7874 0.5842)
					(thickness 0.1524)
				)
			)
		)
		(property "User Part Number" "PARTNUM*"
			(at 0.1016 4.023106 0)
			(unlocked yes)
			(layer "Cmts.User")
			(hide yes)
			(effects
				(font
					(size 0.7874 0.5842)
					(thickness 0.1524)
				)
			)
		)
		(property "Tolerance" "TOL*"
			(at 0.0762 3.032506 0)
			(unlocked yes)
			(layer "Cmts.User")
			(hide yes)
			(effects
				(font
					(size 0.7874 0.5842)
					(thickness 0.1524)
				)
			)
		)
		(duplicate_pad_numbers_are_jumpers no)
		(fp_line
			(start -1.143 -0.5588)
			(end -1.143 0.5588)
			(stroke
				(width 0.1)
				(type default)
			)
			(layer "F.SilkS")
		)
		(fp_line
			(start -1.143 0.5588)
			(end 1.143 0.5588)
			(stroke
				(width 0.1)
				(type default)
			)
			(layer "F.SilkS")
		)
		(fp_line
			(start 1.143 -0.5588)
			(end -1.143 -0.5588)
			(stroke
				(width 0.1)
				(type default)
			)
			(layer "F.SilkS")
		)
		(fp_line
			(start 1.143 0.5588)
			(end 1.143 -0.5588)
			(stroke
				(width 0.1)
				(type default)
			)
			(layer "F.SilkS")
		)
		(fp_rect
			(start 1.143 -0.5588)
			(end -1.143 0.5588)
			(stroke
				(width 0)
				(type default)
			)
			(fill no)
			(layer "F.CrtYd")
		)
		(fp_line
			(start -0.508 -0.3048)
			(end -0.508 0.3048)
			(stroke
				(width 0.1)
				(type default)
			)
			(layer "F.Fab")
		)
		(fp_line
			(start -0.508 0.3048)
			(end 0.508 0.3048)
			(stroke
				(width 0.1)
				(type default)
			)
			(layer "F.Fab")
		)
		(fp_line
			(start 0.508 -0.3048)
			(end -0.508 -0.3048)
			(stroke
				(width 0.1)
				(type default)
			)
			(layer "F.Fab")
		)
		(fp_line
			(start 0.508 0.3048)
			(end 0.508 -0.3048)
			(stroke
				(width 0.1)
				(type default)
			)
			(layer "F.Fab")
		)
		(pad "1" smd rect
			(at -0.5334 0)
			(size 0.7112 0.6096)
			(layers "F.Cu" "F.Mask" "F.Paste")
			(net "XP3R3V_FPGA")
		)
		(pad "2" smd rect
			(at 0.5334 0)
			(size 0.7112 0.6096)
			(layers "F.Cu" "F.Mask" "F.Paste")
			(net "SG")
		)
		(zone
			(layer "F.Cu")
			(hatch none 0.5)
			(connect_pads
				(clearance 0)
			)
			(min_thickness 0.25)
			(keepout
				(tracks allowed)
				(vias not_allowed)
				(pads allowed)
				(copperpour not_allowed)
				(footprints allowed)
			)
			(placement
				(enabled no)
				(sheetname "")
			)
			(fill
				(thermal_gap 0.5)
				(thermal_bridge_width 0.5)
				(island_removal_mode 0)
			)
			(polygon
				(pts
					(xy 133.9342 -23.6728) (xy 133.7818 -23.6728) (xy 133.7818 -23.0632) (xy 133.9342 -23.0632)
				)
			)
		)
	)
	(footprint ""
		(layer "F.Cu")
		(at 27.305 -75.184 -90)
		(property "Reference" "R353"
			(at 3.175 -0.29337 90)
			(unlocked yes)
			(layer "F.SilkS")
			(effects
				(font
					(size 0.7874 0.5842)
					(thickness 0.1524)
				)
			)
		)
		(property "Value" "VAL*"
			(at 0.02032 2.13233 270)
			(unlocked yes)
			(layer "F.Fab")
			(hide yes)
			(effects
				(font
					(size 0.7874 0.5842)
					(thickness 0.1524)
				)
			)
		)
		(property "Tolerance" "TOL*"
			(at 0.044704 3.05435 270)
			(unlocked yes)
			(layer "Cmts.User")
			(hide yes)
			(effects
				(font
					(size 0.7874 0.5842)
					(thickness 0.1524)
				)
			)
		)
		(property "User Part Number" "PARTNUM*"
			(at 0.02032 4.024884 270)
			(unlocked yes)
			(layer "Cmts.User")
			(hide yes)
			(effects
				(font
					(size 0.7874 0.5842)
					(thickness 0.1524)
				)
			)
		)
		(property "Device Type" "RESISTOR-G155-11000-01,100OHM,A"
			(at 0.008382 1.210564 270)
			(unlocked yes)
			(layer "F.Fab")
			(hide yes)
			(effects
				(font
					(size 0.7874 0.5842)
					(thickness 0.1524)
				)
			)
		)
		(duplicate_pad_numbers_are_jumpers no)
		(fp_line
			(start -1.143 0.5588)
			(end 1.143 0.5588)
			(stroke
				(width 0.1)
				(type default)
			)
			(layer "F.SilkS")
		)
		(fp_line
			(start 1.143 0.5588)
			(end 1.143 -0.5588)
			(stroke
				(width 0.1)
				(type default)
			)
			(layer "F.SilkS")
		)
		(fp_line
			(start -1.143 -0.5588)
			(end -1.143 0.5588)
			(stroke
				(width 0.1)
				(type default)
			)
			(layer "F.SilkS")
		)
		(fp_line
			(start 1.143 -0.5588)
			(end -1.143 -0.5588)
			(stroke
				(width 0.1)
				(type default)
			)
			(layer "F.SilkS")
		)
		(fp_poly
			(pts
				(xy -1.143 0.5588) (xy 1.143 0.5588) (xy 1.143 -0.5588) (xy -1.143 -0.5588)
			)
			(stroke
				(width 0)
				(type default)
			)
			(fill no)
			(layer "F.CrtYd")
		)
		(fp_line
			(start -0.508 0.3048)
			(end 0.508 0.3048)
			(stroke
				(width 0.1)
				(type default)
			)
			(layer "F.Fab")
		)
		(fp_line
			(start 0.508 0.3048)
			(end 0.508 -0.3048)
			(stroke
				(width 0.1)
				(type default)
			)
			(layer "F.Fab")
		)
		(fp_line
			(start -0.508 -0.3048)
			(end -0.508 0.3048)
			(stroke
				(width 0.1)
				(type default)
			)
			(layer "F.Fab")
		)
		(fp_line
			(start 0.508 -0.3048)
			(end -0.508 -0.3048)
			(stroke
				(width 0.1)
				(type default)
			)
			(layer "F.Fab")
		)
		(pad "1" smd rect
			(at -0.5334 0 270)
			(size 0.7112 0.6096)
			(layers "F.Cu" "F.Mask" "F.Paste")
			(net "R_FT4232_CHC_TX")
		)
		(pad "2" smd rect
			(at 0.5334 0 270)
			(size 0.7112 0.6096)
			(layers "F.Cu" "F.Mask" "F.Paste")
			(net "UART_FT4232_TX_FPGA_RX")
		)
		(zone
			(layer "F.Cu")
			(hatch none 0.5)
			(connect_pads
				(clearance 0)
			)
			(min_thickness 0.25)
			(keepout
				(tracks not_allowed)
				(vias allowed)
				(pads allowed)
				(copperpour not_allowed)
				(footprints allowed)
			)
			(placement
				(enabled no)
				(sheetname "")
			)
			(fill
				(thermal_gap 0.5)
				(thermal_bridge_width 0.5)
				(island_removal_mode 0)
			)
			(polygon
				(pts
					(xy 27.0002 -75.2602) (xy 27.0002 -75.1078) (xy 27.6098 -75.1078) (xy 27.6098 -75.2602)
				)
			)
		)
		(zone
			(layer "F.Cu")
			(hatch none 0.5)
			(connect_pads
				(clearance 0)
			)
			(min_thickness 0.25)
			(keepout
				(tracks allowed)
				(vias not_allowed)
				(pads allowed)
				(copperpour not_allowed)
				(footprints allowed)
			)
			(placement
				(enabled no)
				(sheetname "")
			)
			(fill
				(thermal_gap 0.5)
				(thermal_bridge_width 0.5)
				(island_removal_mode 0)
			)
			(polygon
				(pts
					(xy 27.0002 -75.2602) (xy 27.0002 -75.1078) (xy 27.6098 -75.1078) (xy 27.6098 -75.2602)
				)
			)
		)
	)
	(footprint ""
		(layer "F.Cu")
		(at 37.084 -77.216 -90)
		(property "Reference" "C308"
			(at 1.27 3.00863 90)
			(unlocked yes)
			(layer "F.SilkS")
			(effects
				(font
					(size 0.7874 0.5842)
					(thickness 0.1524)
				)
			)
		)
		(property "Value" "VAL*"
			(at 0.0762 3.134106 270)
			(unlocked yes)
			(layer "F.Fab")
			(hide yes)
			(effects
				(font
					(size 0.7874 0.5842)
					(thickness 0.1524)
				)
			)
		)
		(property "Tolerance" "TOL*"
			(at 0.0762 4.048506 270)
			(unlocked yes)
			(layer "Cmts.User")
			(hide yes)
			(effects
				(font
					(size 0.7874 0.5842)
					(thickness 0.1524)
				)
			)
		)
		(property "User Part Number" "PARTNUM*"
			(at 0.1016 5.013706 270)
			(unlocked yes)
			(layer "Cmts.User")
			(hide yes)
			(effects
				(font
					(size 0.7874 0.5842)
					(thickness 0.1524)
				)
			)
		)
		(property "Device Type" "CAPACITOR-G107-0F106-EM,10UF,2A"
			(at 0.0508 2.194306 270)
			(unlocked yes)
			(layer "F.Fab")
			(hide yes)
			(effects
				(font
					(size 0.7874 0.5842)
					(thickness 0.1524)
				)
			)
		)
		(duplicate_pad_numbers_are_jumpers no)
		(fp_line
			(start -1.5748 0.9398)
			(end 1.5748 0.9398)
			(stroke
				(width 0.1)
				(type default)
			)
			(layer "F.SilkS")
		)
		(fp_line
			(start 1.5748 0.9398)
			(end 1.5748 -0.9398)
			(stroke
				(width 0.1)
				(type default)
			)
			(layer "F.SilkS")
		)
		(fp_line
			(start -1.5748 -0.9398)
			(end -1.5748 0.9398)
			(stroke
				(width 0.1)
				(type default)
			)
			(layer "F.SilkS")
		)
		(fp_line
			(start 1.5748 -0.9398)
			(end -1.5748 -0.9398)
			(stroke
				(width 0.1)
				(type default)
			)
			(layer "F.SilkS")
		)
		(fp_poly
			(pts
				(xy -1.5748 0.9398) (xy 1.5748 0.9398) (xy 1.5748 -0.9398) (xy -1.5748 -0.9398)
			)
			(stroke
				(width 0)
				(type default)
			)
			(fill no)
			(layer "F.CrtYd")
		)
		(fp_line
			(start -1.016 0.635)
			(end 1.016 0.635)
			(stroke
				(width 0.1)
				(type default)
			)
			(layer "F.Fab")
		)
		(fp_line
			(start 1.016 0.635)
			(end 1.016 -0.635)
			(stroke
				(width 0.1)
				(type default)
			)
			(layer "F.Fab")
		)
		(fp_line
			(start -1.016 -0.635)
			(end -1.016 0.635)
			(stroke
				(width 0.1)
				(type default)
			)
			(layer "F.Fab")
		)
		(fp_line
			(start 1.016 -0.635)
			(end -1.016 -0.635)
			(stroke
				(width 0.1)
				(type default)
			)
			(layer "F.Fab")
		)
		(pad "1" smd rect
			(at -0.8382 0 270)
			(size 0.9652 1.3716)
			(layers "F.Cu" "F.Mask" "F.Paste")
			(net "XP3R3V_FT4232")
		)
		(pad "2" smd rect
			(at 0.8382 0 270)
			(size 0.9652 1.3716)
			(layers "F.Cu" "F.Mask" "F.Paste")
			(net "SG")
		)
		(zone
			(layer "F.Cu")
			(hatch none 0.5)
			(connect_pads
				(clearance 0)
			)
			(min_thickness 0.25)
			(keepout
				(tracks allowed)
				(vias not_allowed)
				(pads allowed)
				(copperpour not_allowed)
				(footprints allowed)
			)
			(placement
				(enabled no)
				(sheetname "")
			)
			(fill
				(thermal_gap 0.5)
				(thermal_bridge_width 0.5)
				(island_removal_mode 0)
			)
			(polygon
				(pts
					(xy 36.449 -77.4446) (xy 36.449 -76.9874) (xy 37.719 -76.9874) (xy 37.719 -77.4446)
				)
			)
		)
		(zone
			(layer "F.Cu")
			(hatch none 0.5)
			(connect_pads
				(clearance 0)
			)
			(min_thickness 0.25)
			(keepout
				(tracks not_allowed)
				(vias allowed)
				(pads allowed)
				(copperpour not_allowed)
				(footprints allowed)
			)
			(placement
				(enabled no)
				(sheetname "")
			)
			(fill
				(thermal_gap 0.5)
				(thermal_bridge_width 0.5)
				(island_removal_mode 0)
			)
			(polygon
				(pts
					(xy 36.449 -77.4446) (xy 36.449 -76.9874) (xy 37.719 -76.9874) (xy 37.719 -77.4446)
				)
			)
		)
	)
	(footprint ""
		(layer "F.Cu")
		(at 53.467 -15.621 90)
		(property "Reference" "C287"
			(at 3.556 0.42037 90)
			(unlocked yes)
			(layer "F.SilkS")
			(effects
				(font
					(size 0.7874 0.5842)
					(thickness 0.1524)
				)
			)
		)
		(property "Value" "VAL*"
			(at 0.0762 2.067306 90)
			(unlocked yes)
			(layer "F.Fab")
			(hide yes)
			(effects
				(font
					(size 0.7874 0.5842)
					(thickness 0.1524)
				)
			)
		)
		(property "Device Type" "CAPACITOR-G105-0C106-BM,10UF,2A"
			(at 0.0508 1.127506 90)
			(unlocked yes)
			(layer "F.Fab")
			(hide yes)
			(effects
				(font
					(size 0.7874 0.5842)
					(thickness 0.1524)
				)
			)
		)
		(property "User Part Number" "PARTNUM*"
			(at 0.1016 4.023106 90)
			(unlocked yes)
			(layer "Cmts.User")
			(hide yes)
			(effects
				(font
					(size 0.7874 0.5842)
					(thickness 0.1524)
				)
			)
		)
		(property "Tolerance" "TOL*"
			(at 0.0762 3.032506 90)
			(unlocked yes)
			(layer "Cmts.User")
			(hide yes)
			(effects
				(font
					(size 0.7874 0.5842)
					(thickness 0.1524)
				)
			)
		)
		(duplicate_pad_numbers_are_jumpers no)
		(fp_line
			(start 1.143 -0.5588)
			(end -1.143 -0.5588)
			(stroke
				(width 0.1)
				(type default)
			)
			(layer "F.SilkS")
		)
		(fp_line
			(start -1.143 -0.5588)
			(end -1.143 0.5588)
			(stroke
				(width 0.1)
				(type default)
			)
			(layer "F.SilkS")
		)
		(fp_line
			(start 1.143 0.5588)
			(end 1.143 -0.5588)
			(stroke
				(width 0.1)
				(type default)
			)
			(layer "F.SilkS")
		)
		(fp_line
			(start -1.143 0.5588)
			(end 1.143 0.5588)
			(stroke
				(width 0.1)
				(type default)
			)
			(layer "F.SilkS")
		)
		(fp_poly
			(pts
				(xy -1.143 0.5588) (xy 1.143 0.5588) (xy 1.143 -0.5588) (xy -1.143 -0.5588)
			)
			(stroke
				(width 0)
				(type default)
			)
			(fill no)
			(layer "F.CrtYd")
		)
		(fp_line
			(start 0.508 -0.3048)
			(end -0.508 -0.3048)
			(stroke
				(width 0.1)
				(type default)
			)
			(layer "F.Fab")
		)
		(fp_line
			(start -0.508 -0.3048)
			(end -0.508 0.3048)
			(stroke
				(width 0.1)
				(type default)
			)
			(layer "F.Fab")
		)
		(fp_line
			(start 0.508 0.3048)
			(end 0.508 -0.3048)
			(stroke
				(width 0.1)
				(type default)
			)
			(layer "F.Fab")
		)
		(fp_line
			(start -0.508 0.3048)
			(end 0.508 0.3048)
			(stroke
				(width 0.1)
				(type default)
			)
			(layer "F.Fab")
		)
		(pad "1" smd rect
			(at -0.5334 0 90)
			(size 0.7112 0.6096)
			(layers "F.Cu" "F.Mask" "F.Paste")
			(net "XP3R3V_AUX_PCIE")
		)
		(pad "2" smd rect
			(at 0.5334 0 90)
			(size 0.7112 0.6096)
			(layers "F.Cu" "F.Mask" "F.Paste")
			(net "SG")
		)
		(zone
			(layer "F.Cu")
			(hatch none 0.5)
			(connect_pads
				(clearance 0)
			)
			(min_thickness 0.25)
			(keepout
				(tracks not_allowed)
				(vias allowed)
				(pads allowed)
				(copperpour not_allowed)
				(footprints allowed)
			)
			(placement
				(enabled no)
				(sheetname "")
			)
			(fill
				(thermal_gap 0.5)
				(thermal_bridge_width 0.5)
				(island_removal_mode 0)
			)
			(polygon
				(pts
					(xy 53.7718 -15.5448) (xy 53.7718 -15.6972) (xy 53.1622 -15.6972) (xy 53.1622 -15.5448)
				)
			)
		)
		(zone
			(layer "F.Cu")
			(hatch none 0.5)
			(connect_pads
				(clearance 0)
			)
			(min_thickness 0.25)
			(keepout
				(tracks allowed)
				(vias not_allowed)
				(pads allowed)
				(copperpour not_allowed)
				(footprints allowed)
			)
			(placement
				(enabled no)
				(sheetname "")
			)
			(fill
				(thermal_gap 0.5)
				(thermal_bridge_width 0.5)
				(island_removal_mode 0)
			)
			(polygon
				(pts
					(xy 53.7718 -15.5448) (xy 53.7718 -15.6972) (xy 53.1622 -15.6972) (xy 53.1622 -15.5448)
				)
			)
		)
	)
	(footprint ""
		(layer "F.Cu")
		(at 149.098 -46.736)
		(property "Reference" "TP27"
			(at -2.4892 1.43637 0)
			(unlocked yes)
			(layer "F.SilkS")
			(effects
				(font
					(size 0.7874 0.5842)
					(thickness 0.1524)
				)
				(justify left)
			)
		)
		(property "Value" ""
			(at 0 0 0)
			(layer "F.Fab")
			(effects
				(font
					(size 1.27 1.27)
				)
			)
		)
		(property "Device Type" "TP_PIONT-TP010CT020B030_PTH-TPA"
			(at -1.341882 0.996696 0)
			(unlocked yes)
			(layer "F.Fab")
			(hide yes)
			(effects
				(font
					(size 0.7874 0.5842)
					(thickness 0.000001)
				)
				(justify left)
			)
		)
		(duplicate_pad_numbers_are_jumpers no)
		(fp_poly
			(pts
				(arc
					(start 0.889 0)
					(mid -0.889 0)
					(end 0.889 0)
				)
			)
			(stroke
				(width 0)
				(type default)
			)
			(fill no)
			(layer "B.CrtYd")
		)
		(fp_poly
			(pts
				(arc
					(start 0.889 0)
					(mid -0.889 0)
					(end 0.889 0)
				)
			)
			(stroke
				(width 0)
				(type default)
			)
			(fill no)
			(layer "F.CrtYd")
		)
		(pad "1" thru_hole circle
			(at 0 0)
			(size 0.508 0.508)
			(drill 0.254)
			(layers "*.Cu" "*.Mask")
			(remove_unused_layers no)
			(net "R_SHT3X_ALERT_N")
			(clearance 0.1016)
			(padstack
				(mode front_inner_back)
				(layer "Inner"
					(shape circle)
					(size 0.508 0.508)
					(clearance 0.1016)
				)
				(layer "B.Cu"
					(shape circle)
					(size 0.762 0.762)
					(clearance -0.0254)
				)
			)
		)
	)
	(footprint ""
		(layer "F.Cu")
		(at 13.899896 -47.099982 -90)
		(property "Reference" "U16"
			(at -0.906018 2.049526 90)
			(unlocked yes)
			(layer "F.SilkS")
			(effects
				(font
					(size 0.7874 0.5842)
					(thickness 0.1524)
				)
			)
		)
		(property "Value" ""
			(at 0 0 270)
			(layer "F.Fab")
			(effects
				(font
					(size 1.27 1.27)
				)
			)
		)
		(property "Device Type" "74HCT2G125DP_TSSOP8-G220-00055A"
			(at 0 2.413 270)
			(unlocked yes)
			(layer "F.Fab")
			(hide yes)
			(effects
				(font
					(size 0.7874 0.5842)
					(thickness 0.1524)
				)
			)
		)
		(property "User Part Number" "PARTNUM*"
			(at 0 3.6068 270)
			(unlocked yes)
			(layer "Cmts.User")
			(hide yes)
			(effects
				(font
					(size 0.7874 0.5842)
					(thickness 0.1524)
				)
			)
		)
		(duplicate_pad_numbers_are_jumpers no)
		(fp_line
			(start -2.426716 1.304036)
			(end -2.426716 -1.304036)
			(stroke
				(width 0.1)
				(type default)
			)
			(layer "F.SilkS")
		)
		(fp_line
			(start 2.426716 1.304036)
			(end -2.426716 1.304036)
			(stroke
				(width 0.1)
				(type default)
			)
			(layer "F.SilkS")
		)
		(fp_line
			(start -2.426716 -1.304036)
			(end 2.426716 -1.304036)
			(stroke
				(width 0.1)
				(type default)
			)
			(layer "F.SilkS")
		)
		(fp_line
			(start 2.426716 -1.304036)
			(end 2.426716 1.304036)
			(stroke
				(width 0.1)
				(type default)
			)
			(layer "F.SilkS")
		)
		(fp_poly
			(pts
				(arc
					(start -3.21437 -1.465326)
					(mid -3.21437 -0.703326)
					(end -3.21437 -1.465326)
				)
			)
			(stroke
				(width 0)
				(type default)
			)
			(fill yes)
			(layer "F.SilkS")
		)
		(fp_poly
			(pts
				(xy -2.680716 1.558036) (xy 2.680716 1.558036) (xy 2.680716 -1.558036) (xy -2.680716 -1.558036)
			)
			(stroke
				(width 0)
				(type default)
			)
			(fill no)
			(layer "F.CrtYd")
		)
		(fp_line
			(start -1.199896 1.050036)
			(end 1.199896 1.050036)
			(stroke
				(width 0.1)
				(type default)
			)
			(layer "F.Fab")
		)
		(fp_line
			(start 1.199896 1.050036)
			(end 1.199896 -1.050036)
			(stroke
				(width 0.1)
				(type default)
			)
			(layer "F.Fab")
		)
		(fp_line
			(start -1.199896 -1.050036)
			(end -1.199896 1.050036)
			(stroke
				(width 0.1)
				(type default)
			)
			(layer "F.Fab")
		)
		(fp_line
			(start 1.199896 -1.050036)
			(end -1.199896 -1.050036)
			(stroke
				(width 0.1)
				(type default)
			)
			(layer "F.Fab")
		)
		(fp_poly
			(pts
				(arc
					(start -1.922018 -1.721104)
					(mid -1.922018 -0.959104)
					(end -1.922018 -1.721104)
				)
			)
			(stroke
				(width 0)
				(type default)
			)
			(fill yes)
			(layer "F.Fab")
		)
		(fp_text user "5"
			(at 2.884932 1.580896 0)
			(unlocked yes)
			(layer "F.SilkS")
			(effects
				(font
					(size 0.635 0.4064)
					(thickness 0.1524)
				)
			)
		)
		(fp_text user "4"
			(at -2.957068 1.326896 0)
			(unlocked yes)
			(layer "F.SilkS")
			(effects
				(font
					(size 0.635 0.4064)
					(thickness 0.1524)
				)
			)
		)
		(fp_text user "8"
			(at 1.919732 -1.721104 0)
			(unlocked yes)
			(layer "F.SilkS")
			(effects
				(font
					(size 0.635 0.4064)
					(thickness 0.1524)
				)
			)
		)
		(fp_text user "4"
			(at -1.755648 1.326896 0)
			(unlocked yes)
			(layer "F.Fab")
			(effects
				(font
					(size 0.7874 0.5842)
					(thickness 0.1524)
				)
			)
		)
		(fp_text user "5"
			(at 2.181352 1.199896 0)
			(unlocked yes)
			(layer "F.Fab")
			(effects
				(font
					(size 0.7874 0.5842)
					(thickness 0.1524)
				)
			)
		)
		(fp_text user "8"
			(at 2.054352 -1.594104 0)
			(unlocked yes)
			(layer "F.Fab")
			(effects
				(font
					(size 0.7874 0.5842)
					(thickness 0.1524)
				)
			)
		)
		(pad "1" smd rect
			(at -1.690116 -0.749808 270)
			(size 0.9652 0.3048)
			(layers "F.Cu" "F.Mask" "F.Paste")
			(net "SMA2_SIG_OUT_BF_EN_N")
		)
		(pad "2" smd rect
			(at -1.690116 -0.249936 270)
			(size 0.9652 0.3048)
			(layers "F.Cu" "F.Mask" "F.Paste")
			(net "UNNAMED_12_74HCT2G125DPTSSOP8_9")
		)
		(pad "3" smd rect
			(at -1.690116 0.249936 270)
			(size 0.9652 0.3048)
			(layers "F.Cu" "F.Mask" "F.Paste")
			(net "BF_ANT2_IN")
		)
		(pad "4" smd rect
			(at -1.690116 0.749808 270)
			(size 0.9652 0.3048)
			(layers "F.Cu" "F.Mask" "F.Paste")
			(net "SG")
		)
		(pad "5" smd rect
			(at 1.690116 0.749808 270)
			(size 0.9652 0.3048)
			(layers "F.Cu" "F.Mask" "F.Paste")
			(net "BF_SMA2_SIG_IO_CONN")
		)
		(pad "6" smd rect
			(at 1.690116 0.249936 270)
			(size 0.9652 0.3048)
			(layers "F.Cu" "F.Mask" "F.Paste")
			(net "BF_SMA2_SIG_IO_CONN")
		)
		(pad "7" smd rect
			(at 1.690116 -0.249936 270)
			(size 0.9652 0.3048)
			(layers "F.Cu" "F.Mask" "F.Paste")
			(net "SMA2_SIG_IN_BF_EN_N")
		)
		(pad "8" smd rect
			(at 1.690116 -0.749808 270)
			(size 0.9652 0.3048)
			(layers "F.Cu" "F.Mask" "F.Paste")
			(net "XP3R3V_FPGA")
		)
	)
	(footprint ""
		(layer "F.Cu")
		(at 110.8456 -21.971 90)
		(property "Reference" "Y3"
			(at -7.02437 0.0254 0)
			(unlocked yes)
			(layer "F.SilkS")
			(effects
				(font
					(size 0.7874 0.5842)
					(thickness 0.1524)
				)
			)
		)
		(property "Value" ""
			(at 0 0 90)
			(layer "F.Fab")
			(effects
				(font
					(size 1.27 1.27)
				)
			)
		)
		(property "User Part Number" "PARTNUM*"
			(at 0 5.10667 90)
			(unlocked yes)
			(layer "Cmts.User")
			(hide yes)
			(effects
				(font
					(size 0.7874 0.5842)
					(thickness 0.1524)
				)
			)
		)
		(property "Device Type" "OSC6P_V2-A130-00003-AW"
			(at 0 3.91287 90)
			(unlocked yes)
			(layer "F.Fab")
			(hide yes)
			(effects
				(font
					(size 0.7874 0.5842)
					(thickness 0.1524)
				)
			)
		)
		(duplicate_pad_numbers_are_jumpers no)
		(fp_line
			(start 1.903984 -2.803906)
			(end 1.903984 2.803906)
			(stroke
				(width 0.1)
				(type default)
			)
			(layer "F.SilkS")
		)
		(fp_line
			(start -1.903984 -2.803906)
			(end 1.903984 -2.803906)
			(stroke
				(width 0.1)
				(type default)
			)
			(layer "F.SilkS")
		)
		(fp_line
			(start 1.903984 2.803906)
			(end -1.903984 2.803906)
			(stroke
				(width 0.1)
				(type default)
			)
			(layer "F.SilkS")
		)
		(fp_line
			(start -1.903984 2.803906)
			(end -1.903984 -2.803906)
			(stroke
				(width 0.1)
				(type default)
			)
			(layer "F.SilkS")
		)
		(fp_rect
			(start 2.157984 -3.057906)
			(end -2.157984 3.057906)
			(stroke
				(width 0)
				(type default)
			)
			(fill no)
			(layer "F.CrtYd")
		)
		(fp_line
			(start 1.649984 -2.549906)
			(end 1.649984 2.549906)
			(stroke
				(width 0.1)
				(type default)
			)
			(layer "F.Fab")
		)
		(fp_line
			(start -1.649984 -2.549906)
			(end 1.649984 -2.549906)
			(stroke
				(width 0.1)
				(type default)
			)
			(layer "F.Fab")
		)
		(fp_line
			(start 1.649984 2.549906)
			(end -1.649984 2.549906)
			(stroke
				(width 0.1)
				(type default)
			)
			(layer "F.Fab")
		)
		(fp_line
			(start -1.649984 2.549906)
			(end -1.649984 -2.549906)
			(stroke
				(width 0.1)
				(type default)
			)
			(layer "F.Fab")
		)
		(fp_text user "1"
			(at -1.69037 -3.1496 0)
			(unlocked yes)
			(layer "F.SilkS")
			(effects
				(font
					(size 0.7874 0.5842)
					(thickness 0.1524)
				)
			)
		)
		(fp_text user "3"
			(at -1.56337 3.3274 0)
			(unlocked yes)
			(layer "F.SilkS")
			(effects
				(font
					(size 0.7874 0.5842)
					(thickness 0.1524)
				)
			)
		)
		(fp_text user "6"
			(at 2.11963 -2.6416 0)
			(unlocked yes)
			(layer "F.Fab")
			(effects
				(font
					(size 0.7874 0.5842)
					(thickness 0.1524)
				)
			)
		)
		(fp_text user "1"
			(at -2.56667 -2.2606 0)
			(unlocked yes)
			(layer "F.Fab")
			(effects
				(font
					(size 0.7874 0.5842)
					(thickness 0.1524)
				)
			)
		)
		(fp_text user "3"
			(at -2.56667 2.1844 0)
			(unlocked yes)
			(layer "F.Fab")
			(effects
				(font
					(size 0.7874 0.5842)
					(thickness 0.1524)
				)
			)
		)
		(fp_text user "4"
			(at 1.49733 2.9464 0)
			(unlocked yes)
			(layer "F.Fab")
			(effects
				(font
					(size 0.7874 0.5842)
					(thickness 0.1524)
				)
			)
		)
		(pad "1" smd rect
			(at -1.050036 -1.27 90)
			(size 0.889 0.635)
			(layers "F.Cu" "F.Mask" "F.Paste")
			(net "CLK_200M_OE")
		)
		(pad "2" smd rect
			(at -1.050036 0 90)
			(size 0.889 0.635)
			(layers "F.Cu" "F.Mask" "F.Paste")
			(net "Net_763")
		)
		(pad "3" smd rect
			(at -1.050036 1.27 90)
			(size 0.889 0.635)
			(layers "F.Cu" "F.Mask" "F.Paste")
			(net "SG")
		)
		(pad "4" smd rect
			(at 1.050036 1.27 90)
			(size 0.889 0.635)
			(layers "F.Cu" "F.Mask" "F.Paste")
			(net "OSC_200M_CLKP")
		)
		(pad "5" smd rect
			(at 1.050036 0 90)
			(size 0.889 0.635)
			(layers "F.Cu" "F.Mask" "F.Paste")
			(net "OSC_200M_CLKN")
		)
		(pad "6" smd rect
			(at 1.050036 -1.27 90)
			(size 0.889 0.635)
			(layers "F.Cu" "F.Mask" "F.Paste")
			(net "VDD3V3_OSC_200M")
		)
		(zone
			(layer "F.Cu")
			(hatch none 0.5)
			(connect_pads
				(clearance 0)
			)
			(min_thickness 0.25)
			(keepout
				(tracks allowed)
				(vias not_allowed)
				(pads allowed)
				(copperpour not_allowed)
				(footprints allowed)
			)
			(placement
				(enabled no)
				(sheetname "")
			)
			(fill
				(thermal_gap 0.5)
				(thermal_bridge_width 0.5)
				(island_removal_mode 0)
			)
			(polygon
				(pts
					(xy 108.295694 -20.321016) (xy 113.395506 -20.321016) (xy 113.395506 -23.620984) (xy 108.295694 -23.620984)
				)
			)
			(polygon
				(pts
					(xy 109.8931 -21.365464) (xy 109.8931 -20.476464) (xy 109.2581 -20.476464) (xy 109.2581 -21.365464)
				)
			)
			(polygon
				(pts
					(xy 109.8931 -23.465536) (xy 109.8931 -22.576536) (xy 109.2581 -22.576536) (xy 109.2581 -23.465536)
				)
			)
			(polygon
				(pts
					(xy 111.1631 -23.465536) (xy 111.1631 -22.576536) (xy 110.5281 -22.576536) (xy 110.5281 -23.465536)
				)
			)
			(polygon
				(pts
					(xy 111.1631 -21.365464) (xy 111.1631 -20.476464) (xy 110.5281 -20.476464) (xy 110.5281 -21.365464)
				)
			)
			(polygon
				(pts
					(xy 112.4331 -21.365464) (xy 112.4331 -20.476464) (xy 111.7981 -20.476464) (xy 111.7981 -21.365464)
				)
			)
			(polygon
				(pts
					(xy 112.4331 -23.465536) (xy 112.4331 -22.576536) (xy 111.7981 -22.576536) (xy 111.7981 -23.465536)
				)
			)
		)
	)
	(footprint ""
		(layer "F.Cu")
		(at 115.062 -83.058)
		(property "Reference" "C97"
			(at 1.016 -1.10363 0)
			(unlocked yes)
			(layer "F.SilkS")
			(effects
				(font
					(size 0.7874 0.5842)
					(thickness 0.1524)
				)
			)
		)
		(property "Value" "VAL*"
			(at 0.0762 2.067306 0)
			(unlocked yes)
			(layer "F.Fab")
			(hide yes)
			(effects
				(font
					(size 0.7874 0.5842)
					(thickness 0.1524)
				)
			)
		)
		(property "Tolerance" "TOL*"
			(at 0.0762 3.032506 0)
			(unlocked yes)
			(layer "Cmts.User")
			(hide yes)
			(effects
				(font
					(size 0.7874 0.5842)
					(thickness 0.1524)
				)
			)
		)
		(property "User Part Number" "PARTNUM*"
			(at 0.1016 4.023106 0)
			(unlocked yes)
			(layer "Cmts.User")
			(hide yes)
			(effects
				(font
					(size 0.7874 0.5842)
					(thickness 0.1524)
				)
			)
		)
		(property "Device Type" "CAPACITOR-G105-0B104-EK,0.1UF,A"
			(at 0.0508 1.127506 0)
			(unlocked yes)
			(layer "F.Fab")
			(hide yes)
			(effects
				(font
					(size 0.7874 0.5842)
					(thickness 0.1524)
				)
			)
		)
		(duplicate_pad_numbers_are_jumpers no)
		(fp_line
			(start -1.143 -0.5588)
			(end -1.143 0.5588)
			(stroke
				(width 0.1)
				(type default)
			)
			(layer "F.SilkS")
		)
		(fp_line
			(start -1.143 0.5588)
			(end 1.143 0.5588)
			(stroke
				(width 0.1)
				(type default)
			)
			(layer "F.SilkS")
		)
		(fp_line
			(start 1.143 -0.5588)
			(end -1.143 -0.5588)
			(stroke
				(width 0.1)
				(type default)
			)
			(layer "F.SilkS")
		)
		(fp_line
			(start 1.143 0.5588)
			(end 1.143 -0.5588)
			(stroke
				(width 0.1)
				(type default)
			)
			(layer "F.SilkS")
		)
		(fp_poly
			(pts
				(xy -1.143 0.5588) (xy 1.143 0.5588) (xy 1.143 -0.5588) (xy -1.143 -0.5588)
			)
			(stroke
				(width 0)
				(type default)
			)
			(fill no)
			(layer "F.CrtYd")
		)
		(fp_line
			(start -0.508 -0.3048)
			(end -0.508 0.3048)
			(stroke
				(width 0.1)
				(type default)
			)
			(layer "F.Fab")
		)
		(fp_line
			(start -0.508 0.3048)
			(end 0.508 0.3048)
			(stroke
				(width 0.1)
				(type default)
			)
			(layer "F.Fab")
		)
		(fp_line
			(start 0.508 -0.3048)
			(end -0.508 -0.3048)
			(stroke
				(width 0.1)
				(type default)
			)
			(layer "F.Fab")
		)
		(fp_line
			(start 0.508 0.3048)
			(end 0.508 -0.3048)
			(stroke
				(width 0.1)
				(type default)
			)
			(layer "F.Fab")
		)
		(pad "1" smd rect
			(at -0.5334 0)
			(size 0.7112 0.6096)
			(layers "F.Cu" "F.Mask" "F.Paste")
			(net "XP3R3V_FPGA")
		)
		(pad "2" smd rect
			(at 0.5334 0)
			(size 0.7112 0.6096)
			(layers "F.Cu" "F.Mask" "F.Paste")
			(net "SG")
		)
		(zone
			(layer "F.Cu")
			(hatch none 0.5)
			(connect_pads
				(clearance 0)
			)
			(min_thickness 0.25)
			(keepout
				(tracks allowed)
				(vias not_allowed)
				(pads allowed)
				(copperpour not_allowed)
				(footprints allowed)
			)
			(placement
				(enabled no)
				(sheetname "")
			)
			(fill
				(thermal_gap 0.5)
				(thermal_bridge_width 0.5)
				(island_removal_mode 0)
			)
			(polygon
				(pts
					(xy 114.9858 -82.7532) (xy 115.1382 -82.7532) (xy 115.1382 -83.3628) (xy 114.9858 -83.3628)
				)
			)
		)
		(zone
			(layer "F.Cu")
			(hatch none 0.5)
			(connect_pads
				(clearance 0)
			)
			(min_thickness 0.25)
			(keepout
				(tracks not_allowed)
				(vias allowed)
				(pads allowed)
				(copperpour not_allowed)
				(footprints allowed)
			)
			(placement
				(enabled no)
				(sheetname "")
			)
			(fill
				(thermal_gap 0.5)
				(thermal_bridge_width 0.5)
				(island_removal_mode 0)
			)
			(polygon
				(pts
					(xy 114.9858 -82.7532) (xy 115.1382 -82.7532) (xy 115.1382 -83.3628) (xy 114.9858 -83.3628)
				)
			)
		)
	)
	(footprint ""
		(layer "F.Cu")
		(at 4.073906 -18.10004)
		(property "Reference" "J2"
			(at 4.943094 3.40741 0)
			(unlocked yes)
			(layer "F.SilkS")
			(effects
				(font
					(size 0.7874 0.5842)
					(thickness 0.1524)
				)
			)
		)
		(property "Value" ""
			(at 0 0 0)
			(layer "F.Fab")
			(effects
				(font
					(size 1.27 1.27)
				)
			)
		)
		(property "Device Type" "CONN_JACK_1P_GH4_S_TH-G200-130A"
			(at -5.098288 5.899912 0)
			(unlocked yes)
			(layer "F.Fab")
			(hide yes)
			(effects
				(font
					(size 0.7874 0.5842)
					(thickness 0.1524)
				)
			)
		)
		(property "User Part Number" "PARTNUM*"
			(at -5.098288 7.093712 0)
			(unlocked yes)
			(layer "Cmts.User")
			(hide yes)
			(effects
				(font
					(size 0.7874 0.5842)
					(thickness 0.1524)
				)
			)
		)
		(duplicate_pad_numbers_are_jumpers no)
		(fp_line
			(start -13.953998 -3.937)
			(end 3.937 -3.937)
			(stroke
				(width 0.1)
				(type default)
			)
			(layer "F.SilkS")
		)
		(fp_line
			(start -13.953998 3.937)
			(end -13.953998 -3.937)
			(stroke
				(width 0.1)
				(type default)
			)
			(layer "F.SilkS")
		)
		(fp_line
			(start 3.937 -3.937)
			(end 3.937 3.937)
			(stroke
				(width 0.1)
				(type default)
			)
			(layer "F.SilkS")
		)
		(fp_line
			(start 3.937 3.937)
			(end -13.953998 3.937)
			(stroke
				(width 0.1)
				(type default)
			)
			(layer "F.SilkS")
		)
		(fp_rect
			(start -8.763 8.763)
			(end 8.763 -8.763)
			(stroke
				(width 0)
				(type default)
			)
			(fill no)
			(layer "B.CrtYd")
		)
		(fp_rect
			(start -14.207998 4.191)
			(end 4.191 -4.191)
			(stroke
				(width 0)
				(type default)
			)
			(fill no)
			(layer "F.CrtYd")
		)
		(fp_line
			(start -13.699998 -3.599942)
			(end 3.599942 -3.599942)
			(stroke
				(width 0.1)
				(type default)
			)
			(layer "F.Fab")
		)
		(fp_line
			(start -13.699998 3.599942)
			(end -13.699998 -3.599942)
			(stroke
				(width 0.1)
				(type default)
			)
			(layer "F.Fab")
		)
		(fp_line
			(start 3.599942 -3.599942)
			(end 3.599942 3.599942)
			(stroke
				(width 0.1)
				(type default)
			)
			(layer "F.Fab")
		)
		(fp_line
			(start 3.599942 3.599942)
			(end -13.699998 3.599942)
			(stroke
				(width 0.1)
				(type default)
			)
			(layer "F.Fab")
		)
		(fp_text user "GH3"
			(at -1.660906 4.55041 0)
			(unlocked yes)
			(layer "F.SilkS")
			(effects
				(font
					(size 0.7874 0.5842)
					(thickness 0.1524)
				)
			)
		)
		(fp_text user "GH1"
			(at -0.263906 -4.34721 0)
			(unlocked yes)
			(layer "F.SilkS")
			(effects
				(font
					(size 0.635 0.4064)
					(thickness 0.1524)
				)
			)
		)
		(fp_text user "GH2"
			(at 2.276094 -4.34721 0)
			(unlocked yes)
			(layer "F.SilkS")
			(effects
				(font
					(size 0.635 0.4064)
					(thickness 0.1524)
				)
			)
		)
		(fp_text user "GH4"
			(at 2.784094 4.67741 0)
			(unlocked yes)
			(layer "F.SilkS")
			(effects
				(font
					(size 0.7874 0.5842)
					(thickness 0.1524)
				)
			)
		)
		(fp_text user "1"
			(at 4.191 -0.35433 0)
			(unlocked yes)
			(layer "F.SilkS")
			(effects
				(font
					(size 0.7874 0.5842)
					(thickness 0.1524)
				)
				(justify left)
			)
		)
		(fp_text user "GH3"
			(at -2.803906 4.187698 0)
			(unlocked yes)
			(layer "F.Fab")
			(effects
				(font
					(size 0.7874 0.5842)
					(thickness 0.1524)
				)
			)
		)
		(fp_text user "GH1"
			(at -2.295906 -4.08559 0)
			(unlocked yes)
			(layer "F.Fab")
			(effects
				(font
					(size 0.7874 0.5842)
					(thickness 0.1524)
				)
			)
		)
		(fp_text user "GH2"
			(at 2.530094 -4.08559 0)
			(unlocked yes)
			(layer "F.Fab")
			(effects
				(font
					(size 0.7874 0.5842)
					(thickness 0.1524)
				)
			)
		)
		(fp_text user "GH4"
			(at 2.54 4.64947 0)
			(unlocked yes)
			(layer "F.Fab")
			(effects
				(font
					(size 0.7874 0.5842)
					(thickness 0.1524)
				)
			)
		)
		(fp_text user "1"
			(at 4.191 -0.35433 0)
			(unlocked yes)
			(layer "F.Fab")
			(effects
				(font
					(size 0.7874 0.5842)
					(thickness 0.1524)
				)
				(justify left)
			)
		)
		(pad "1" thru_hole circle
			(at 0 0)
			(size 2.1844 2.1844)
			(drill 1.4986)
			(layers "*.Cu" "*.Mask")
			(remove_unused_layers no)
			(net "SMA4_SIG_IO_CONN")
			(padstack
				(mode front_inner_back)
				(layer "Inner"
					(shape circle)
					(size 2.1844 2.1844)
					(clearance -0.0508)
				)
				(layer "B.Cu"
					(shape circle)
					(size 2.1844 2.1844)
				)
			)
		)
		(pad "GH1" thru_hole circle
			(at -2.54 -2.54)
			(size 2.286 2.286)
			(drill 1.6002)
			(layers "*.Cu" "*.Mask")
			(remove_unused_layers no)
			(net "SG")
			(padstack
				(mode front_inner_back)
				(layer "Inner"
					(shape circle)
					(size 2.286 2.286)
					(clearance -0.0508)
				)
				(layer "B.Cu"
					(shape circle)
					(size 2.286 2.286)
				)
			)
		)
		(pad "GH2" thru_hole circle
			(at 2.54 -2.54)
			(size 2.286 2.286)
			(drill 1.6002)
			(layers "*.Cu" "*.Mask")
			(remove_unused_layers no)
			(net "SG")
			(padstack
				(mode front_inner_back)
				(layer "Inner"
					(shape circle)
					(size 2.286 2.286)
					(clearance -0.0508)
				)
				(layer "B.Cu"
					(shape circle)
					(size 2.286 2.286)
				)
			)
		)
		(pad "GH3" thru_hole circle
			(at -2.54 2.54)
			(size 2.286 2.286)
			(drill 1.6002)
			(layers "*.Cu" "*.Mask")
			(remove_unused_layers no)
			(net "SG")
			(padstack
				(mode front_inner_back)
				(layer "Inner"
					(shape circle)
					(size 2.286 2.286)
					(clearance -0.0508)
				)
				(layer "B.Cu"
					(shape circle)
					(size 2.286 2.286)
				)
			)
		)
		(pad "GH4" thru_hole circle
			(at 2.54 2.54)
			(size 2.286 2.286)
			(drill 1.6002)
			(layers "*.Cu" "*.Mask")
			(remove_unused_layers no)
			(net "SG")
			(padstack
				(mode front_inner_back)
				(layer "Inner"
					(shape circle)
					(size 2.286 2.286)
					(clearance -0.0508)
				)
				(layer "B.Cu"
					(shape circle)
					(size 2.286 2.286)
				)
			)
		)
	)
	(footprint ""
		(layer "F.Cu")
		(at 20.193 -78.359)
		(property "Reference" "TP6"
			(at 0.29337 3.2385 90)
			(unlocked yes)
			(layer "F.SilkS")
			(effects
				(font
					(size 0.7874 0.5842)
					(thickness 0.1524)
				)
				(justify left)
			)
		)
		(property "Value" ""
			(at 0 0 0)
			(layer "F.Fab")
			(effects
				(font
					(size 1.27 1.27)
				)
			)
		)
		(property "Device Type" "TP_PIONT-TP010CT020B030_PTH-TPA"
			(at -1.341882 0.996696 0)
			(unlocked yes)
			(layer "F.Fab")
			(hide yes)
			(effects
				(font
					(size 0.7874 0.5842)
					(thickness 0.1524)
				)
				(justify left)
			)
		)
		(duplicate_pad_numbers_are_jumpers no)
		(fp_poly
			(pts
				(arc
					(start 0.889 0)
					(mid -0.889 0)
					(end 0.889 0)
				)
			)
			(stroke
				(width 0)
				(type default)
			)
			(fill no)
			(layer "B.CrtYd")
		)
		(fp_poly
			(pts
				(arc
					(start 0.889 0)
					(mid -0.889 0)
					(end 0.889 0)
				)
			)
			(stroke
				(width 0)
				(type default)
			)
			(fill no)
			(layer "F.CrtYd")
		)
		(pad "1" thru_hole circle
			(at 0 0)
			(size 0.508 0.508)
			(drill 0.254)
			(layers "*.Cu" "*.Mask")
			(remove_unused_layers no)
			(net "UNNAMED_524_FT4232HLREELQFP64_1")
			(clearance 0.1016)
			(padstack
				(mode front_inner_back)
				(layer "Inner"
					(shape circle)
					(size 0.508 0.508)
					(clearance 0.1016)
				)
				(layer "B.Cu"
					(shape circle)
					(size 0.762 0.762)
					(clearance -0.0254)
				)
			)
		)
	)
	(footprint ""
		(layer "F.Cu")
		(at 124.1806 -68.7578 -90)
		(property "Reference" "R141"
			(at 2.5908 0.18923 90)
			(unlocked yes)
			(layer "F.SilkS")
			(effects
				(font
					(size 0.7874 0.5842)
					(thickness 0.1524)
				)
			)
		)
		(property "Value" "VAL*"
			(at 0.02032 2.13233 270)
			(unlocked yes)
			(layer "F.Fab")
			(hide yes)
			(effects
				(font
					(size 0.7874 0.5842)
					(thickness 0.1524)
				)
			)
		)
		(property "Device Type" "RESISTOR-G155-100R0-J0,0OHM,-"
			(at 0.008382 1.210564 270)
			(unlocked yes)
			(layer "F.Fab")
			(hide yes)
			(effects
				(font
					(size 0.7874 0.5842)
					(thickness 0.1524)
				)
			)
		)
		(property "User Part Number" "PARTNUM*"
			(at 0.02032 4.024884 270)
			(unlocked yes)
			(layer "Cmts.User")
			(hide yes)
			(effects
				(font
					(size 0.7874 0.5842)
					(thickness 0.1524)
				)
			)
		)
		(property "Tolerance" "TOL*"
			(at 0.044704 3.05435 270)
			(unlocked yes)
			(layer "Cmts.User")
			(hide yes)
			(effects
				(font
					(size 0.7874 0.5842)
					(thickness 0.1524)
				)
			)
		)
		(duplicate_pad_numbers_are_jumpers no)
		(fp_line
			(start -1.143 0.5588)
			(end 1.143 0.5588)
			(stroke
				(width 0.1)
				(type default)
			)
			(layer "F.SilkS")
		)
		(fp_line
			(start 1.143 0.5588)
			(end 1.143 -0.5588)
			(stroke
				(width 0.1)
				(type default)
			)
			(layer "F.SilkS")
		)
		(fp_line
			(start -1.143 -0.5588)
			(end -1.143 0.5588)
			(stroke
				(width 0.1)
				(type default)
			)
			(layer "F.SilkS")
		)
		(fp_line
			(start 1.143 -0.5588)
			(end -1.143 -0.5588)
			(stroke
				(width 0.1)
				(type default)
			)
			(layer "F.SilkS")
		)
		(fp_rect
			(start 1.143 0.5588)
			(end -1.143 -0.5588)
			(stroke
				(width 0)
				(type default)
			)
			(fill no)
			(layer "F.CrtYd")
		)
		(fp_line
			(start -0.508 0.3048)
			(end 0.508 0.3048)
			(stroke
				(width 0.1)
				(type default)
			)
			(layer "F.Fab")
		)
		(fp_line
			(start 0.508 0.3048)
			(end 0.508 -0.3048)
			(stroke
				(width 0.1)
				(type default)
			)
			(layer "F.Fab")
		)
		(fp_line
			(start -0.508 -0.3048)
			(end -0.508 0.3048)
			(stroke
				(width 0.1)
				(type default)
			)
			(layer "F.Fab")
		)
		(fp_line
			(start 0.508 -0.3048)
			(end -0.508 -0.3048)
			(stroke
				(width 0.1)
				(type default)
			)
			(layer "F.Fab")
		)
		(pad "1" smd rect
			(at -0.5334 0 270)
			(size 0.7112 0.6096)
			(layers "F.Cu" "F.Mask" "F.Paste")
			(net "XP1R2V_FPGA_PG")
		)
		(pad "2" smd rect
			(at 0.5334 0 270)
			(size 0.7112 0.6096)
			(layers "F.Cu" "F.Mask" "F.Paste")
			(net "XP1R8V_EN_R")
		)
		(zone
			(layer "F.Cu")
			(hatch none 0.5)
			(connect_pads
				(clearance 0)
			)
			(min_thickness 0.25)
			(keepout
				(tracks allowed)
				(vias not_allowed)
				(pads allowed)
				(copperpour not_allowed)
				(footprints allowed)
			)
			(placement
				(enabled no)
				(sheetname "")
			)
			(fill
				(thermal_gap 0.5)
				(thermal_bridge_width 0.5)
				(island_removal_mode 0)
			)
			(polygon
				(pts
					(xy 123.8758 -68.6816) (xy 124.4854 -68.6816) (xy 124.4854 -68.834) (xy 123.8758 -68.834)
				)
			)
		)
	)
	(footprint ""
		(layer "F.Cu")
		(at 124.587 -41.402 180)
		(property "Reference" "R93"
			(at -2.667 1.48463 0)
			(unlocked yes)
			(layer "F.SilkS")
			(effects
				(font
					(size 0.7874 0.5842)
					(thickness 0.1524)
				)
			)
		)
		(property "Value" "VAL*"
			(at 0.02032 2.13233 180)
			(unlocked yes)
			(layer "F.Fab")
			(hide yes)
			(effects
				(font
					(size 0.7874 0.5842)
					(thickness 0.1524)
				)
			)
		)
		(property "Tolerance" "TOL*"
			(at 0.044704 3.05435 180)
			(unlocked yes)
			(layer "Cmts.User")
			(hide yes)
			(effects
				(font
					(size 0.7874 0.5842)
					(thickness 0.1524)
				)
			)
		)
		(property "User Part Number" "PARTNUM*"
			(at 0.02032 4.024884 180)
			(unlocked yes)
			(layer "Cmts.User")
			(hide yes)
			(effects
				(font
					(size 0.7874 0.5842)
					(thickness 0.1524)
				)
			)
		)
		(property "Device Type" "RESISTOR-G155-133R0-01,33OHM,1%"
			(at 0.008382 1.210564 180)
			(unlocked yes)
			(layer "F.Fab")
			(hide yes)
			(effects
				(font
					(size 0.7874 0.5842)
					(thickness 0.1524)
				)
			)
		)
		(duplicate_pad_numbers_are_jumpers no)
		(fp_line
			(start 1.143 0.5588)
			(end 1.143 -0.5588)
			(stroke
				(width 0.1)
				(type default)
			)
			(layer "F.SilkS")
		)
		(fp_line
			(start 1.143 -0.5588)
			(end -1.143 -0.5588)
			(stroke
				(width 0.1)
				(type default)
			)
			(layer "F.SilkS")
		)
		(fp_line
			(start -1.143 0.5588)
			(end 1.143 0.5588)
			(stroke
				(width 0.1)
				(type default)
			)
			(layer "F.SilkS")
		)
		(fp_line
			(start -1.143 -0.5588)
			(end -1.143 0.5588)
			(stroke
				(width 0.1)
				(type default)
			)
			(layer "F.SilkS")
		)
		(fp_rect
			(start 1.143 -0.5588)
			(end -1.143 0.5588)
			(stroke
				(width 0)
				(type default)
			)
			(fill no)
			(layer "F.CrtYd")
		)
		(fp_line
			(start 0.508 0.3048)
			(end 0.508 -0.3048)
			(stroke
				(width 0.1)
				(type default)
			)
			(layer "F.Fab")
		)
		(fp_line
			(start 0.508 -0.3048)
			(end -0.508 -0.3048)
			(stroke
				(width 0.1)
				(type default)
			)
			(layer "F.Fab")
		)
		(fp_line
			(start -0.508 0.3048)
			(end 0.508 0.3048)
			(stroke
				(width 0.1)
				(type default)
			)
			(layer "F.Fab")
		)
		(fp_line
			(start -0.508 -0.3048)
			(end -0.508 0.3048)
			(stroke
				(width 0.1)
				(type default)
			)
			(layer "F.Fab")
		)
		(pad "1" smd rect
			(at -0.5334 0 180)
			(size 0.7112 0.6096)
			(layers "F.Cu" "F.Mask" "F.Paste")
			(net "R_MAC_BITEOUT")
		)
		(pad "2" smd rect
			(at 0.5334 0 180)
			(size 0.7112 0.6096)
			(layers "F.Cu" "F.Mask" "F.Paste")
			(net "FPGA_IN_MAC_BITEOUT")
		)
		(zone
			(layer "F.Cu")
			(hatch none 0.5)
			(connect_pads
				(clearance 0)
			)
			(min_thickness 0.25)
			(keepout
				(tracks allowed)
				(vias not_allowed)
				(pads allowed)
				(copperpour not_allowed)
				(footprints allowed)
			)
			(placement
				(enabled no)
				(sheetname "")
			)
			(fill
				(thermal_gap 0.5)
				(thermal_bridge_width 0.5)
				(island_removal_mode 0)
			)
			(polygon
				(pts
					(xy 124.5108 -41.0972) (xy 124.6632 -41.0972) (xy 124.6632 -41.7068) (xy 124.5108 -41.7068)
				)
			)
		)
	)
	(footprint ""
		(layer "F.Cu")
		(at 138.43 -16.129 180)
		(property "Reference" "C234"
			(at 2.032 -1.56337 0)
			(unlocked yes)
			(layer "F.SilkS")
			(effects
				(font
					(size 0.7874 0.5842)
					(thickness 0.1524)
				)
			)
		)
		(property "Value" "VAL*"
			(at 0.193548 2.13614 180)
			(unlocked yes)
			(layer "F.Fab")
			(hide yes)
			(effects
				(font
					(size 0.7874 0.5842)
					(thickness 0.1524)
				)
			)
		)
		(property "User Part Number" "PARTNUM*"
			(at 0.216154 4.185666 180)
			(unlocked yes)
			(layer "Cmts.User")
			(hide yes)
			(effects
				(font
					(size 0.7874 0.5842)
					(thickness 0.1524)
				)
			)
		)
		(property "Device Type" "CAPACITOR-G104-0B103-EK,0.01UFA"
			(at 0.184404 1.180592 180)
			(unlocked yes)
			(layer "F.Fab")
			(hide yes)
			(effects
				(font
					(size 0.7874 0.5842)
					(thickness 0.1524)
				)
			)
		)
		(property "Tolerance" "TOL*"
			(at 0.216154 3.1496 180)
			(unlocked yes)
			(layer "Cmts.User")
			(hide yes)
			(effects
				(font
					(size 0.7874 0.5842)
					(thickness 0.1524)
				)
			)
		)
		(duplicate_pad_numbers_are_jumpers no)
		(fp_line
			(start 0.671322 0.4445)
			(end -0.671322 0.4445)
			(stroke
				(width 0.1)
				(type default)
			)
			(layer "F.SilkS")
		)
		(fp_line
			(start 0.671322 -0.4445)
			(end 0.671322 0.4445)
			(stroke
				(width 0.1)
				(type default)
			)
			(layer "F.SilkS")
		)
		(fp_line
			(start -0.671322 0.4445)
			(end -0.671322 -0.4445)
			(stroke
				(width 0.1)
				(type default)
			)
			(layer "F.SilkS")
		)
		(fp_line
			(start -0.671322 -0.4445)
			(end 0.671322 -0.4445)
			(stroke
				(width 0.1)
				(type default)
			)
			(layer "F.SilkS")
		)
		(fp_rect
			(start -0.671322 -0.4445)
			(end 0.671322 0.4445)
			(stroke
				(width 0)
				(type default)
			)
			(fill no)
			(layer "F.CrtYd")
		)
		(fp_line
			(start 0.31496 0.1651)
			(end 0.31496 -0.1651)
			(stroke
				(width 0.1)
				(type default)
			)
			(layer "F.Fab")
		)
		(fp_line
			(start 0.31496 -0.1651)
			(end -0.31496 -0.1651)
			(stroke
				(width 0.1)
				(type default)
			)
			(layer "F.Fab")
		)
		(fp_line
			(start -0.31496 0.1651)
			(end 0.31496 0.1651)
			(stroke
				(width 0.1)
				(type default)
			)
			(layer "F.Fab")
		)
		(fp_line
			(start -0.31496 -0.1651)
			(end -0.31496 0.1651)
			(stroke
				(width 0.1)
				(type default)
			)
			(layer "F.Fab")
		)
		(pad "1" smd rect
			(at -0.264922 0 180)
			(size 0.3048 0.381)
			(layers "F.Cu" "F.Mask" "F.Paste")
			(net "UNNAMED_515_CAPACITOR_I138_1")
		)
		(pad "2" smd rect
			(at 0.264922 0 180)
			(size 0.3048 0.381)
			(layers "F.Cu" "F.Mask" "F.Paste")
			(net "SG")
		)
		(zone
			(layer "F.Cu")
			(hatch none 0.5)
			(connect_pads
				(clearance 0)
			)
			(min_thickness 0.25)
			(keepout
				(tracks allowed)
				(vias not_allowed)
				(pads allowed)
				(copperpour not_allowed)
				(footprints allowed)
			)
			(placement
				(enabled no)
				(sheetname "")
			)
			(fill
				(thermal_gap 0.5)
				(thermal_bridge_width 0.5)
				(island_removal_mode 0)
			)
			(polygon
				(pts
					(xy 138.542522 -15.9385) (xy 138.542522 -16.3195) (xy 138.317478 -16.3195) (xy 138.317478 -15.9385)
				)
			)
		)
	)
	(footprint ""
		(layer "F.Cu")
		(at 99.06 -59.055 90)
		(property "Reference" "TP78"
			(at -2.9464 -0.47625 90)
			(unlocked yes)
			(layer "F.SilkS")
			(effects
				(font
					(size 0.635 0.4064)
					(thickness 0.1524)
				)
				(justify left)
			)
		)
		(property "Value" ""
			(at 0 0 90)
			(layer "F.Fab")
			(effects
				(font
					(size 1.27 1.27)
				)
			)
		)
		(property "Device Type" "TP_PIONT-TP010CT020B030_PTH-TPA"
			(at -1.341882 0.996696 90)
			(unlocked yes)
			(layer "F.Fab")
			(hide yes)
			(effects
				(font
					(size 0.7874 0.5842)
					(thickness 0.1524)
				)
				(justify left)
			)
		)
		(duplicate_pad_numbers_are_jumpers no)
		(fp_poly
			(pts
				(arc
					(start 0 0.889)
					(mid 0 -0.889)
					(end 0 0.889)
				)
			)
			(stroke
				(width 0)
				(type default)
			)
			(fill no)
			(layer "B.CrtYd")
		)
		(fp_poly
			(pts
				(arc
					(start 0 0.889)
					(mid 0 -0.889)
					(end 0 0.889)
				)
			)
			(stroke
				(width 0)
				(type default)
			)
			(fill no)
			(layer "F.CrtYd")
		)
		(pad "1" thru_hole circle
			(at 0 0 90)
			(size 0.508 0.508)
			(drill 0.254)
			(layers "*.Cu" "*.Mask")
			(remove_unused_layers no)
			(net "IO_L20P_16")
			(clearance 0.1016)
			(padstack
				(mode front_inner_back)
				(layer "Inner"
					(shape circle)
					(size 0.508 0.508)
					(clearance 0.1016)
				)
				(layer "B.Cu"
					(shape circle)
					(size 0.762 0.762)
					(clearance -0.0254)
				)
			)
		)
	)
	(footprint ""
		(layer "F.Cu")
		(at 39.37 -128.905)
		(property "Reference" "SP35"
			(at 0 0 0)
			(layer "F.SilkS")
			(hide yes)
			(effects
				(font
					(size 1.27 1.27)
				)
			)
		)
		(property "Value" ""
			(at 0 0 0)
			(layer "F.Fab")
			(effects
				(font
					(size 1.27 1.27)
				)
			)
		)
		(duplicate_pad_numbers_are_jumpers no)
	)
	(footprint ""
		(layer "F.Cu")
		(at 105.41 -64.2874 -90)
		(property "Reference" "R327"
			(at 0.0254 -2.70637 90)
			(unlocked yes)
			(layer "F.SilkS")
			(effects
				(font
					(size 0.7874 0.5842)
					(thickness 0.1524)
				)
			)
		)
		(property "Value" "VAL*"
			(at 0.02032 2.13233 270)
			(unlocked yes)
			(layer "F.Fab")
			(hide yes)
			(effects
				(font
					(size 0.7874 0.5842)
					(thickness 0.1524)
				)
			)
		)
		(property "Tolerance" "TOL*"
			(at 0.044704 3.05435 270)
			(unlocked yes)
			(layer "Cmts.User")
			(hide yes)
			(effects
				(font
					(size 0.7874 0.5842)
					(thickness 0.1524)
				)
			)
		)
		(property "User Part Number" "PARTNUM*"
			(at 0.02032 4.024884 270)
			(unlocked yes)
			(layer "Cmts.User")
			(hide yes)
			(effects
				(font
					(size 0.7874 0.5842)
					(thickness 0.1524)
				)
			)
		)
		(property "Device Type" "RESISTOR-G155-11002-01,10KOHM,A"
			(at 0.008382 1.210564 270)
			(unlocked yes)
			(layer "F.Fab")
			(hide yes)
			(effects
				(font
					(size 0.7874 0.5842)
					(thickness 0.1524)
				)
			)
		)
		(duplicate_pad_numbers_are_jumpers no)
		(fp_line
			(start -1.143 0.5588)
			(end 1.143 0.5588)
			(stroke
				(width 0.1)
				(type default)
			)
			(layer "F.SilkS")
		)
		(fp_line
			(start 1.143 0.5588)
			(end 1.143 -0.5588)
			(stroke
				(width 0.1)
				(type default)
			)
			(layer "F.SilkS")
		)
		(fp_line
			(start -1.143 -0.5588)
			(end -1.143 0.5588)
			(stroke
				(width 0.1)
				(type default)
			)
			(layer "F.SilkS")
		)
		(fp_line
			(start 1.143 -0.5588)
			(end -1.143 -0.5588)
			(stroke
				(width 0.1)
				(type default)
			)
			(layer "F.SilkS")
		)
		(fp_poly
			(pts
				(xy -1.143 0.5588) (xy 1.143 0.5588) (xy 1.143 -0.5588) (xy -1.143 -0.5588)
			)
			(stroke
				(width 0)
				(type default)
			)
			(fill no)
			(layer "F.CrtYd")
		)
		(fp_line
			(start -0.508 0.3048)
			(end 0.508 0.3048)
			(stroke
				(width 0.1)
				(type default)
			)
			(layer "F.Fab")
		)
		(fp_line
			(start 0.508 0.3048)
			(end 0.508 -0.3048)
			(stroke
				(width 0.1)
				(type default)
			)
			(layer "F.Fab")
		)
		(fp_line
			(start -0.508 -0.3048)
			(end -0.508 0.3048)
			(stroke
				(width 0.1)
				(type default)
			)
			(layer "F.Fab")
		)
		(fp_line
			(start 0.508 -0.3048)
			(end -0.508 -0.3048)
			(stroke
				(width 0.1)
				(type default)
			)
			(layer "F.Fab")
		)
		(pad "1" smd rect
			(at -0.5334 0 270)
			(size 0.7112 0.6096)
			(layers "F.Cu" "F.Mask" "F.Paste")
			(net "XP3R3V_FPGA")
		)
		(pad "2" smd rect
			(at 0.5334 0 270)
			(size 0.7112 0.6096)
			(layers "F.Cu" "F.Mask" "F.Paste")
			(net "FPGA_IO_7")
		)
		(zone
			(layer "F.Cu")
			(hatch none 0.5)
			(connect_pads
				(clearance 0)
			)
			(min_thickness 0.25)
			(keepout
				(tracks not_allowed)
				(vias allowed)
				(pads allowed)
				(copperpour not_allowed)
				(footprints allowed)
			)
			(placement
				(enabled no)
				(sheetname "")
			)
			(fill
				(thermal_gap 0.5)
				(thermal_bridge_width 0.5)
				(island_removal_mode 0)
			)
			(polygon
				(pts
					(xy 105.1052 -64.3636) (xy 105.1052 -64.2112) (xy 105.7148 -64.2112) (xy 105.7148 -64.3636)
				)
			)
		)
		(zone
			(layer "F.Cu")
			(hatch none 0.5)
			(connect_pads
				(clearance 0)
			)
			(min_thickness 0.25)
			(keepout
				(tracks allowed)
				(vias not_allowed)
				(pads allowed)
				(copperpour not_allowed)
				(footprints allowed)
			)
			(placement
				(enabled no)
				(sheetname "")
			)
			(fill
				(thermal_gap 0.5)
				(thermal_bridge_width 0.5)
				(island_removal_mode 0)
			)
			(polygon
				(pts
					(xy 105.1052 -64.3636) (xy 105.1052 -64.2112) (xy 105.7148 -64.2112) (xy 105.7148 -64.3636)
				)
			)
		)
	)
	(footprint ""
		(layer "F.Cu")
		(at 12.8524 -55.0164 180)
		(property "Reference" "C318"
			(at 2.1844 -0.19177 0)
			(unlocked yes)
			(layer "F.SilkS")
			(effects
				(font
					(size 0.7874 0.5842)
					(thickness 0.1524)
				)
			)
		)
		(property "Value" "VAL*"
			(at 0.193548 2.13614 180)
			(unlocked yes)
			(layer "F.Fab")
			(hide yes)
			(effects
				(font
					(size 0.7874 0.5842)
					(thickness 0.1524)
				)
			)
		)
		(property "User Part Number" "PARTNUM*"
			(at 0.216154 4.185666 180)
			(unlocked yes)
			(layer "Cmts.User")
			(hide yes)
			(effects
				(font
					(size 0.7874 0.5842)
					(thickness 0.1524)
				)
			)
		)
		(property "Device Type" "CAPACITOR-G104-0A180-FJ,18PF,5%"
			(at 0.184404 1.180592 180)
			(unlocked yes)
			(layer "F.Fab")
			(hide yes)
			(effects
				(font
					(size 0.7874 0.5842)
					(thickness 0.1524)
				)
			)
		)
		(property "Tolerance" "TOL*"
			(at 0.216154 3.1496 180)
			(unlocked yes)
			(layer "Cmts.User")
			(hide yes)
			(effects
				(font
					(size 0.7874 0.5842)
					(thickness 0.1524)
				)
			)
		)
		(duplicate_pad_numbers_are_jumpers no)
		(fp_line
			(start 0.671322 0.4445)
			(end -0.671322 0.4445)
			(stroke
				(width 0.1)
				(type default)
			)
			(layer "F.SilkS")
		)
		(fp_line
			(start 0.671322 -0.4445)
			(end 0.671322 0.4445)
			(stroke
				(width 0.1)
				(type default)
			)
			(layer "F.SilkS")
		)
		(fp_line
			(start -0.671322 0.4445)
			(end -0.671322 -0.4445)
			(stroke
				(width 0.1)
				(type default)
			)
			(layer "F.SilkS")
		)
		(fp_line
			(start -0.671322 -0.4445)
			(end 0.671322 -0.4445)
			(stroke
				(width 0.1)
				(type default)
			)
			(layer "F.SilkS")
		)
		(fp_rect
			(start -0.671322 0.4445)
			(end 0.671322 -0.4445)
			(stroke
				(width 0)
				(type default)
			)
			(fill no)
			(layer "F.CrtYd")
		)
		(fp_line
			(start 0.31496 0.1651)
			(end 0.31496 -0.1651)
			(stroke
				(width 0.1)
				(type default)
			)
			(layer "F.Fab")
		)
		(fp_line
			(start 0.31496 -0.1651)
			(end -0.31496 -0.1651)
			(stroke
				(width 0.1)
				(type default)
			)
			(layer "F.Fab")
		)
		(fp_line
			(start -0.31496 0.1651)
			(end 0.31496 0.1651)
			(stroke
				(width 0.1)
				(type default)
			)
			(layer "F.Fab")
		)
		(fp_line
			(start -0.31496 -0.1651)
			(end -0.31496 0.1651)
			(stroke
				(width 0.1)
				(type default)
			)
			(layer "F.Fab")
		)
		(pad "1" smd rect
			(at -0.264922 0 180)
			(size 0.3048 0.381)
			(layers "F.Cu" "F.Mask" "F.Paste")
			(net "SG")
		)
		(pad "2" smd rect
			(at 0.264922 0 180)
			(size 0.3048 0.381)
			(layers "F.Cu" "F.Mask" "F.Paste")
			(net "UNNAMED_12_CAPACITOR_I332_2")
		)
		(zone
			(layer "F.Cu")
			(hatch none 0.5)
			(connect_pads
				(clearance 0)
			)
			(min_thickness 0.25)
			(keepout
				(tracks not_allowed)
				(vias allowed)
				(pads allowed)
				(copperpour not_allowed)
				(footprints allowed)
			)
			(placement
				(enabled no)
				(sheetname "")
			)
			(fill
				(thermal_gap 0.5)
				(thermal_bridge_width 0.5)
				(island_removal_mode 0)
			)
			(polygon
				(pts
					(xy 12.964922 -55.2069) (xy 12.739878 -55.2069) (xy 12.739878 -54.8259) (xy 12.964922 -54.8259)
				)
			)
		)
		(zone
			(layer "F.Cu")
			(hatch none 0.5)
			(connect_pads
				(clearance 0)
			)
			(min_thickness 0.25)
			(keepout
				(tracks allowed)
				(vias not_allowed)
				(pads allowed)
				(copperpour not_allowed)
				(footprints allowed)
			)
			(placement
				(enabled no)
				(sheetname "")
			)
			(fill
				(thermal_gap 0.5)
				(thermal_bridge_width 0.5)
				(island_removal_mode 0)
			)
			(polygon
				(pts
					(xy 12.964922 -54.8259) (xy 12.964922 -55.2069) (xy 12.739878 -55.2069) (xy 12.739878 -54.8259)
				)
			)
		)
	)
	(footprint ""
		(layer "F.Cu")
		(at 94.7928 -75.819 -90)
		(property "Reference" "C185"
			(at -19.304 27.57043 90)
			(unlocked yes)
			(layer "F.SilkS")
			(effects
				(font
					(size 0.7874 0.5842)
					(thickness 0.1524)
				)
			)
		)
		(property "Value" "VAL*"
			(at 0.0762 3.134106 270)
			(unlocked yes)
			(layer "F.Fab")
			(hide yes)
			(effects
				(font
					(size 0.7874 0.5842)
					(thickness 0.1524)
				)
			)
		)
		(property "Device Type" "CAPACITOR-G107-0F106-EM,10UF,2A"
			(at 0.0508 2.194306 270)
			(unlocked yes)
			(layer "F.Fab")
			(hide yes)
			(effects
				(font
					(size 0.7874 0.5842)
					(thickness 0.1524)
				)
			)
		)
		(property "User Part Number" "PARTNUM*"
			(at 0.1016 5.013706 270)
			(unlocked yes)
			(layer "Cmts.User")
			(hide yes)
			(effects
				(font
					(size 0.7874 0.5842)
					(thickness 0.1524)
				)
			)
		)
		(property "Tolerance" "TOL*"
			(at 0.0762 4.048506 270)
			(unlocked yes)
			(layer "Cmts.User")
			(hide yes)
			(effects
				(font
					(size 0.7874 0.5842)
					(thickness 0.1524)
				)
			)
		)
		(duplicate_pad_numbers_are_jumpers no)
		(fp_line
			(start -1.5748 0.9398)
			(end 1.5748 0.9398)
			(stroke
				(width 0.1)
				(type default)
			)
			(layer "F.SilkS")
		)
		(fp_line
			(start 1.5748 0.9398)
			(end 1.5748 -0.9398)
			(stroke
				(width 0.1)
				(type default)
			)
			(layer "F.SilkS")
		)
		(fp_line
			(start -1.5748 -0.9398)
			(end -1.5748 0.9398)
			(stroke
				(width 0.1)
				(type default)
			)
			(layer "F.SilkS")
		)
		(fp_line
			(start 1.5748 -0.9398)
			(end -1.5748 -0.9398)
			(stroke
				(width 0.1)
				(type default)
			)
			(layer "F.SilkS")
		)
		(fp_rect
			(start -1.5748 0.9398)
			(end 1.5748 -0.9398)
			(stroke
				(width 0)
				(type default)
			)
			(fill no)
			(layer "F.CrtYd")
		)
		(fp_line
			(start -1.016 0.635)
			(end 1.016 0.635)
			(stroke
				(width 0.1)
				(type default)
			)
			(layer "F.Fab")
		)
		(fp_line
			(start 1.016 0.635)
			(end 1.016 -0.635)
			(stroke
				(width 0.1)
				(type default)
			)
			(layer "F.Fab")
		)
		(fp_line
			(start -1.016 -0.635)
			(end -1.016 0.635)
			(stroke
				(width 0.1)
				(type default)
			)
			(layer "F.Fab")
		)
		(fp_line
			(start 1.016 -0.635)
			(end -1.016 -0.635)
			(stroke
				(width 0.1)
				(type default)
			)
			(layer "F.Fab")
		)
		(pad "1" smd rect
			(at -0.8382 0 270)
			(size 0.9652 1.3716)
			(layers "F.Cu" "F.Mask" "F.Paste")
			(net "XP1R2V_VIN")
		)
		(pad "2" smd rect
			(at 0.8382 0 270)
			(size 0.9652 1.3716)
			(layers "F.Cu" "F.Mask" "F.Paste")
			(net "SG")
		)
		(zone
			(layer "F.Cu")
			(hatch none 0.5)
			(connect_pads
				(clearance 0)
			)
			(min_thickness 0.25)
			(keepout
				(tracks allowed)
				(vias not_allowed)
				(pads allowed)
				(copperpour not_allowed)
				(footprints allowed)
			)
			(placement
				(enabled no)
				(sheetname "")
			)
			(fill
				(thermal_gap 0.5)
				(thermal_bridge_width 0.5)
				(island_removal_mode 0)
			)
			(polygon
				(pts
					(xy 94.1578 -76.0476) (xy 94.1578 -75.5904) (xy 95.4278 -75.5904) (xy 95.4278 -76.0476)
				)
			)
		)
	)
	(footprint ""
		(layer "F.Cu")
		(at 151.613108 -49.01311 90)
		(property "Reference" "R68"
			(at 0.00127 -2.882138 90)
			(unlocked yes)
			(layer "F.SilkS")
			(effects
				(font
					(size 0.7874 0.5842)
					(thickness 0.1524)
				)
			)
		)
		(property "Value" "VAL*"
			(at 0.02032 2.13233 90)
			(unlocked yes)
			(layer "F.Fab")
			(hide yes)
			(effects
				(font
					(size 0.7874 0.5842)
					(thickness 0.1524)
				)
			)
		)
		(property "Device Type" "RESISTOR-G155-14701-01,4.7KOHMA"
			(at 0.008382 1.210564 90)
			(unlocked yes)
			(layer "F.Fab")
			(hide yes)
			(effects
				(font
					(size 0.7874 0.5842)
					(thickness 0.1524)
				)
			)
		)
		(property "User Part Number" "PARTNUM*"
			(at 0.02032 4.024884 90)
			(unlocked yes)
			(layer "Cmts.User")
			(hide yes)
			(effects
				(font
					(size 0.7874 0.5842)
					(thickness 0.1524)
				)
			)
		)
		(property "Tolerance" "TOL*"
			(at 0.044704 3.05435 90)
			(unlocked yes)
			(layer "Cmts.User")
			(hide yes)
			(effects
				(font
					(size 0.7874 0.5842)
					(thickness 0.1524)
				)
			)
		)
		(duplicate_pad_numbers_are_jumpers no)
		(fp_line
			(start 1.143 -0.5588)
			(end -1.143 -0.5588)
			(stroke
				(width 0.1)
				(type default)
			)
			(layer "F.SilkS")
		)
		(fp_line
			(start -1.143 -0.5588)
			(end -1.143 0.5588)
			(stroke
				(width 0.1)
				(type default)
			)
			(layer "F.SilkS")
		)
		(fp_line
			(start 1.143 0.5588)
			(end 1.143 -0.5588)
			(stroke
				(width 0.1)
				(type default)
			)
			(layer "F.SilkS")
		)
		(fp_line
			(start -1.143 0.5588)
			(end 1.143 0.5588)
			(stroke
				(width 0.1)
				(type default)
			)
			(layer "F.SilkS")
		)
		(fp_rect
			(start 1.143 0.5588)
			(end -1.143 -0.5588)
			(stroke
				(width 0)
				(type default)
			)
			(fill no)
			(layer "F.CrtYd")
		)
		(fp_line
			(start 0.508 -0.3048)
			(end -0.508 -0.3048)
			(stroke
				(width 0.1)
				(type default)
			)
			(layer "F.Fab")
		)
		(fp_line
			(start -0.508 -0.3048)
			(end -0.508 0.3048)
			(stroke
				(width 0.1)
				(type default)
			)
			(layer "F.Fab")
		)
		(fp_line
			(start 0.508 0.3048)
			(end 0.508 -0.3048)
			(stroke
				(width 0.1)
				(type default)
			)
			(layer "F.Fab")
		)
		(fp_line
			(start -0.508 0.3048)
			(end 0.508 0.3048)
			(stroke
				(width 0.1)
				(type default)
			)
			(layer "F.Fab")
		)
		(pad "1" smd rect
			(at -0.5334 0 90)
			(size 0.7112 0.6096)
			(layers "F.Cu" "F.Mask" "F.Paste")
			(net "XP3R3V_FPGA")
		)
		(pad "2" smd rect
			(at 0.5334 0 90)
			(size 0.7112 0.6096)
			(layers "F.Cu" "F.Mask" "F.Paste")
			(net "SHT3X_ADDR")
		)
		(zone
			(layer "F.Cu")
			(hatch none 0.5)
			(connect_pads
				(clearance 0)
			)
			(min_thickness 0.25)
			(keepout
				(tracks allowed)
				(vias not_allowed)
				(pads allowed)
				(copperpour not_allowed)
				(footprints allowed)
			)
			(placement
				(enabled no)
				(sheetname "")
			)
			(fill
				(thermal_gap 0.5)
				(thermal_bridge_width 0.5)
				(island_removal_mode 0)
			)
			(polygon
				(pts
					(xy 151.917908 -49.08931) (xy 151.308308 -49.08931) (xy 151.308308 -48.93691) (xy 151.917908 -48.93691)
				)
			)
		)
	)
	(footprint ""
		(layer "F.Cu")
		(at 140.1318 -21.9202)
		(property "Reference" "C239"
			(at -3.2258 -1.02743 0)
			(unlocked yes)
			(layer "F.SilkS")
			(effects
				(font
					(size 0.7874 0.5842)
					(thickness 0.1524)
				)
			)
		)
		(property "Value" "VAL*"
			(at 0.0762 3.134106 0)
			(unlocked yes)
			(layer "F.Fab")
			(hide yes)
			(effects
				(font
					(size 0.7874 0.5842)
					(thickness 0.1524)
				)
			)
		)
		(property "Tolerance" "TOL*"
			(at 0.0762 4.048506 0)
			(unlocked yes)
			(layer "Cmts.User")
			(hide yes)
			(effects
				(font
					(size 0.7874 0.5842)
					(thickness 0.1524)
				)
			)
		)
		(property "User Part Number" "PARTNUM*"
			(at 0.1016 5.013706 0)
			(unlocked yes)
			(layer "Cmts.User")
			(hide yes)
			(effects
				(font
					(size 0.7874 0.5842)
					(thickness 0.1524)
				)
			)
		)
		(property "Device Type" "CAPACITOR-G107-0F106-EM,10UF,2A"
			(at 0.0508 2.194306 0)
			(unlocked yes)
			(layer "F.Fab")
			(hide yes)
			(effects
				(font
					(size 0.7874 0.5842)
					(thickness 0.1524)
				)
			)
		)
		(duplicate_pad_numbers_are_jumpers no)
		(fp_line
			(start -1.5748 -0.9398)
			(end -1.5748 0.9398)
			(stroke
				(width 0.1)
				(type default)
			)
			(layer "F.SilkS")
		)
		(fp_line
			(start -1.5748 0.9398)
			(end 1.5748 0.9398)
			(stroke
				(width 0.1)
				(type default)
			)
			(layer "F.SilkS")
		)
		(fp_line
			(start 1.5748 -0.9398)
			(end -1.5748 -0.9398)
			(stroke
				(width 0.1)
				(type default)
			)
			(layer "F.SilkS")
		)
		(fp_line
			(start 1.5748 0.9398)
			(end 1.5748 -0.9398)
			(stroke
				(width 0.1)
				(type default)
			)
			(layer "F.SilkS")
		)
		(fp_rect
			(start 1.5748 -0.9398)
			(end -1.5748 0.9398)
			(stroke
				(width 0)
				(type default)
			)
			(fill no)
			(layer "F.CrtYd")
		)
		(fp_line
			(start -1.016 -0.635)
			(end -1.016 0.635)
			(stroke
				(width 0.1)
				(type default)
			)
			(layer "F.Fab")
		)
		(fp_line
			(start -1.016 0.635)
			(end 1.016 0.635)
			(stroke
				(width 0.1)
				(type default)
			)
			(layer "F.Fab")
		)
		(fp_line
			(start 1.016 -0.635)
			(end -1.016 -0.635)
			(stroke
				(width 0.1)
				(type default)
			)
			(layer "F.Fab")
		)
		(fp_line
			(start 1.016 0.635)
			(end 1.016 -0.635)
			(stroke
				(width 0.1)
				(type default)
			)
			(layer "F.Fab")
		)
		(pad "1" smd rect
			(at -0.8382 0)
			(size 0.9652 1.3716)
			(layers "F.Cu" "F.Mask" "F.Paste")
			(net "XP2R5V_FPGA")
		)
		(pad "2" smd rect
			(at 0.8382 0)
			(size 0.9652 1.3716)
			(layers "F.Cu" "F.Mask" "F.Paste")
			(net "SG")
		)
		(zone
			(layer "F.Cu")
			(hatch none 0.5)
			(connect_pads
				(clearance 0)
			)
			(min_thickness 0.25)
			(keepout
				(tracks allowed)
				(vias not_allowed)
				(pads allowed)
				(copperpour not_allowed)
				(footprints allowed)
			)
			(placement
				(enabled no)
				(sheetname "")
			)
			(fill
				(thermal_gap 0.5)
				(thermal_bridge_width 0.5)
				(island_removal_mode 0)
			)
			(polygon
				(pts
					(xy 140.3604 -22.5552) (xy 139.9032 -22.5552) (xy 139.9032 -21.2852) (xy 140.3604 -21.2852)
				)
			)
		)
	)
	(footprint ""
		(layer "F.Cu")
		(at 123.215908 -96.270064 90)
		(property "Reference" "P2"
			(at -0.932434 -4.089908 0)
			(unlocked yes)
			(layer "F.SilkS")
			(effects
				(font
					(size 0.7874 0.5842)
					(thickness 0.1524)
				)
			)
		)
		(property "Value" ""
			(at 0 0 90)
			(layer "F.Fab")
			(effects
				(font
					(size 1.27 1.27)
				)
			)
		)
		(property "User Part Number" "PARTNUM*"
			(at 0 5.311902 90)
			(unlocked yes)
			(layer "Cmts.User")
			(hide yes)
			(effects
				(font
					(size 0.7874 0.5842)
					(thickness 0.1524)
				)
			)
		)
		(property "Device Type" "CONN_HDR_2X4_F_S_SMT-G200-1307A"
			(at 0 4.118102 90)
			(unlocked yes)
			(layer "F.Fab")
			(hide yes)
			(effects
				(font
					(size 0.7874 0.5842)
					(thickness 0.1524)
				)
			)
		)
		(duplicate_pad_numbers_are_jumpers no)
		(fp_line
			(start 4.52755 -3.008884)
			(end 4.52755 3.009138)
			(stroke
				(width 0.1)
				(type default)
			)
			(layer "F.SilkS")
		)
		(fp_line
			(start -4.52755 -3.008884)
			(end 4.52755 -3.008884)
			(stroke
				(width 0.1)
				(type default)
			)
			(layer "F.SilkS")
		)
		(fp_line
			(start 4.52755 3.009138)
			(end -4.52755 3.009138)
			(stroke
				(width 0.1)
				(type default)
			)
			(layer "F.SilkS")
		)
		(fp_line
			(start -4.52755 3.009138)
			(end -4.52755 -3.008884)
			(stroke
				(width 0.1)
				(type default)
			)
			(layer "F.SilkS")
		)
		(fp_rect
			(start -4.78155 -3.262884)
			(end 4.78155 3.263138)
			(stroke
				(width 0)
				(type default)
			)
			(fill no)
			(layer "F.CrtYd")
		)
		(fp_line
			(start 4.27355 -2.06502)
			(end 4.27355 2.06502)
			(stroke
				(width 0.1)
				(type default)
			)
			(layer "F.Fab")
		)
		(fp_line
			(start -4.27355 -2.06502)
			(end 4.27355 -2.06502)
			(stroke
				(width 0.1)
				(type default)
			)
			(layer "F.Fab")
		)
		(fp_line
			(start 4.27355 2.06502)
			(end -4.27355 2.06502)
			(stroke
				(width 0.1)
				(type default)
			)
			(layer "F.Fab")
		)
		(fp_line
			(start -4.27355 2.06502)
			(end -4.27355 -2.06502)
			(stroke
				(width 0.1)
				(type default)
			)
			(layer "F.Fab")
		)
		(fp_text user "8"
			(at -3.218434 -3.962908 0)
			(unlocked yes)
			(layer "F.SilkS")
			(effects
				(font
					(size 0.7874 0.5842)
					(thickness 0.1524)
				)
			)
		)
		(fp_text user "2"
			(at 2.115566 -3.581908 0)
			(unlocked yes)
			(layer "F.SilkS")
			(effects
				(font
					(size 0.7874 0.5842)
					(thickness 0.1524)
				)
			)
		)
		(fp_text user "1"
			(at 3.004566 3.657092 0)
			(unlocked yes)
			(layer "F.SilkS")
			(effects
				(font
					(size 0.7874 0.5842)
					(thickness 0.1524)
				)
			)
		)
		(fp_text user "7"
			(at -2.329434 4.038092 0)
			(unlocked yes)
			(layer "F.SilkS")
			(effects
				(font
					(size 0.7874 0.5842)
					(thickness 0.1524)
				)
			)
		)
		(fp_text user "8"
			(at -3.205734 -2.946908 0)
			(unlocked yes)
			(layer "F.Fab")
			(effects
				(font
					(size 0.7874 0.5842)
					(thickness 0.1524)
				)
			)
		)
		(fp_text user "2"
			(at 3.525266 -2.819908 0)
			(unlocked yes)
			(layer "F.Fab")
			(effects
				(font
					(size 0.7874 0.5842)
					(thickness 0.1524)
				)
			)
		)
		(fp_text user "1"
			(at 3.398266 2.641092 0)
			(unlocked yes)
			(layer "F.Fab")
			(effects
				(font
					(size 0.7874 0.5842)
					(thickness 0.1524)
				)
			)
		)
		(fp_text user "7"
			(at -3.280664 2.932938 0)
			(unlocked yes)
			(layer "F.Fab")
			(effects
				(font
					(size 0.7874 0.5842)
					(thickness 0.1524)
				)
			)
		)
		(pad "1" smd rect
			(at 2.999994 1.637538 90)
			(size 1.016 2.2352)
			(layers "F.Cu" "F.Mask" "F.Paste")
			(net "XP5R0V_VCC_ANT")
		)
		(pad "2" smd rect
			(at 2.999994 -1.637284 90)
			(size 1.016 2.2352)
			(layers "F.Cu" "F.Mask" "F.Paste")
			(net "XP3R3V_GPS")
		)
		(pad "3" smd rect
			(at 0.999998 1.637538 90)
			(size 1.016 2.2352)
			(layers "F.Cu" "F.Mask" "F.Paste")
			(net "GPS_UART_TXD")
		)
		(pad "4" smd rect
			(at 0.999998 -1.637284 90)
			(size 1.016 2.2352)
			(layers "F.Cu" "F.Mask" "F.Paste")
			(net "GPS_RST_N")
		)
		(pad "5" smd rect
			(at -0.999998 1.637538 90)
			(size 1.016 2.2352)
			(layers "F.Cu" "F.Mask" "F.Paste")
			(net "GPS_UART_RXD")
		)
		(pad "6" smd rect
			(at -0.999998 -1.637284 90)
			(size 1.016 2.2352)
			(layers "F.Cu" "F.Mask" "F.Paste")
			(net "GPSTP1_OUT")
		)
		(pad "7" smd rect
			(at -2.999994 1.637538 90)
			(size 1.016 2.2352)
			(layers "F.Cu" "F.Mask" "F.Paste")
			(net "GPSTP2_OUT")
		)
		(pad "8" smd rect
			(at -2.999994 -1.637284 90)
			(size 1.016 2.2352)
			(layers "F.Cu" "F.Mask" "F.Paste")
			(net "SG")
		)
	)
	(footprint ""
		(layer "F.Cu")
		(at 109.22 -98.171)
		(property "Reference" "TP25"
			(at -0.9144 1.04775 0)
			(unlocked yes)
			(layer "F.SilkS")
			(effects
				(font
					(size 0.635 0.4064)
					(thickness 0.1524)
				)
				(justify left)
			)
		)
		(property "Value" ""
			(at 0 0 0)
			(layer "F.Fab")
			(effects
				(font
					(size 1.27 1.27)
				)
			)
		)
		(property "Device Type" "TP_PIONT-TP010CT020B030_PTH-TPA"
			(at -1.341882 0.996696 0)
			(unlocked yes)
			(layer "F.Fab")
			(hide yes)
			(effects
				(font
					(size 0.7874 0.5842)
					(thickness 0.000001)
				)
				(justify left)
			)
		)
		(duplicate_pad_numbers_are_jumpers no)
		(fp_poly
			(pts
				(arc
					(start 0.889 0)
					(mid -0.889 0)
					(end 0.889 0)
				)
			)
			(stroke
				(width 0)
				(type default)
			)
			(fill no)
			(layer "B.CrtYd")
		)
		(fp_poly
			(pts
				(arc
					(start 0.889 0)
					(mid -0.889 0)
					(end 0.889 0)
				)
			)
			(stroke
				(width 0)
				(type default)
			)
			(fill no)
			(layer "F.CrtYd")
		)
		(pad "1" thru_hole circle
			(at 0 0)
			(size 0.508 0.508)
			(drill 0.254)
			(layers "*.Cu" "*.Mask")
			(remove_unused_layers no)
			(net "RGB_LED_SHUTDOWN_N")
			(clearance 0.1016)
			(padstack
				(mode front_inner_back)
				(layer "Inner"
					(shape circle)
					(size 0.508 0.508)
					(clearance 0.1016)
				)
				(layer "B.Cu"
					(shape circle)
					(size 0.762 0.762)
					(clearance -0.0254)
				)
			)
		)
	)
	(footprint ""
		(layer "F.Cu")
		(at 89.281 -96.012 180)
		(property "Reference" "R38"
			(at -1.651 -2.32537 0)
			(unlocked yes)
			(layer "F.SilkS")
			(effects
				(font
					(size 0.7874 0.5842)
					(thickness 0.1524)
				)
			)
		)
		(property "Value" "VAL*"
			(at 0.02032 2.13233 180)
			(unlocked yes)
			(layer "F.Fab")
			(hide yes)
			(effects
				(font
					(size 0.7874 0.5842)
					(thickness 0.1524)
				)
			)
		)
		(property "Tolerance" "TOL*"
			(at 0.044704 3.05435 180)
			(unlocked yes)
			(layer "Cmts.User")
			(hide yes)
			(effects
				(font
					(size 0.7874 0.5842)
					(thickness 0.1524)
				)
			)
		)
		(property "User Part Number" "PARTNUM*"
			(at 0.02032 4.024884 180)
			(unlocked yes)
			(layer "Cmts.User")
			(hide yes)
			(effects
				(font
					(size 0.7874 0.5842)
					(thickness 0.1524)
				)
			)
		)
		(property "Device Type" "RESISTOR-G155-04421-01,4.42KOHA"
			(at 0.008382 1.210564 180)
			(unlocked yes)
			(layer "F.Fab")
			(hide yes)
			(effects
				(font
					(size 0.7874 0.5842)
					(thickness 0.1524)
				)
			)
		)
		(duplicate_pad_numbers_are_jumpers no)
		(fp_line
			(start 1.143 0.5588)
			(end 1.143 -0.5588)
			(stroke
				(width 0.1)
				(type default)
			)
			(layer "F.SilkS")
		)
		(fp_line
			(start 1.143 -0.5588)
			(end -1.143 -0.5588)
			(stroke
				(width 0.1)
				(type default)
			)
			(layer "F.SilkS")
		)
		(fp_line
			(start -1.143 0.5588)
			(end 1.143 0.5588)
			(stroke
				(width 0.1)
				(type default)
			)
			(layer "F.SilkS")
		)
		(fp_line
			(start -1.143 -0.5588)
			(end -1.143 0.5588)
			(stroke
				(width 0.1)
				(type default)
			)
			(layer "F.SilkS")
		)
		(fp_rect
			(start -1.143 -0.5588)
			(end 1.143 0.5588)
			(stroke
				(width 0)
				(type default)
			)
			(fill no)
			(layer "F.CrtYd")
		)
		(fp_line
			(start 0.508 0.3048)
			(end 0.508 -0.3048)
			(stroke
				(width 0.1)
				(type default)
			)
			(layer "F.Fab")
		)
		(fp_line
			(start 0.508 -0.3048)
			(end -0.508 -0.3048)
			(stroke
				(width 0.1)
				(type default)
			)
			(layer "F.Fab")
		)
		(fp_line
			(start -0.508 0.3048)
			(end 0.508 0.3048)
			(stroke
				(width 0.1)
				(type default)
			)
			(layer "F.Fab")
		)
		(fp_line
			(start -0.508 -0.3048)
			(end -0.508 0.3048)
			(stroke
				(width 0.1)
				(type default)
			)
			(layer "F.Fab")
		)
		(pad "1" smd rect
			(at -0.5334 0 180)
			(size 0.7112 0.6096)
			(layers "F.Cu" "F.Mask" "F.Paste")
			(net "XP3R3V_FB_R_TO_AGND")
		)
		(pad "2" smd rect
			(at 0.5334 0 180)
			(size 0.7112 0.6096)
			(layers "F.Cu" "F.Mask" "F.Paste")
			(net "XP3R3V_AGND")
		)
		(zone
			(layer "F.Cu")
			(hatch none 0.5)
			(connect_pads
				(clearance 0)
			)
			(min_thickness 0.25)
			(keepout
				(tracks allowed)
				(vias not_allowed)
				(pads allowed)
				(copperpour not_allowed)
				(footprints allowed)
			)
			(placement
				(enabled no)
				(sheetname "")
			)
			(fill
				(thermal_gap 0.5)
				(thermal_bridge_width 0.5)
				(island_removal_mode 0)
			)
			(polygon
				(pts
					(xy 89.3572 -95.7072) (xy 89.3572 -96.3168) (xy 89.2048 -96.3168) (xy 89.2048 -95.7072)
				)
			)
		)
	)
	(footprint ""
		(layer "F.Cu")
		(at 159.7406 -50.590196 -90)
		(property "Reference" "C63"
			(at -1.098804 3.11023 90)
			(unlocked yes)
			(layer "F.SilkS")
			(effects
				(font
					(size 0.7874 0.5842)
					(thickness 0.1524)
				)
			)
		)
		(property "Value" "VAL*"
			(at 0.0762 2.067306 270)
			(unlocked yes)
			(layer "F.Fab")
			(hide yes)
			(effects
				(font
					(size 0.7874 0.5842)
					(thickness 0.1524)
				)
			)
		)
		(property "Tolerance" "TOL*"
			(at 0.0762 3.032506 270)
			(unlocked yes)
			(layer "Cmts.User")
			(hide yes)
			(effects
				(font
					(size 0.7874 0.5842)
					(thickness 0.1524)
				)
			)
		)
		(property "User Part Number" "PARTNUM*"
			(at 0.1016 4.023106 270)
			(unlocked yes)
			(layer "Cmts.User")
			(hide yes)
			(effects
				(font
					(size 0.7874 0.5842)
					(thickness 0.1524)
				)
			)
		)
		(property "Device Type" "CAPACITOR-G105-0B104-EK,0.1UF,A"
			(at 0.0508 1.127506 270)
			(unlocked yes)
			(layer "F.Fab")
			(hide yes)
			(effects
				(font
					(size 0.7874 0.5842)
					(thickness 0.1524)
				)
			)
		)
		(duplicate_pad_numbers_are_jumpers no)
		(fp_line
			(start -1.143 0.5588)
			(end 1.143 0.5588)
			(stroke
				(width 0.1)
				(type default)
			)
			(layer "F.SilkS")
		)
		(fp_line
			(start 1.143 0.5588)
			(end 1.143 -0.5588)
			(stroke
				(width 0.1)
				(type default)
			)
			(layer "F.SilkS")
		)
		(fp_line
			(start -1.143 -0.5588)
			(end -1.143 0.5588)
			(stroke
				(width 0.1)
				(type default)
			)
			(layer "F.SilkS")
		)
		(fp_line
			(start 1.143 -0.5588)
			(end -1.143 -0.5588)
			(stroke
				(width 0.1)
				(type default)
			)
			(layer "F.SilkS")
		)
		(fp_rect
			(start 1.143 -0.5588)
			(end -1.143 0.5588)
			(stroke
				(width 0)
				(type default)
			)
			(fill no)
			(layer "F.CrtYd")
		)
		(fp_line
			(start -0.508 0.3048)
			(end 0.508 0.3048)
			(stroke
				(width 0.1)
				(type default)
			)
			(layer "F.Fab")
		)
		(fp_line
			(start 0.508 0.3048)
			(end 0.508 -0.3048)
			(stroke
				(width 0.1)
				(type default)
			)
			(layer "F.Fab")
		)
		(fp_line
			(start -0.508 -0.3048)
			(end -0.508 0.3048)
			(stroke
				(width 0.1)
				(type default)
			)
			(layer "F.Fab")
		)
		(fp_line
			(start 0.508 -0.3048)
			(end -0.508 -0.3048)
			(stroke
				(width 0.1)
				(type default)
			)
			(layer "F.Fab")
		)
		(pad "1" smd rect
			(at -0.5334 0 270)
			(size 0.7112 0.6096)
			(layers "F.Cu" "F.Mask" "F.Paste")
			(net "XP5R0V_USB_CONN")
		)
		(pad "2" smd rect
			(at 0.5334 0 270)
			(size 0.7112 0.6096)
			(layers "F.Cu" "F.Mask" "F.Paste")
			(net "SG")
		)
		(zone
			(layer "F.Cu")
			(hatch none 0.5)
			(connect_pads
				(clearance 0)
			)
			(min_thickness 0.25)
			(keepout
				(tracks allowed)
				(vias not_allowed)
				(pads allowed)
				(copperpour not_allowed)
				(footprints allowed)
			)
			(placement
				(enabled no)
				(sheetname "")
			)
			(fill
				(thermal_gap 0.5)
				(thermal_bridge_width 0.5)
				(island_removal_mode 0)
			)
			(polygon
				(pts
					(xy 160.0454 -50.513996) (xy 160.0454 -50.666396) (xy 159.4358 -50.666396) (xy 159.4358 -50.513996)
				)
			)
		)
	)
	(footprint ""
		(layer "F.Cu")
		(at 93.0148 -76.1238 -90)
		(property "Reference" "C182"
			(at -18.9992 27.06243 90)
			(unlocked yes)
			(layer "F.SilkS")
			(effects
				(font
					(size 0.7874 0.5842)
					(thickness 0.1524)
				)
			)
		)
		(property "Value" "VAL*"
			(at 0.0762 2.067306 270)
			(unlocked yes)
			(layer "F.Fab")
			(hide yes)
			(effects
				(font
					(size 0.7874 0.5842)
					(thickness 0.1524)
				)
			)
		)
		(property "Tolerance" "TOL*"
			(at 0.0762 3.032506 270)
			(unlocked yes)
			(layer "Cmts.User")
			(hide yes)
			(effects
				(font
					(size 0.7874 0.5842)
					(thickness 0.1524)
				)
			)
		)
		(property "User Part Number" "PARTNUM*"
			(at 0.1016 4.023106 270)
			(unlocked yes)
			(layer "Cmts.User")
			(hide yes)
			(effects
				(font
					(size 0.7874 0.5842)
					(thickness 0.1524)
				)
			)
		)
		(property "Device Type" "CAPACITOR-G105-0B104-EK,0.1UF,A"
			(at 0.0508 1.127506 270)
			(unlocked yes)
			(layer "F.Fab")
			(hide yes)
			(effects
				(font
					(size 0.7874 0.5842)
					(thickness 0.1524)
				)
			)
		)
		(duplicate_pad_numbers_are_jumpers no)
		(fp_line
			(start -1.143 0.5588)
			(end 1.143 0.5588)
			(stroke
				(width 0.1)
				(type default)
			)
			(layer "F.SilkS")
		)
		(fp_line
			(start 1.143 0.5588)
			(end 1.143 -0.5588)
			(stroke
				(width 0.1)
				(type default)
			)
			(layer "F.SilkS")
		)
		(fp_line
			(start -1.143 -0.5588)
			(end -1.143 0.5588)
			(stroke
				(width 0.1)
				(type default)
			)
			(layer "F.SilkS")
		)
		(fp_line
			(start 1.143 -0.5588)
			(end -1.143 -0.5588)
			(stroke
				(width 0.1)
				(type default)
			)
			(layer "F.SilkS")
		)
		(fp_rect
			(start -1.143 0.5588)
			(end 1.143 -0.5588)
			(stroke
				(width 0)
				(type default)
			)
			(fill no)
			(layer "F.CrtYd")
		)
		(fp_line
			(start -0.508 0.3048)
			(end 0.508 0.3048)
			(stroke
				(width 0.1)
				(type default)
			)
			(layer "F.Fab")
		)
		(fp_line
			(start 0.508 0.3048)
			(end 0.508 -0.3048)
			(stroke
				(width 0.1)
				(type default)
			)
			(layer "F.Fab")
		)
		(fp_line
			(start -0.508 -0.3048)
			(end -0.508 0.3048)
			(stroke
				(width 0.1)
				(type default)
			)
			(layer "F.Fab")
		)
		(fp_line
			(start 0.508 -0.3048)
			(end -0.508 -0.3048)
			(stroke
				(width 0.1)
				(type default)
			)
			(layer "F.Fab")
		)
		(pad "1" smd rect
			(at -0.5334 0 270)
			(size 0.7112 0.6096)
			(layers "F.Cu" "F.Mask" "F.Paste")
			(net "XP3R3V")
		)
		(pad "2" smd rect
			(at 0.5334 0 270)
			(size 0.7112 0.6096)
			(layers "F.Cu" "F.Mask" "F.Paste")
			(net "SG")
		)
		(zone
			(layer "F.Cu")
			(hatch none 0.5)
			(connect_pads
				(clearance 0)
			)
			(min_thickness 0.25)
			(keepout
				(tracks allowed)
				(vias not_allowed)
				(pads allowed)
				(copperpour not_allowed)
				(footprints allowed)
			)
			(placement
				(enabled no)
				(sheetname "")
			)
			(fill
				(thermal_gap 0.5)
				(thermal_bridge_width 0.5)
				(island_removal_mode 0)
			)
			(polygon
				(pts
					(xy 92.71 -76.2) (xy 92.71 -76.0476) (xy 93.3196 -76.0476) (xy 93.3196 -76.2)
				)
			)
		)
	)
	(footprint ""
		(layer "F.Cu")
		(at 94.107 -21.336)
		(property "Reference" "TP50"
			(at -2.3622 1.43637 0)
			(unlocked yes)
			(layer "F.SilkS")
			(effects
				(font
					(size 0.7874 0.5842)
					(thickness 0.1524)
				)
				(justify left)
			)
		)
		(property "Value" ""
			(at 0 0 0)
			(layer "F.Fab")
			(effects
				(font
					(size 1.27 1.27)
				)
			)
		)
		(property "Device Type" "TP_PIONT-TP010CT020B030_PTH-TPA"
			(at -1.341882 0.996696 0)
			(unlocked yes)
			(layer "F.Fab")
			(hide yes)
			(effects
				(font
					(size 0.7874 0.5842)
					(thickness 0.000001)
				)
				(justify left)
			)
		)
		(duplicate_pad_numbers_are_jumpers no)
		(fp_poly
			(pts
				(arc
					(start 0.889 0)
					(mid -0.889 0)
					(end 0.889 0)
				)
			)
			(stroke
				(width 0)
				(type default)
			)
			(fill no)
			(layer "B.CrtYd")
		)
		(fp_poly
			(pts
				(arc
					(start 0.889 0)
					(mid -0.889 0)
					(end 0.889 0)
				)
			)
			(stroke
				(width 0)
				(type default)
			)
			(fill no)
			(layer "F.CrtYd")
		)
		(pad "1" thru_hole circle
			(at 0 0)
			(size 0.508 0.508)
			(drill 0.254)
			(layers "*.Cu" "*.Mask")
			(remove_unused_layers no)
			(net "CLK_125M_OE")
			(clearance 0.1016)
			(padstack
				(mode front_inner_back)
				(layer "Inner"
					(shape circle)
					(size 0.508 0.508)
					(clearance 0.1016)
				)
				(layer "B.Cu"
					(shape circle)
					(size 0.762 0.762)
					(clearance -0.0254)
				)
			)
		)
	)
	(footprint ""
		(layer "F.Cu")
		(at 146.6088 -17.2466 -90)
		(property "Reference" "C227"
			(at 1.79197 -2.6162 0)
			(unlocked yes)
			(layer "F.SilkS")
			(effects
				(font
					(size 0.7874 0.5842)
					(thickness 0.1524)
				)
			)
		)
		(property "Value" "VAL*"
			(at 0.0762 2.067306 270)
			(unlocked yes)
			(layer "F.Fab")
			(hide yes)
			(effects
				(font
					(size 0.7874 0.5842)
					(thickness 0.1524)
				)
			)
		)
		(property "Tolerance" "TOL*"
			(at 0.0762 3.032506 270)
			(unlocked yes)
			(layer "Cmts.User")
			(hide yes)
			(effects
				(font
					(size 0.7874 0.5842)
					(thickness 0.1524)
				)
			)
		)
		(property "User Part Number" "PARTNUM*"
			(at 0.1016 4.023106 270)
			(unlocked yes)
			(layer "Cmts.User")
			(hide yes)
			(effects
				(font
					(size 0.7874 0.5842)
					(thickness 0.1524)
				)
			)
		)
		(property "Device Type" "CAPACITOR-G105-0B104-EK,0.1UF,A"
			(at 0.0508 1.127506 270)
			(unlocked yes)
			(layer "F.Fab")
			(hide yes)
			(effects
				(font
					(size 0.7874 0.5842)
					(thickness 0.1524)
				)
			)
		)
		(duplicate_pad_numbers_are_jumpers no)
		(fp_line
			(start -1.143 0.5588)
			(end 1.143 0.5588)
			(stroke
				(width 0.1)
				(type default)
			)
			(layer "F.SilkS")
		)
		(fp_line
			(start 1.143 0.5588)
			(end 1.143 -0.5588)
			(stroke
				(width 0.1)
				(type default)
			)
			(layer "F.SilkS")
		)
		(fp_line
			(start -1.143 -0.5588)
			(end -1.143 0.5588)
			(stroke
				(width 0.1)
				(type default)
			)
			(layer "F.SilkS")
		)
		(fp_line
			(start 1.143 -0.5588)
			(end -1.143 -0.5588)
			(stroke
				(width 0.1)
				(type default)
			)
			(layer "F.SilkS")
		)
		(fp_rect
			(start -1.143 -0.5588)
			(end 1.143 0.5588)
			(stroke
				(width 0)
				(type default)
			)
			(fill no)
			(layer "F.CrtYd")
		)
		(fp_line
			(start -0.508 0.3048)
			(end 0.508 0.3048)
			(stroke
				(width 0.1)
				(type default)
			)
			(layer "F.Fab")
		)
		(fp_line
			(start 0.508 0.3048)
			(end 0.508 -0.3048)
			(stroke
				(width 0.1)
				(type default)
			)
			(layer "F.Fab")
		)
		(fp_line
			(start -0.508 -0.3048)
			(end -0.508 0.3048)
			(stroke
				(width 0.1)
				(type default)
			)
			(layer "F.Fab")
		)
		(fp_line
			(start 0.508 -0.3048)
			(end -0.508 -0.3048)
			(stroke
				(width 0.1)
				(type default)
			)
			(layer "F.Fab")
		)
		(pad "1" smd rect
			(at -0.5334 0 270)
			(size 0.7112 0.6096)
			(layers "F.Cu" "F.Mask" "F.Paste")
			(net "UNNAMED_515_CAPACITOR_I128_1")
		)
		(pad "2" smd rect
			(at 0.5334 0 270)
			(size 0.7112 0.6096)
			(layers "F.Cu" "F.Mask" "F.Paste")
			(net "SG")
		)
		(zone
			(layer "F.Cu")
			(hatch none 0.5)
			(connect_pads
				(clearance 0)
			)
			(min_thickness 0.25)
			(keepout
				(tracks allowed)
				(vias not_allowed)
				(pads allowed)
				(copperpour not_allowed)
				(footprints allowed)
			)
			(placement
				(enabled no)
				(sheetname "")
			)
			(fill
				(thermal_gap 0.5)
				(thermal_bridge_width 0.5)
				(island_removal_mode 0)
			)
			(polygon
				(pts
					(xy 146.9136 -17.3228) (xy 146.304 -17.3228) (xy 146.304 -17.1704) (xy 146.9136 -17.1704)
				)
			)
		)
	)
	(footprint ""
		(layer "B.Cu")
		(at 139.065 -72.898 180)
		(property "Reference" "R43"
			(at 2.286 0.21463 0)
			(unlocked yes)
			(layer "B.SilkS")
			(effects
				(font
					(size 0.7874 0.5842)
					(thickness 0.1524)
				)
				(justify mirror)
			)
		)
		(property "Value" "VAL*"
			(at -0.02032 2.13233 180)
			(unlocked yes)
			(layer "B.Fab")
			(hide yes)
			(effects
				(font
					(size 0.7874 0.5842)
					(thickness 0.1524)
				)
				(justify mirror)
			)
		)
		(property "Tolerance" "TOL*"
			(at -0.044704 3.05435 180)
			(unlocked yes)
			(layer "Cmts.User")
			(hide yes)
			(effects
				(font
					(size 0.7874 0.5842)
					(thickness 0.1524)
				)
				(justify mirror)
			)
		)
		(property "User Part Number" "PARTNUM*"
			(at -0.02032 4.024884 180)
			(unlocked yes)
			(layer "Cmts.User")
			(hide yes)
			(effects
				(font
					(size 0.7874 0.5842)
					(thickness 0.1524)
				)
				(justify mirror)
			)
		)
		(property "Device Type" "RESISTOR-G155-100R0-J0,0OHM,-"
			(at -0.008382 1.210564 180)
			(unlocked yes)
			(layer "B.Fab")
			(hide yes)
			(effects
				(font
					(size 0.7874 0.5842)
					(thickness 0.1524)
				)
				(justify mirror)
			)
		)
		(duplicate_pad_numbers_are_jumpers no)
		(fp_line
			(start 1.143 0.5588)
			(end -1.143 0.5588)
			(stroke
				(width 0.1)
				(type default)
			)
			(layer "B.SilkS")
		)
		(fp_line
			(start 1.143 -0.5588)
			(end 1.143 0.5588)
			(stroke
				(width 0.1)
				(type default)
			)
			(layer "B.SilkS")
		)
		(fp_line
			(start -1.143 0.5588)
			(end -1.143 -0.5588)
			(stroke
				(width 0.1)
				(type default)
			)
			(layer "B.SilkS")
		)
		(fp_line
			(start -1.143 -0.5588)
			(end 1.143 -0.5588)
			(stroke
				(width 0.1)
				(type default)
			)
			(layer "B.SilkS")
		)
		(fp_rect
			(start 1.143 0.5588)
			(end -1.143 -0.5588)
			(stroke
				(width 0)
				(type default)
			)
			(fill no)
			(layer "B.CrtYd")
		)
		(fp_line
			(start 0.508 0.3048)
			(end -0.508 0.3048)
			(stroke
				(width 0.1)
				(type default)
			)
			(layer "B.Fab")
		)
		(fp_line
			(start 0.508 -0.3048)
			(end 0.508 0.3048)
			(stroke
				(width 0.1)
				(type default)
			)
			(layer "B.Fab")
		)
		(fp_line
			(start -0.508 0.3048)
			(end -0.508 -0.3048)
			(stroke
				(width 0.1)
				(type default)
			)
			(layer "B.Fab")
		)
		(fp_line
			(start -0.508 -0.3048)
			(end 0.508 -0.3048)
			(stroke
				(width 0.1)
				(type default)
			)
			(layer "B.Fab")
		)
		(pad "1" smd rect
			(at 0.5334 0)
			(size 0.7112 0.6096)
			(layers "B.Cu" "B.Mask" "B.Paste")
			(net "PCIE_CONN_TMS")
		)
		(pad "2" smd rect
			(at -0.5334 0)
			(size 0.7112 0.6096)
			(layers "B.Cu" "B.Mask" "B.Paste")
			(net "FPGA_TMS")
		)
		(zone
			(layer "B.Cu")
			(hatch none 0.5)
			(connect_pads
				(clearance 0)
			)
			(min_thickness 0.25)
			(keepout
				(tracks allowed)
				(vias not_allowed)
				(pads allowed)
				(copperpour not_allowed)
				(footprints allowed)
			)
			(placement
				(enabled no)
				(sheetname "")
			)
			(fill
				(thermal_gap 0.5)
				(thermal_bridge_width 0.5)
				(island_removal_mode 0)
			)
			(polygon
				(pts
					(xy 138.9888 -73.2028) (xy 138.9888 -72.5932) (xy 139.1412 -72.5932) (xy 139.1412 -73.2028)
				)
			)
		)
	)
	(footprint ""
		(layer "B.Cu")
		(at 140.335 -67.056)
		(property "Reference" "R134"
			(at 1.73863 -1.143 270)
			(unlocked yes)
			(layer "B.SilkS")
			(effects
				(font
					(size 0.7874 0.5842)
					(thickness 0.1524)
				)
				(justify mirror)
			)
		)
		(property "Value" "VAL*"
			(at -0.02032 2.13233 0)
			(unlocked yes)
			(layer "B.Fab")
			(hide yes)
			(effects
				(font
					(size 0.7874 0.5842)
					(thickness 0.1524)
				)
				(justify mirror)
			)
		)
		(property "Tolerance" "TOL*"
			(at -0.044704 3.05435 0)
			(unlocked yes)
			(layer "Cmts.User")
			(hide yes)
			(effects
				(font
					(size 0.7874 0.5842)
					(thickness 0.1524)
				)
				(justify mirror)
			)
		)
		(property "User Part Number" "PARTNUM*"
			(at -0.02032 4.024884 0)
			(unlocked yes)
			(layer "Cmts.User")
			(hide yes)
			(effects
				(font
					(size 0.7874 0.5842)
					(thickness 0.1524)
				)
				(justify mirror)
			)
		)
		(property "Device Type" "RESISTOR-G155-133R0-01,33OHM,1%"
			(at -0.008382 1.210564 0)
			(unlocked yes)
			(layer "B.Fab")
			(hide yes)
			(effects
				(font
					(size 0.7874 0.5842)
					(thickness 0.1524)
				)
				(justify mirror)
			)
		)
		(duplicate_pad_numbers_are_jumpers no)
		(fp_line
			(start -1.143 -0.5588)
			(end 1.143 -0.5588)
			(stroke
				(width 0.1)
				(type default)
			)
			(layer "B.SilkS")
		)
		(fp_line
			(start -1.143 0.5588)
			(end -1.143 -0.5588)
			(stroke
				(width 0.1)
				(type default)
			)
			(layer "B.SilkS")
		)
		(fp_line
			(start 1.143 -0.5588)
			(end 1.143 0.5588)
			(stroke
				(width 0.1)
				(type default)
			)
			(layer "B.SilkS")
		)
		(fp_line
			(start 1.143 0.5588)
			(end -1.143 0.5588)
			(stroke
				(width 0.1)
				(type default)
			)
			(layer "B.SilkS")
		)
		(fp_rect
			(start -1.143 -0.5588)
			(end 1.143 0.5588)
			(stroke
				(width 0)
				(type default)
			)
			(fill no)
			(layer "B.CrtYd")
		)
		(fp_line
			(start -0.508 -0.3048)
			(end 0.508 -0.3048)
			(stroke
				(width 0.1)
				(type default)
			)
			(layer "B.Fab")
		)
		(fp_line
			(start -0.508 0.3048)
			(end -0.508 -0.3048)
			(stroke
				(width 0.1)
				(type default)
			)
			(layer "B.Fab")
		)
		(fp_line
			(start 0.508 -0.3048)
			(end 0.508 0.3048)
			(stroke
				(width 0.1)
				(type default)
			)
			(layer "B.Fab")
		)
		(fp_line
			(start 0.508 0.3048)
			(end -0.508 0.3048)
			(stroke
				(width 0.1)
				(type default)
			)
			(layer "B.Fab")
		)
		(pad "1" smd rect
			(at 0.5334 0 180)
			(size 0.7112 0.6096)
			(layers "B.Cu" "B.Mask" "B.Paste")
			(net "FT4232_FPGA_TCK")
		)
		(pad "2" smd rect
			(at -0.5334 0 180)
			(size 0.7112 0.6096)
			(layers "B.Cu" "B.Mask" "B.Paste")
			(net "FPGA_TCK")
		)
		(zone
			(layer "B.Cu")
			(hatch none 0.5)
			(connect_pads
				(clearance 0)
			)
			(min_thickness 0.25)
			(keepout
				(tracks allowed)
				(vias not_allowed)
				(pads allowed)
				(copperpour not_allowed)
				(footprints allowed)
			)
			(placement
				(enabled no)
				(sheetname "")
			)
			(fill
				(thermal_gap 0.5)
				(thermal_bridge_width 0.5)
				(island_removal_mode 0)
			)
			(polygon
				(pts
					(xy 140.2588 -67.3608) (xy 140.2588 -66.7512) (xy 140.4112 -66.7512) (xy 140.4112 -67.3608)
				)
			)
		)
	)
	(footprint ""
		(layer "B.Cu")
		(at 162.56 -27.432 180)
		(property "Reference" "R417"
			(at 0.508 2.11963 0)
			(unlocked yes)
			(layer "B.SilkS")
			(effects
				(font
					(size 0.7874 0.5842)
					(thickness 0.1524)
				)
				(justify mirror)
			)
		)
		(property "Value" "VAL*"
			(at -0.02032 2.13233 180)
			(unlocked yes)
			(layer "B.Fab")
			(hide yes)
			(effects
				(font
					(size 0.7874 0.5842)
					(thickness 0.1524)
				)
				(justify mirror)
			)
		)
		(property "Tolerance" "TOL*"
			(at -0.044704 3.05435 180)
			(unlocked yes)
			(layer "Cmts.User")
			(hide yes)
			(effects
				(font
					(size 0.7874 0.5842)
					(thickness 0.1524)
				)
				(justify mirror)
			)
		)
		(property "User Part Number" "PARTNUM*"
			(at -0.02032 4.024884 180)
			(unlocked yes)
			(layer "Cmts.User")
			(hide yes)
			(effects
				(font
					(size 0.7874 0.5842)
					(thickness 0.1524)
				)
				(justify mirror)
			)
		)
		(property "Device Type" "RESISTOR-G155-11001-01,1KOHM,1%"
			(at -0.008382 1.210564 180)
			(unlocked yes)
			(layer "B.Fab")
			(hide yes)
			(effects
				(font
					(size 0.7874 0.5842)
					(thickness 0.1524)
				)
				(justify mirror)
			)
		)
		(duplicate_pad_numbers_are_jumpers no)
		(fp_line
			(start 1.143 0.5588)
			(end -1.143 0.5588)
			(stroke
				(width 0.1)
				(type default)
			)
			(layer "B.SilkS")
		)
		(fp_line
			(start 1.143 -0.5588)
			(end 1.143 0.5588)
			(stroke
				(width 0.1)
				(type default)
			)
			(layer "B.SilkS")
		)
		(fp_line
			(start -1.143 0.5588)
			(end -1.143 -0.5588)
			(stroke
				(width 0.1)
				(type default)
			)
			(layer "B.SilkS")
		)
		(fp_line
			(start -1.143 -0.5588)
			(end 1.143 -0.5588)
			(stroke
				(width 0.1)
				(type default)
			)
			(layer "B.SilkS")
		)
		(fp_rect
			(start 1.143 -0.5588)
			(end -1.143 0.5588)
			(stroke
				(width 0)
				(type default)
			)
			(fill no)
			(layer "B.CrtYd")
		)
		(fp_line
			(start 0.508 0.3048)
			(end -0.508 0.3048)
			(stroke
				(width 0.1)
				(type default)
			)
			(layer "B.Fab")
		)
		(fp_line
			(start 0.508 -0.3048)
			(end 0.508 0.3048)
			(stroke
				(width 0.1)
				(type default)
			)
			(layer "B.Fab")
		)
		(fp_line
			(start -0.508 0.3048)
			(end -0.508 -0.3048)
			(stroke
				(width 0.1)
				(type default)
			)
			(layer "B.Fab")
		)
		(fp_line
			(start -0.508 -0.3048)
			(end 0.508 -0.3048)
			(stroke
				(width 0.1)
				(type default)
			)
			(layer "B.Fab")
		)
		(pad "1" smd rect
			(at 0.5334 0)
			(size 0.7112 0.6096)
			(layers "B.Cu" "B.Mask" "B.Paste")
			(net "UNNAMED_6_LM75BDPTSSOP8_I81_A0")
		)
		(pad "2" smd rect
			(at -0.5334 0)
			(size 0.7112 0.6096)
			(layers "B.Cu" "B.Mask" "B.Paste")
			(net "SG")
		)
		(zone
			(layer "B.Cu")
			(hatch none 0.5)
			(connect_pads
				(clearance 0)
			)
			(min_thickness 0.25)
			(keepout
				(tracks not_allowed)
				(vias allowed)
				(pads allowed)
				(copperpour not_allowed)
				(footprints allowed)
			)
			(placement
				(enabled no)
				(sheetname "")
			)
			(fill
				(thermal_gap 0.5)
				(thermal_bridge_width 0.5)
				(island_removal_mode 0)
			)
			(polygon
				(pts
					(xy 162.4838 -27.1272) (xy 162.6362 -27.1272) (xy 162.6362 -27.7368) (xy 162.4838 -27.7368)
				)
			)
		)
		(zone
			(layer "B.Cu")
			(hatch none 0.5)
			(connect_pads
				(clearance 0)
			)
			(min_thickness 0.25)
			(keepout
				(tracks allowed)
				(vias not_allowed)
				(pads allowed)
				(copperpour not_allowed)
				(footprints allowed)
			)
			(placement
				(enabled no)
				(sheetname "")
			)
			(fill
				(thermal_gap 0.5)
				(thermal_bridge_width 0.5)
				(island_removal_mode 0)
			)
			(polygon
				(pts
					(xy 162.4838 -27.1272) (xy 162.6362 -27.1272) (xy 162.6362 -27.7368) (xy 162.4838 -27.7368)
				)
			)
		)
	)
	(footprint ""
		(layer "B.Cu")
		(at 105.8418 -72.517)
		(property "Reference" "C243"
			(at -3.81 -0.08763 0)
			(unlocked yes)
			(layer "B.SilkS")
			(effects
				(font
					(size 0.7874 0.5842)
					(thickness 0.1524)
				)
				(justify mirror)
			)
		)
		(property "Value" "VAL*"
			(at -0.0762 3.134106 0)
			(unlocked yes)
			(layer "B.Fab")
			(hide yes)
			(effects
				(font
					(size 0.7874 0.5842)
					(thickness 0.1524)
				)
				(justify mirror)
			)
		)
		(property "Device Type" "CAPACITOR-G107-0F226-CM,22UF,2A"
			(at -0.0508 2.194306 0)
			(unlocked yes)
			(layer "B.Fab")
			(hide yes)
			(effects
				(font
					(size 0.7874 0.5842)
					(thickness 0.1524)
				)
				(justify mirror)
			)
		)
		(property "User Part Number" "PARTNUM*"
			(at -0.1016 5.013706 0)
			(unlocked yes)
			(layer "Cmts.User")
			(hide yes)
			(effects
				(font
					(size 0.7874 0.5842)
					(thickness 0.1524)
				)
				(justify mirror)
			)
		)
		(property "Tolerance" "TOL*"
			(at -0.0762 4.048506 0)
			(unlocked yes)
			(layer "Cmts.User")
			(hide yes)
			(effects
				(font
					(size 0.7874 0.5842)
					(thickness 0.1524)
				)
				(justify mirror)
			)
		)
		(duplicate_pad_numbers_are_jumpers no)
		(fp_line
			(start -1.5748 -0.9398)
			(end 1.5748 -0.9398)
			(stroke
				(width 0.1)
				(type default)
			)
			(layer "B.SilkS")
		)
		(fp_line
			(start -1.5748 0.9398)
			(end -1.5748 -0.9398)
			(stroke
				(width 0.1)
				(type default)
			)
			(layer "B.SilkS")
		)
		(fp_line
			(start 1.5748 -0.9398)
			(end 1.5748 0.9398)
			(stroke
				(width 0.1)
				(type default)
			)
			(layer "B.SilkS")
		)
		(fp_line
			(start 1.5748 0.9398)
			(end -1.5748 0.9398)
			(stroke
				(width 0.1)
				(type default)
			)
			(layer "B.SilkS")
		)
		(fp_rect
			(start 1.5748 -0.9398)
			(end -1.5748 0.9398)
			(stroke
				(width 0)
				(type default)
			)
			(fill no)
			(layer "B.CrtYd")
		)
		(fp_line
			(start -1.016 -0.635)
			(end 1.016 -0.635)
			(stroke
				(width 0.1)
				(type default)
			)
			(layer "B.Fab")
		)
		(fp_line
			(start -1.016 0.635)
			(end -1.016 -0.635)
			(stroke
				(width 0.1)
				(type default)
			)
			(layer "B.Fab")
		)
		(fp_line
			(start 1.016 -0.635)
			(end 1.016 0.635)
			(stroke
				(width 0.1)
				(type default)
			)
			(layer "B.Fab")
		)
		(fp_line
			(start 1.016 0.635)
			(end -1.016 0.635)
			(stroke
				(width 0.1)
				(type default)
			)
			(layer "B.Fab")
		)
		(pad "1" smd rect
			(at 0.8382 0 180)
			(size 0.9652 1.3716)
			(layers "B.Cu" "B.Mask" "B.Paste")
			(net "XP3R3V_FPGA")
		)
		(pad "2" smd rect
			(at -0.8382 0 180)
			(size 0.9652 1.3716)
			(layers "B.Cu" "B.Mask" "B.Paste")
			(net "SG")
		)
		(zone
			(layer "B.Cu")
			(hatch none 0.5)
			(connect_pads
				(clearance 0)
			)
			(min_thickness 0.25)
			(keepout
				(tracks allowed)
				(vias not_allowed)
				(pads allowed)
				(copperpour not_allowed)
				(footprints allowed)
			)
			(placement
				(enabled no)
				(sheetname "")
			)
			(fill
				(thermal_gap 0.5)
				(thermal_bridge_width 0.5)
				(island_removal_mode 0)
			)
			(polygon
				(pts
					(xy 106.0704 -73.152) (xy 105.6132 -73.152) (xy 105.6132 -71.882) (xy 106.0704 -71.882)
				)
			)
		)
	)
	(footprint ""
		(layer "B.Cu")
		(at 99.846892 -44.323254 -90)
		(property "Reference" "C205"
			(at -0.634746 -0.959358 270)
			(unlocked yes)
			(layer "B.SilkS")
			(effects
				(font
					(size 0.635 0.4064)
					(thickness 0.1524)
				)
				(justify mirror)
			)
		)
		(property "Value" "VAL*"
			(at 0 3.718306 270)
			(unlocked yes)
			(layer "B.Fab")
			(hide yes)
			(effects
				(font
					(size 0.7874 0.5842)
					(thickness 0.127)
				)
				(justify mirror)
			)
		)
		(property "Tolerance" "TOL*"
			(at 0 4.861306 270)
			(unlocked yes)
			(layer "Cmts.User")
			(hide yes)
			(effects
				(font
					(size 0.7874 0.5842)
					(thickness 0.127)
				)
				(justify mirror)
			)
		)
		(property "User Part Number" "PARTNUM*"
			(at 0 2.575306 270)
			(unlocked yes)
			(layer "Cmts.User")
			(hide yes)
			(effects
				(font
					(size 0.7874 0.5842)
					(thickness 0.127)
				)
				(justify mirror)
			)
		)
		(property "Device Type" "CAPACITOR-G105-0B104-CK,0.1UF,A"
			(at 0 1.432306 270)
			(unlocked yes)
			(layer "B.Fab")
			(hide yes)
			(effects
				(font
					(size 0.7874 0.5842)
					(thickness 0.127)
				)
				(justify mirror)
			)
		)
		(duplicate_pad_numbers_are_jumpers no)
		(fp_line
			(start -0.970026 0.4699)
			(end 0.970026 0.4699)
			(stroke
				(width 0.1)
				(type default)
			)
			(layer "B.SilkS")
		)
		(fp_line
			(start 0.970026 0.4699)
			(end 0.970026 -0.4699)
			(stroke
				(width 0.1)
				(type default)
			)
			(layer "B.SilkS")
		)
		(fp_line
			(start -0.970026 -0.4699)
			(end -0.970026 0.4699)
			(stroke
				(width 0.1)
				(type default)
			)
			(layer "B.SilkS")
		)
		(fp_line
			(start 0.970026 -0.4699)
			(end -0.970026 -0.4699)
			(stroke
				(width 0.1)
				(type default)
			)
			(layer "B.SilkS")
		)
		(fp_poly
			(pts
				(xy 0.970026 0.4699) (xy -0.970026 0.4699) (xy -0.970026 -0.4699) (xy 0.970026 -0.4699)
			)
			(stroke
				(width 0)
				(type default)
			)
			(fill no)
			(layer "B.CrtYd")
		)
		(fp_line
			(start -0.508 0.3048)
			(end 0.508 0.3048)
			(stroke
				(width 0.1)
				(type default)
			)
			(layer "B.Fab")
		)
		(fp_line
			(start 0.508 0.3048)
			(end 0.508 -0.3048)
			(stroke
				(width 0.1)
				(type default)
			)
			(layer "B.Fab")
		)
		(fp_line
			(start -0.508 -0.3048)
			(end -0.508 0.3048)
			(stroke
				(width 0.1)
				(type default)
			)
			(layer "B.Fab")
		)
		(fp_line
			(start 0.508 -0.3048)
			(end -0.508 -0.3048)
			(stroke
				(width 0.1)
				(type default)
			)
			(layer "B.Fab")
		)
		(pad "1" smd circle
			(at 0.500126 0 90)
			(size 0.635 0.635)
			(layers "B.Cu" "B.Mask" "B.Paste")
			(net "FPGA_MGTAVTT")
		)
		(pad "2" smd circle
			(at -0.500126 0 90)
			(size 0.635 0.635)
			(layers "B.Cu" "B.Mask" "B.Paste")
			(net "SG")
		)
	)
	(footprint ""
		(layer "B.Cu")
		(at 137.795 -17.526 180)
		(property "Reference" "R233"
			(at 1.27 1.10363 0)
			(unlocked yes)
			(layer "B.SilkS")
			(effects
				(font
					(size 0.7874 0.5842)
					(thickness 0.1524)
				)
				(justify mirror)
			)
		)
		(property "Value" "VAL*"
			(at -0.0508 2.245106 180)
			(unlocked yes)
			(layer "B.Fab")
			(hide yes)
			(effects
				(font
					(size 0.7874 0.5842)
					(thickness 0.1524)
				)
				(justify mirror)
			)
		)
		(property "Tolerance" "TOL*"
			(at -0.0508 3.261106 180)
			(unlocked yes)
			(layer "Cmts.User")
			(hide yes)
			(effects
				(font
					(size 0.7874 0.5842)
					(thickness 0.1524)
				)
				(justify mirror)
			)
		)
		(property "Device Type" "RESISTOR-G155-02101-01,2.1KOHMA"
			(at -0.0762 1.254506 180)
			(unlocked yes)
			(layer "B.Fab")
			(hide yes)
			(effects
				(font
					(size 0.7874 0.5842)
					(thickness 0.1524)
				)
				(justify mirror)
			)
		)
		(property "User Part Number" "PARTNUM*"
			(at -0.0762 4.302506 180)
			(unlocked yes)
			(layer "Cmts.User")
			(hide yes)
			(effects
				(font
					(size 0.7874 0.5842)
					(thickness 0.1524)
				)
				(justify mirror)
			)
		)
		(duplicate_pad_numbers_are_jumpers no)
		(fp_line
			(start 1.143 0.5588)
			(end -1.143 0.5588)
			(stroke
				(width 0.1)
				(type default)
			)
			(layer "B.SilkS")
		)
		(fp_line
			(start 1.143 -0.5588)
			(end 1.143 0.5588)
			(stroke
				(width 0.1)
				(type default)
			)
			(layer "B.SilkS")
		)
		(fp_line
			(start -1.143 0.5588)
			(end -1.143 -0.5588)
			(stroke
				(width 0.1)
				(type default)
			)
			(layer "B.SilkS")
		)
		(fp_line
			(start -1.143 -0.5588)
			(end 1.143 -0.5588)
			(stroke
				(width 0.1)
				(type default)
			)
			(layer "B.SilkS")
		)
		(fp_rect
			(start 1.143 -0.5588)
			(end -1.143 0.5588)
			(stroke
				(width 0)
				(type default)
			)
			(fill no)
			(layer "B.CrtYd")
		)
		(fp_line
			(start 0.508 0.3048)
			(end -0.508 0.3048)
			(stroke
				(width 0.1)
				(type default)
			)
			(layer "B.Fab")
		)
		(fp_line
			(start 0.508 -0.3048)
			(end 0.508 0.3048)
			(stroke
				(width 0.1)
				(type default)
			)
			(layer "B.Fab")
		)
		(fp_line
			(start -0.508 0.3048)
			(end -0.508 -0.3048)
			(stroke
				(width 0.1)
				(type default)
			)
			(layer "B.Fab")
		)
		(fp_line
			(start -0.508 -0.3048)
			(end 0.508 -0.3048)
			(stroke
				(width 0.1)
				(type default)
			)
			(layer "B.Fab")
		)
		(pad "1" smd rect
			(at 0.5334 0)
			(size 0.7112 0.6096)
			(layers "B.Cu" "B.Mask" "B.Paste")
			(net "SG")
		)
		(pad "2" smd rect
			(at -0.5334 0)
			(size 0.7112 0.6096)
			(layers "B.Cu" "B.Mask" "B.Paste")
			(net "UNNAMED_515_ISL80101IRAJZDFN10_")
		)
		(zone
			(layer "B.Cu")
			(hatch none 0.5)
			(connect_pads
				(clearance 0)
			)
			(min_thickness 0.25)
			(keepout
				(tracks allowed)
				(vias not_allowed)
				(pads allowed)
				(copperpour not_allowed)
				(footprints allowed)
			)
			(placement
				(enabled no)
				(sheetname "")
			)
			(fill
				(thermal_gap 0.5)
				(thermal_bridge_width 0.5)
				(island_removal_mode 0)
			)
			(polygon
				(pts
					(xy 137.7188 -17.2212) (xy 137.8712 -17.2212) (xy 137.8712 -17.8308) (xy 137.7188 -17.8308)
				)
			)
		)
	)
	(footprint ""
		(layer "B.Cu")
		(at 17.653 -37.973 180)
		(property "Reference" "R59"
			(at 0 -2.32537 0)
			(unlocked yes)
			(layer "B.SilkS")
			(effects
				(font
					(size 0.7874 0.5842)
					(thickness 0.1524)
				)
				(justify mirror)
			)
		)
		(property "Value" "VAL*"
			(at -0.02032 2.13233 180)
			(unlocked yes)
			(layer "B.Fab")
			(hide yes)
			(effects
				(font
					(size 0.7874 0.5842)
					(thickness 0.1524)
				)
				(justify mirror)
			)
		)
		(property "Device Type" "RESISTOR-G155-133R0-01,33OHM,1%"
			(at -0.008382 1.210564 180)
			(unlocked yes)
			(layer "B.Fab")
			(hide yes)
			(effects
				(font
					(size 0.7874 0.5842)
					(thickness 0.1524)
				)
				(justify mirror)
			)
		)
		(property "User Part Number" "PARTNUM*"
			(at -0.02032 4.024884 180)
			(unlocked yes)
			(layer "Cmts.User")
			(hide yes)
			(effects
				(font
					(size 0.7874 0.5842)
					(thickness 0.1524)
				)
				(justify mirror)
			)
		)
		(property "Tolerance" "TOL*"
			(at -0.044704 3.05435 180)
			(unlocked yes)
			(layer "Cmts.User")
			(hide yes)
			(effects
				(font
					(size 0.7874 0.5842)
					(thickness 0.1524)
				)
				(justify mirror)
			)
		)
		(duplicate_pad_numbers_are_jumpers no)
		(fp_line
			(start 1.143 0.5588)
			(end -1.143 0.5588)
			(stroke
				(width 0.1)
				(type default)
			)
			(layer "B.SilkS")
		)
		(fp_line
			(start 1.143 -0.5588)
			(end 1.143 0.5588)
			(stroke
				(width 0.1)
				(type default)
			)
			(layer "B.SilkS")
		)
		(fp_line
			(start -1.143 0.5588)
			(end -1.143 -0.5588)
			(stroke
				(width 0.1)
				(type default)
			)
			(layer "B.SilkS")
		)
		(fp_line
			(start -1.143 -0.5588)
			(end 1.143 -0.5588)
			(stroke
				(width 0.1)
				(type default)
			)
			(layer "B.SilkS")
		)
		(fp_rect
			(start 1.143 0.5588)
			(end -1.143 -0.5588)
			(stroke
				(width 0)
				(type default)
			)
			(fill no)
			(layer "B.CrtYd")
		)
		(fp_line
			(start 0.508 0.3048)
			(end -0.508 0.3048)
			(stroke
				(width 0.1)
				(type default)
			)
			(layer "B.Fab")
		)
		(fp_line
			(start 0.508 -0.3048)
			(end 0.508 0.3048)
			(stroke
				(width 0.1)
				(type default)
			)
			(layer "B.Fab")
		)
		(fp_line
			(start -0.508 0.3048)
			(end -0.508 -0.3048)
			(stroke
				(width 0.1)
				(type default)
			)
			(layer "B.Fab")
		)
		(fp_line
			(start -0.508 -0.3048)
			(end 0.508 -0.3048)
			(stroke
				(width 0.1)
				(type default)
			)
			(layer "B.Fab")
		)
		(pad "1" smd rect
			(at 0.5334 0)
			(size 0.7112 0.6096)
			(layers "B.Cu" "B.Mask" "B.Paste")
			(net "UNNAMED_5_CONNHDR2X2MSSMT_I12_1")
		)
		(pad "2" smd rect
			(at -0.5334 0)
			(size 0.7112 0.6096)
			(layers "B.Cu" "B.Mask" "B.Paste")
			(net "R_PCA9546_I2C_SCL")
		)
		(zone
			(layer "B.Cu")
			(hatch none 0.5)
			(connect_pads
				(clearance 0)
			)
			(min_thickness 0.25)
			(keepout
				(tracks allowed)
				(vias not_allowed)
				(pads allowed)
				(copperpour not_allowed)
				(footprints allowed)
			)
			(placement
				(enabled no)
				(sheetname "")
			)
			(fill
				(thermal_gap 0.5)
				(thermal_bridge_width 0.5)
				(island_removal_mode 0)
			)
			(polygon
				(pts
					(xy 17.5768 -38.2778) (xy 17.5768 -37.6682) (xy 17.7292 -37.6682) (xy 17.7292 -38.2778)
				)
			)
		)
	)
	(footprint ""
		(layer "B.Cu")
		(at 77.3938 -81.534 180)
		(property "Reference" "R61"
			(at 2.9718 -0.03937 0)
			(unlocked yes)
			(layer "B.SilkS")
			(effects
				(font
					(size 0.7874 0.5842)
					(thickness 0.1524)
				)
				(justify mirror)
			)
		)
		(property "Value" "VAL*"
			(at -0.02032 2.13233 180)
			(unlocked yes)
			(layer "B.Fab")
			(hide yes)
			(effects
				(font
					(size 0.7874 0.5842)
					(thickness 0.1524)
				)
				(justify mirror)
			)
		)
		(property "Tolerance" "TOL*"
			(at -0.044704 3.05435 180)
			(unlocked yes)
			(layer "Cmts.User")
			(hide yes)
			(effects
				(font
					(size 0.7874 0.5842)
					(thickness 0.1524)
				)
				(justify mirror)
			)
		)
		(property "User Part Number" "PARTNUM*"
			(at -0.02032 4.024884 180)
			(unlocked yes)
			(layer "Cmts.User")
			(hide yes)
			(effects
				(font
					(size 0.7874 0.5842)
					(thickness 0.1524)
				)
				(justify mirror)
			)
		)
		(property "Device Type" "RESISTOR-G155-100R0-J0,0OHM,-"
			(at -0.008382 1.210564 180)
			(unlocked yes)
			(layer "B.Fab")
			(hide yes)
			(effects
				(font
					(size 0.7874 0.5842)
					(thickness 0.1524)
				)
				(justify mirror)
			)
		)
		(duplicate_pad_numbers_are_jumpers no)
		(fp_line
			(start 1.143 0.5588)
			(end -1.143 0.5588)
			(stroke
				(width 0.1)
				(type default)
			)
			(layer "B.SilkS")
		)
		(fp_line
			(start 1.143 -0.5588)
			(end 1.143 0.5588)
			(stroke
				(width 0.1)
				(type default)
			)
			(layer "B.SilkS")
		)
		(fp_line
			(start -1.143 0.5588)
			(end -1.143 -0.5588)
			(stroke
				(width 0.1)
				(type default)
			)
			(layer "B.SilkS")
		)
		(fp_line
			(start -1.143 -0.5588)
			(end 1.143 -0.5588)
			(stroke
				(width 0.1)
				(type default)
			)
			(layer "B.SilkS")
		)
		(fp_poly
			(pts
				(xy 1.143 0.5588) (xy -1.143 0.5588) (xy -1.143 -0.5588) (xy 1.143 -0.5588)
			)
			(stroke
				(width 0)
				(type default)
			)
			(fill no)
			(layer "B.CrtYd")
		)
		(fp_line
			(start 0.508 0.3048)
			(end -0.508 0.3048)
			(stroke
				(width 0.1)
				(type default)
			)
			(layer "B.Fab")
		)
		(fp_line
			(start 0.508 -0.3048)
			(end 0.508 0.3048)
			(stroke
				(width 0.1)
				(type default)
			)
			(layer "B.Fab")
		)
		(fp_line
			(start -0.508 0.3048)
			(end -0.508 -0.3048)
			(stroke
				(width 0.1)
				(type default)
			)
			(layer "B.Fab")
		)
		(fp_line
			(start -0.508 -0.3048)
			(end 0.508 -0.3048)
			(stroke
				(width 0.1)
				(type default)
			)
			(layer "B.Fab")
		)
		(pad "1" smd rect
			(at 0.5334 0)
			(size 0.7112 0.6096)
			(layers "B.Cu" "B.Mask" "B.Paste")
			(net "VDD_PCA9546A")
		)
		(pad "2" smd rect
			(at -0.5334 0)
			(size 0.7112 0.6096)
			(layers "B.Cu" "B.Mask" "B.Paste")
			(net "XP2R5V_FPGA")
		)
		(zone
			(layer "B.Cu")
			(hatch none 0.5)
			(connect_pads
				(clearance 0)
			)
			(min_thickness 0.25)
			(keepout
				(tracks not_allowed)
				(vias allowed)
				(pads allowed)
				(copperpour not_allowed)
				(footprints allowed)
			)
			(placement
				(enabled no)
				(sheetname "")
			)
			(fill
				(thermal_gap 0.5)
				(thermal_bridge_width 0.5)
				(island_removal_mode 0)
			)
			(polygon
				(pts
					(xy 77.3176 -81.8388) (xy 77.3176 -81.2292) (xy 77.47 -81.2292) (xy 77.47 -81.8388)
				)
			)
		)
		(zone
			(layer "B.Cu")
			(hatch none 0.5)
			(connect_pads
				(clearance 0)
			)
			(min_thickness 0.25)
			(keepout
				(tracks allowed)
				(vias not_allowed)
				(pads allowed)
				(copperpour not_allowed)
				(footprints allowed)
			)
			(placement
				(enabled no)
				(sheetname "")
			)
			(fill
				(thermal_gap 0.5)
				(thermal_bridge_width 0.5)
				(island_removal_mode 0)
			)
			(polygon
				(pts
					(xy 77.3176 -81.8388) (xy 77.3176 -81.2292) (xy 77.47 -81.2292) (xy 77.47 -81.8388)
				)
			)
		)
	)
	(footprint ""
		(layer "B.Cu")
		(at 22.0472 -18.034 180)
		(property "Reference" "R24"
			(at -2.3368 -0.03937 0)
			(unlocked yes)
			(layer "B.SilkS")
			(effects
				(font
					(size 0.7874 0.5842)
					(thickness 0.1524)
				)
				(justify mirror)
			)
		)
		(property "Value" "VAL*"
			(at -0.02032 2.13233 180)
			(unlocked yes)
			(layer "B.Fab")
			(hide yes)
			(effects
				(font
					(size 0.7874 0.5842)
					(thickness 0.1524)
				)
				(justify mirror)
			)
		)
		(property "Device Type" "RESISTOR-G155-14701-01,4.7KOHMA"
			(at -0.008382 1.210564 180)
			(unlocked yes)
			(layer "B.Fab")
			(hide yes)
			(effects
				(font
					(size 0.7874 0.5842)
					(thickness 0.1524)
				)
				(justify mirror)
			)
		)
		(property "User Part Number" "PARTNUM*"
			(at -0.02032 4.024884 180)
			(unlocked yes)
			(layer "Cmts.User")
			(hide yes)
			(effects
				(font
					(size 0.7874 0.5842)
					(thickness 0.1524)
				)
				(justify mirror)
			)
		)
		(property "Tolerance" "TOL*"
			(at -0.044704 3.05435 180)
			(unlocked yes)
			(layer "Cmts.User")
			(hide yes)
			(effects
				(font
					(size 0.7874 0.5842)
					(thickness 0.1524)
				)
				(justify mirror)
			)
		)
		(duplicate_pad_numbers_are_jumpers no)
		(fp_line
			(start 1.143 0.5588)
			(end -1.143 0.5588)
			(stroke
				(width 0.1)
				(type default)
			)
			(layer "B.SilkS")
		)
		(fp_line
			(start 1.143 -0.5588)
			(end 1.143 0.5588)
			(stroke
				(width 0.1)
				(type default)
			)
			(layer "B.SilkS")
		)
		(fp_line
			(start -1.143 0.5588)
			(end -1.143 -0.5588)
			(stroke
				(width 0.1)
				(type default)
			)
			(layer "B.SilkS")
		)
		(fp_line
			(start -1.143 -0.5588)
			(end 1.143 -0.5588)
			(stroke
				(width 0.1)
				(type default)
			)
			(layer "B.SilkS")
		)
		(fp_rect
			(start -1.143 0.5588)
			(end 1.143 -0.5588)
			(stroke
				(width 0)
				(type default)
			)
			(fill no)
			(layer "B.CrtYd")
		)
		(fp_line
			(start 0.508 0.3048)
			(end -0.508 0.3048)
			(stroke
				(width 0.1)
				(type default)
			)
			(layer "B.Fab")
		)
		(fp_line
			(start 0.508 -0.3048)
			(end 0.508 0.3048)
			(stroke
				(width 0.1)
				(type default)
			)
			(layer "B.Fab")
		)
		(fp_line
			(start -0.508 0.3048)
			(end -0.508 -0.3048)
			(stroke
				(width 0.1)
				(type default)
			)
			(layer "B.Fab")
		)
		(fp_line
			(start -0.508 -0.3048)
			(end 0.508 -0.3048)
			(stroke
				(width 0.1)
				(type default)
			)
			(layer "B.Fab")
		)
		(pad "1" smd rect
			(at 0.5334 0)
			(size 0.7112 0.6096)
			(layers "B.Cu" "B.Mask" "B.Paste")
			(net "SEC_EEPROM_WP")
		)
		(pad "2" smd rect
			(at -0.5334 0)
			(size 0.7112 0.6096)
			(layers "B.Cu" "B.Mask" "B.Paste")
			(net "SG")
		)
		(zone
			(layer "B.Cu")
			(hatch none 0.5)
			(connect_pads
				(clearance 0)
			)
			(min_thickness 0.25)
			(keepout
				(tracks allowed)
				(vias not_allowed)
				(pads allowed)
				(copperpour not_allowed)
				(footprints allowed)
			)
			(placement
				(enabled no)
				(sheetname "")
			)
			(fill
				(thermal_gap 0.5)
				(thermal_bridge_width 0.5)
				(island_removal_mode 0)
			)
			(polygon
				(pts
					(xy 22.1234 -18.3388) (xy 21.971 -18.3388) (xy 21.971 -17.7292) (xy 22.1234 -17.7292)
				)
			)
		)
	)
	(footprint ""
		(layer "B.Cu")
		(at 137.414 -57.785 180)
		(property "Reference" "R243"
			(at 0.381 -1.18237 0)
			(unlocked yes)
			(layer "B.SilkS")
			(effects
				(font
					(size 0.7874 0.5842)
					(thickness 0.1524)
				)
				(justify mirror)
			)
		)
		(property "Value" "VAL*"
			(at -0.02032 2.13233 180)
			(unlocked yes)
			(layer "B.Fab")
			(hide yes)
			(effects
				(font
					(size 0.7874 0.5842)
					(thickness 0.1524)
				)
				(justify mirror)
			)
		)
		(property "Device Type" "RESISTOR-G155-14701-01,4.7KOHMA"
			(at -0.008382 1.210564 180)
			(unlocked yes)
			(layer "B.Fab")
			(hide yes)
			(effects
				(font
					(size 0.7874 0.5842)
					(thickness 0.1524)
				)
				(justify mirror)
			)
		)
		(property "User Part Number" "PARTNUM*"
			(at -0.02032 4.024884 180)
			(unlocked yes)
			(layer "Cmts.User")
			(hide yes)
			(effects
				(font
					(size 0.7874 0.5842)
					(thickness 0.1524)
				)
				(justify mirror)
			)
		)
		(property "Tolerance" "TOL*"
			(at -0.044704 3.05435 180)
			(unlocked yes)
			(layer "Cmts.User")
			(hide yes)
			(effects
				(font
					(size 0.7874 0.5842)
					(thickness 0.1524)
				)
				(justify mirror)
			)
		)
		(duplicate_pad_numbers_are_jumpers no)
		(fp_line
			(start 1.143 0.5588)
			(end -1.143 0.5588)
			(stroke
				(width 0.1)
				(type default)
			)
			(layer "B.SilkS")
		)
		(fp_line
			(start 1.143 -0.5588)
			(end 1.143 0.5588)
			(stroke
				(width 0.1)
				(type default)
			)
			(layer "B.SilkS")
		)
		(fp_line
			(start -1.143 0.5588)
			(end -1.143 -0.5588)
			(stroke
				(width 0.1)
				(type default)
			)
			(layer "B.SilkS")
		)
		(fp_line
			(start -1.143 -0.5588)
			(end 1.143 -0.5588)
			(stroke
				(width 0.1)
				(type default)
			)
			(layer "B.SilkS")
		)
		(fp_rect
			(start -1.143 -0.5588)
			(end 1.143 0.5588)
			(stroke
				(width 0)
				(type default)
			)
			(fill no)
			(layer "B.CrtYd")
		)
		(fp_line
			(start 0.508 0.3048)
			(end -0.508 0.3048)
			(stroke
				(width 0.1)
				(type default)
			)
			(layer "B.Fab")
		)
		(fp_line
			(start 0.508 -0.3048)
			(end 0.508 0.3048)
			(stroke
				(width 0.1)
				(type default)
			)
			(layer "B.Fab")
		)
		(fp_line
			(start -0.508 0.3048)
			(end -0.508 -0.3048)
			(stroke
				(width 0.1)
				(type default)
			)
			(layer "B.Fab")
		)
		(fp_line
			(start -0.508 -0.3048)
			(end 0.508 -0.3048)
			(stroke
				(width 0.1)
				(type default)
			)
			(layer "B.Fab")
		)
		(pad "1" smd rect
			(at 0.5334 0)
			(size 0.7112 0.6096)
			(layers "B.Cu" "B.Mask" "B.Paste")
			(net "XP3R3V")
		)
		(pad "2" smd rect
			(at -0.5334 0)
			(size 0.7112 0.6096)
			(layers "B.Cu" "B.Mask" "B.Paste")
			(net "XP1R0V_PG")
		)
		(zone
			(layer "B.Cu")
			(hatch none 0.5)
			(connect_pads
				(clearance 0)
			)
			(min_thickness 0.25)
			(keepout
				(tracks allowed)
				(vias not_allowed)
				(pads allowed)
				(copperpour not_allowed)
				(footprints allowed)
			)
			(placement
				(enabled no)
				(sheetname "")
			)
			(fill
				(thermal_gap 0.5)
				(thermal_bridge_width 0.5)
				(island_removal_mode 0)
			)
			(polygon
				(pts
					(xy 137.4902 -57.4802) (xy 137.4902 -58.0898) (xy 137.3378 -58.0898) (xy 137.3378 -57.4802)
				)
			)
		)
	)
	(footprint ""
		(layer "B.Cu")
		(at 139.954 -54.61 90)
		(property "Reference" "R250"
			(at 0.508 1.10363 270)
			(unlocked yes)
			(layer "B.SilkS")
			(effects
				(font
					(size 0.7874 0.5842)
					(thickness 0.1524)
				)
				(justify mirror)
			)
		)
		(property "Value" "VAL*"
			(at -0.02032 2.13233 90)
			(unlocked yes)
			(layer "B.Fab")
			(hide yes)
			(effects
				(font
					(size 0.7874 0.5842)
					(thickness 0.1524)
				)
				(justify mirror)
			)
		)
		(property "Tolerance" "TOL*"
			(at -0.044704 3.05435 90)
			(unlocked yes)
			(layer "Cmts.User")
			(hide yes)
			(effects
				(font
					(size 0.7874 0.5842)
					(thickness 0.1524)
				)
				(justify mirror)
			)
		)
		(property "User Part Number" "PARTNUM*"
			(at -0.02032 4.024884 90)
			(unlocked yes)
			(layer "Cmts.User")
			(hide yes)
			(effects
				(font
					(size 0.7874 0.5842)
					(thickness 0.1524)
				)
				(justify mirror)
			)
		)
		(property "Device Type" "RESISTOR-G155-100R0-J0,0OHM,-"
			(at -0.008382 1.210564 90)
			(unlocked yes)
			(layer "B.Fab")
			(hide yes)
			(effects
				(font
					(size 0.7874 0.5842)
					(thickness 0.1524)
				)
				(justify mirror)
			)
		)
		(duplicate_pad_numbers_are_jumpers no)
		(fp_line
			(start 1.143 -0.5588)
			(end 1.143 0.5588)
			(stroke
				(width 0.1)
				(type default)
			)
			(layer "B.SilkS")
		)
		(fp_line
			(start -1.143 -0.5588)
			(end 1.143 -0.5588)
			(stroke
				(width 0.1)
				(type default)
			)
			(layer "B.SilkS")
		)
		(fp_line
			(start 1.143 0.5588)
			(end -1.143 0.5588)
			(stroke
				(width 0.1)
				(type default)
			)
			(layer "B.SilkS")
		)
		(fp_line
			(start -1.143 0.5588)
			(end -1.143 -0.5588)
			(stroke
				(width 0.1)
				(type default)
			)
			(layer "B.SilkS")
		)
		(fp_poly
			(pts
				(xy 1.143 0.5588) (xy -1.143 0.5588) (xy -1.143 -0.5588) (xy 1.143 -0.5588)
			)
			(stroke
				(width 0)
				(type default)
			)
			(fill no)
			(layer "B.CrtYd")
		)
		(fp_line
			(start 0.508 -0.3048)
			(end 0.508 0.3048)
			(stroke
				(width 0.1)
				(type default)
			)
			(layer "B.Fab")
		)
		(fp_line
			(start -0.508 -0.3048)
			(end 0.508 -0.3048)
			(stroke
				(width 0.1)
				(type default)
			)
			(layer "B.Fab")
		)
		(fp_line
			(start 0.508 0.3048)
			(end -0.508 0.3048)
			(stroke
				(width 0.1)
				(type default)
			)
			(layer "B.Fab")
		)
		(fp_line
			(start -0.508 0.3048)
			(end -0.508 -0.3048)
			(stroke
				(width 0.1)
				(type default)
			)
			(layer "B.Fab")
		)
		(pad "1" smd rect
			(at 0.5334 0 270)
			(size 0.7112 0.6096)
			(layers "B.Cu" "B.Mask" "B.Paste")
			(net "XP1R0V_BT")
		)
		(pad "2" smd rect
			(at -0.5334 0 270)
			(size 0.7112 0.6096)
			(layers "B.Cu" "B.Mask" "B.Paste")
			(net "UNNAMED_523_CAPACITOR_I24_1")
		)
		(zone
			(layer "B.Cu")
			(hatch none 0.5)
			(connect_pads
				(clearance 0)
			)
			(min_thickness 0.25)
			(keepout
				(tracks allowed)
				(vias not_allowed)
				(pads allowed)
				(copperpour not_allowed)
				(footprints allowed)
			)
			(placement
				(enabled no)
				(sheetname "")
			)
			(fill
				(thermal_gap 0.5)
				(thermal_bridge_width 0.5)
				(island_removal_mode 0)
			)
			(polygon
				(pts
					(xy 140.2588 -54.6862) (xy 139.6492 -54.6862) (xy 139.6492 -54.5338) (xy 140.2588 -54.5338)
				)
			)
		)
		(zone
			(layer "B.Cu")
			(hatch none 0.5)
			(connect_pads
				(clearance 0)
			)
			(min_thickness 0.25)
			(keepout
				(tracks not_allowed)
				(vias allowed)
				(pads allowed)
				(copperpour not_allowed)
				(footprints allowed)
			)
			(placement
				(enabled no)
				(sheetname "")
			)
			(fill
				(thermal_gap 0.5)
				(thermal_bridge_width 0.5)
				(island_removal_mode 0)
			)
			(polygon
				(pts
					(xy 140.2588 -54.6862) (xy 139.6492 -54.6862) (xy 139.6492 -54.5338) (xy 140.2588 -54.5338)
				)
			)
		)
	)
	(footprint ""
		(layer "B.Cu")
		(at 117.346984 -32.822896 180)
		(property "Reference" "R275"
			(at -0.509016 -1.231646 0)
			(unlocked yes)
			(layer "B.SilkS")
			(effects
				(font
					(size 0.635 0.4064)
					(thickness 0.1524)
				)
				(justify mirror)
			)
		)
		(property "Value" "VAL*"
			(at 0 3.718306 180)
			(unlocked yes)
			(layer "B.Fab")
			(hide yes)
			(effects
				(font
					(size 0.7874 0.5842)
					(thickness 0.127)
				)
				(justify mirror)
			)
		)
		(property "Tolerance" "TOL*"
			(at 0 4.861306 180)
			(unlocked yes)
			(layer "Cmts.User")
			(hide yes)
			(effects
				(font
					(size 0.7874 0.5842)
					(thickness 0.127)
				)
				(justify mirror)
			)
		)
		(property "User Part Number" "PARTNUM*"
			(at 0 2.575306 180)
			(unlocked yes)
			(layer "Cmts.User")
			(hide yes)
			(effects
				(font
					(size 0.7874 0.5842)
					(thickness 0.127)
				)
				(justify mirror)
			)
		)
		(property "Device Type" "RESISTOR-G155-11000-01,100OHM,A"
			(at 0 1.432306 180)
			(unlocked yes)
			(layer "B.Fab")
			(hide yes)
			(effects
				(font
					(size 0.7874 0.5842)
					(thickness 0.127)
				)
				(justify mirror)
			)
		)
		(duplicate_pad_numbers_are_jumpers no)
		(fp_line
			(start 0.970026 0.4699)
			(end 0.970026 -0.4699)
			(stroke
				(width 0.1)
				(type default)
			)
			(layer "B.SilkS")
		)
		(fp_line
			(start 0.970026 -0.4699)
			(end -0.970026 -0.4699)
			(stroke
				(width 0.1)
				(type default)
			)
			(layer "B.SilkS")
		)
		(fp_line
			(start -0.970026 0.4699)
			(end 0.970026 0.4699)
			(stroke
				(width 0.1)
				(type default)
			)
			(layer "B.SilkS")
		)
		(fp_line
			(start -0.970026 -0.4699)
			(end -0.970026 0.4699)
			(stroke
				(width 0.1)
				(type default)
			)
			(layer "B.SilkS")
		)
		(fp_poly
			(pts
				(xy 0.970026 0.4699) (xy -0.970026 0.4699) (xy -0.970026 -0.4699) (xy 0.970026 -0.4699)
			)
			(stroke
				(width 0)
				(type default)
			)
			(fill no)
			(layer "B.CrtYd")
		)
		(fp_line
			(start 0.508 0.3048)
			(end 0.508 -0.3048)
			(stroke
				(width 0.1)
				(type default)
			)
			(layer "B.Fab")
		)
		(fp_line
			(start 0.508 -0.3048)
			(end -0.508 -0.3048)
			(stroke
				(width 0.1)
				(type default)
			)
			(layer "B.Fab")
		)
		(fp_line
			(start -0.508 0.3048)
			(end 0.508 0.3048)
			(stroke
				(width 0.1)
				(type default)
			)
			(layer "B.Fab")
		)
		(fp_line
			(start -0.508 -0.3048)
			(end -0.508 0.3048)
			(stroke
				(width 0.1)
				(type default)
			)
			(layer "B.Fab")
		)
		(pad "1" smd circle
			(at 0.500126 0)
			(size 0.635 0.635)
			(layers "B.Cu" "B.Mask" "B.Paste")
			(net "FPGA_IN_MAC_PPS_OUTP")
		)
		(pad "2" smd circle
			(at -0.500126 0)
			(size 0.635 0.635)
			(layers "B.Cu" "B.Mask" "B.Paste")
			(net "FPGA_IN_MAC_PPS_OUTN")
		)
	)
	(footprint ""
		(layer "B.Cu")
		(at 140.335 -77.851)
		(property "Reference" "R41"
			(at 0.381 -2.11963 0)
			(unlocked yes)
			(layer "B.SilkS")
			(effects
				(font
					(size 0.7874 0.5842)
					(thickness 0.1524)
				)
				(justify mirror)
			)
		)
		(property "Value" "VAL*"
			(at -0.02032 2.13233 0)
			(unlocked yes)
			(layer "B.Fab")
			(hide yes)
			(effects
				(font
					(size 0.7874 0.5842)
					(thickness 0.1524)
				)
				(justify mirror)
			)
		)
		(property "Tolerance" "TOL*"
			(at -0.044704 3.05435 0)
			(unlocked yes)
			(layer "Cmts.User")
			(hide yes)
			(effects
				(font
					(size 0.7874 0.5842)
					(thickness 0.1524)
				)
				(justify mirror)
			)
		)
		(property "User Part Number" "PARTNUM*"
			(at -0.02032 4.024884 0)
			(unlocked yes)
			(layer "Cmts.User")
			(hide yes)
			(effects
				(font
					(size 0.7874 0.5842)
					(thickness 0.1524)
				)
				(justify mirror)
			)
		)
		(property "Device Type" "RESISTOR-G155-100R0-J0,0OHM,-"
			(at -0.008382 1.210564 0)
			(unlocked yes)
			(layer "B.Fab")
			(hide yes)
			(effects
				(font
					(size 0.7874 0.5842)
					(thickness 0.1524)
				)
				(justify mirror)
			)
		)
		(duplicate_pad_numbers_are_jumpers no)
		(fp_line
			(start -1.143 -0.5588)
			(end 1.143 -0.5588)
			(stroke
				(width 0.1)
				(type default)
			)
			(layer "B.SilkS")
		)
		(fp_line
			(start -1.143 0.5588)
			(end -1.143 -0.5588)
			(stroke
				(width 0.1)
				(type default)
			)
			(layer "B.SilkS")
		)
		(fp_line
			(start 1.143 -0.5588)
			(end 1.143 0.5588)
			(stroke
				(width 0.1)
				(type default)
			)
			(layer "B.SilkS")
		)
		(fp_line
			(start 1.143 0.5588)
			(end -1.143 0.5588)
			(stroke
				(width 0.1)
				(type default)
			)
			(layer "B.SilkS")
		)
		(fp_rect
			(start 1.143 0.5588)
			(end -1.143 -0.5588)
			(stroke
				(width 0)
				(type default)
			)
			(fill no)
			(layer "B.CrtYd")
		)
		(fp_line
			(start -0.508 -0.3048)
			(end 0.508 -0.3048)
			(stroke
				(width 0.1)
				(type default)
			)
			(layer "B.Fab")
		)
		(fp_line
			(start -0.508 0.3048)
			(end -0.508 -0.3048)
			(stroke
				(width 0.1)
				(type default)
			)
			(layer "B.Fab")
		)
		(fp_line
			(start 0.508 -0.3048)
			(end 0.508 0.3048)
			(stroke
				(width 0.1)
				(type default)
			)
			(layer "B.Fab")
		)
		(fp_line
			(start 0.508 0.3048)
			(end -0.508 0.3048)
			(stroke
				(width 0.1)
				(type default)
			)
			(layer "B.Fab")
		)
		(pad "1" smd rect
			(at 0.5334 0 180)
			(size 0.7112 0.6096)
			(layers "B.Cu" "B.Mask" "B.Paste")
			(net "PCIE_CONN_TDI")
		)
		(pad "2" smd rect
			(at -0.5334 0 180)
			(size 0.7112 0.6096)
			(layers "B.Cu" "B.Mask" "B.Paste")
			(net "FPGA_TDI")
		)
		(zone
			(layer "B.Cu")
			(hatch none 0.5)
			(connect_pads
				(clearance 0)
			)
			(min_thickness 0.25)
			(keepout
				(tracks allowed)
				(vias not_allowed)
				(pads allowed)
				(copperpour not_allowed)
				(footprints allowed)
			)
			(placement
				(enabled no)
				(sheetname "")
			)
			(fill
				(thermal_gap 0.5)
				(thermal_bridge_width 0.5)
				(island_removal_mode 0)
			)
			(polygon
				(pts
					(xy 140.4112 -77.5462) (xy 140.4112 -78.1558) (xy 140.2588 -78.1558) (xy 140.2588 -77.5462)
				)
			)
		)
	)
	(footprint ""
		(layer "B.Cu")
		(at 62.514988 -15.367 -90)
		(property "Reference" "C24"
			(at 2.032 0.062738 270)
			(unlocked yes)
			(layer "B.SilkS")
			(effects
				(font
					(size 0.635 0.4064)
					(thickness 0.1524)
				)
				(justify mirror)
			)
		)
		(property "Value" "VAL*"
			(at -0.0762 2.067306 270)
			(unlocked yes)
			(layer "B.Fab")
			(hide yes)
			(effects
				(font
					(size 0.7874 0.5842)
					(thickness 0.1524)
				)
				(justify mirror)
			)
		)
		(property "Tolerance" "TOL*"
			(at -0.0762 3.032506 270)
			(unlocked yes)
			(layer "Cmts.User")
			(hide yes)
			(effects
				(font
					(size 0.7874 0.5842)
					(thickness 0.1524)
				)
				(justify mirror)
			)
		)
		(property "User Part Number" "PARTNUM*"
			(at -0.1016 4.023106 270)
			(unlocked yes)
			(layer "Cmts.User")
			(hide yes)
			(effects
				(font
					(size 0.7874 0.5842)
					(thickness 0.1524)
				)
				(justify mirror)
			)
		)
		(property "Device Type" "CAPACITOR-G105-0B104-CK,0.1UF,A"
			(at -0.0508 1.127506 270)
			(unlocked yes)
			(layer "B.Fab")
			(hide yes)
			(effects
				(font
					(size 0.7874 0.5842)
					(thickness 0.1524)
				)
				(justify mirror)
			)
		)
		(duplicate_pad_numbers_are_jumpers no)
		(fp_line
			(start -1.143 0.5588)
			(end -1.143 -0.5588)
			(stroke
				(width 0.1)
				(type default)
			)
			(layer "B.SilkS")
		)
		(fp_line
			(start 1.143 0.5588)
			(end -1.143 0.5588)
			(stroke
				(width 0.1)
				(type default)
			)
			(layer "B.SilkS")
		)
		(fp_line
			(start -1.143 -0.5588)
			(end 1.143 -0.5588)
			(stroke
				(width 0.1)
				(type default)
			)
			(layer "B.SilkS")
		)
		(fp_line
			(start 1.143 -0.5588)
			(end 1.143 0.5588)
			(stroke
				(width 0.1)
				(type default)
			)
			(layer "B.SilkS")
		)
		(fp_rect
			(start 1.143 0.5588)
			(end -1.143 -0.5588)
			(stroke
				(width 0)
				(type default)
			)
			(fill no)
			(layer "B.CrtYd")
		)
		(fp_line
			(start -0.508 0.3048)
			(end -0.508 -0.3048)
			(stroke
				(width 0.1)
				(type default)
			)
			(layer "B.Fab")
		)
		(fp_line
			(start 0.508 0.3048)
			(end -0.508 0.3048)
			(stroke
				(width 0.1)
				(type default)
			)
			(layer "B.Fab")
		)
		(fp_line
			(start -0.508 -0.3048)
			(end 0.508 -0.3048)
			(stroke
				(width 0.1)
				(type default)
			)
			(layer "B.Fab")
		)
		(fp_line
			(start 0.508 -0.3048)
			(end 0.508 0.3048)
			(stroke
				(width 0.1)
				(type default)
			)
			(layer "B.Fab")
		)
		(pad "1" smd rect
			(at 0.5334 0 90)
			(size 0.7112 0.6096)
			(layers "B.Cu" "B.Mask" "B.Paste")
			(net "C_CPU_RX_PCIE_MGT0_TXP")
		)
		(pad "2" smd rect
			(at -0.5334 0 90)
			(size 0.7112 0.6096)
			(layers "B.Cu" "B.Mask" "B.Paste")
			(net "CPU_RX_PCIE_MGT0_TXP")
		)
		(zone
			(layer "B.Cu")
			(hatch none 0.5)
			(connect_pads
				(clearance 0)
			)
			(min_thickness 0.25)
			(keepout
				(tracks allowed)
				(vias not_allowed)
				(pads allowed)
				(copperpour not_allowed)
				(footprints allowed)
			)
			(placement
				(enabled no)
				(sheetname "")
			)
			(fill
				(thermal_gap 0.5)
				(thermal_bridge_width 0.5)
				(island_removal_mode 0)
			)
			(polygon
				(pts
					(xy 62.210188 -15.2908) (xy 62.819788 -15.2908) (xy 62.819788 -15.4432) (xy 62.210188 -15.4432)
				)
			)
		)
	)
	(footprint ""
		(layer "B.Cu")
		(at 100.347018 -41.823132 180)
		(property "Reference" "C209"
			(at 42.435018 -1.214882 0)
			(unlocked yes)
			(layer "B.SilkS")
			(effects
				(font
					(size 0.635 0.4064)
					(thickness 0.1524)
				)
				(justify mirror)
			)
		)
		(property "Value" "VAL*"
			(at 0 3.718306 180)
			(unlocked yes)
			(layer "B.Fab")
			(hide yes)
			(effects
				(font
					(size 0.7874 0.5842)
					(thickness 0.127)
				)
				(justify mirror)
			)
		)
		(property "Tolerance" "TOL*"
			(at 0 4.861306 180)
			(unlocked yes)
			(layer "Cmts.User")
			(hide yes)
			(effects
				(font
					(size 0.7874 0.5842)
					(thickness 0.127)
				)
				(justify mirror)
			)
		)
		(property "User Part Number" "PARTNUM*"
			(at 0 2.575306 180)
			(unlocked yes)
			(layer "Cmts.User")
			(hide yes)
			(effects
				(font
					(size 0.7874 0.5842)
					(thickness 0.127)
				)
				(justify mirror)
			)
		)
		(property "Device Type" "CAPACITOR-G105-0B104-CK,0.1UF,A"
			(at 0 1.432306 180)
			(unlocked yes)
			(layer "B.Fab")
			(hide yes)
			(effects
				(font
					(size 0.7874 0.5842)
					(thickness 0.127)
				)
				(justify mirror)
			)
		)
		(duplicate_pad_numbers_are_jumpers no)
		(fp_line
			(start 0.970026 0.4699)
			(end 0.970026 -0.4699)
			(stroke
				(width 0.1)
				(type default)
			)
			(layer "B.SilkS")
		)
		(fp_line
			(start 0.970026 -0.4699)
			(end -0.970026 -0.4699)
			(stroke
				(width 0.1)
				(type default)
			)
			(layer "B.SilkS")
		)
		(fp_line
			(start -0.970026 0.4699)
			(end 0.970026 0.4699)
			(stroke
				(width 0.1)
				(type default)
			)
			(layer "B.SilkS")
		)
		(fp_line
			(start -0.970026 -0.4699)
			(end -0.970026 0.4699)
			(stroke
				(width 0.1)
				(type default)
			)
			(layer "B.SilkS")
		)
		(fp_poly
			(pts
				(xy 0.970026 0.4699) (xy -0.970026 0.4699) (xy -0.970026 -0.4699) (xy 0.970026 -0.4699)
			)
			(stroke
				(width 0)
				(type default)
			)
			(fill no)
			(layer "B.CrtYd")
		)
		(fp_line
			(start 0.508 0.3048)
			(end 0.508 -0.3048)
			(stroke
				(width 0.1)
				(type default)
			)
			(layer "B.Fab")
		)
		(fp_line
			(start 0.508 -0.3048)
			(end -0.508 -0.3048)
			(stroke
				(width 0.1)
				(type default)
			)
			(layer "B.Fab")
		)
		(fp_line
			(start -0.508 0.3048)
			(end 0.508 0.3048)
			(stroke
				(width 0.1)
				(type default)
			)
			(layer "B.Fab")
		)
		(fp_line
			(start -0.508 -0.3048)
			(end -0.508 0.3048)
			(stroke
				(width 0.1)
				(type default)
			)
			(layer "B.Fab")
		)
		(pad "1" smd circle
			(at 0.500126 0)
			(size 0.635 0.635)
			(layers "B.Cu" "B.Mask" "B.Paste")
			(net "FPGA_MGTAVTT")
		)
		(pad "2" smd circle
			(at -0.500126 0)
			(size 0.635 0.635)
			(layers "B.Cu" "B.Mask" "B.Paste")
			(net "SG")
		)
	)
	(footprint ""
		(layer "B.Cu")
		(at 89.408 -34.417 90)
		(property "Reference" "C136"
			(at -3.937 0.10033 270)
			(unlocked yes)
			(layer "B.SilkS")
			(effects
				(font
					(size 0.7874 0.5842)
					(thickness 0.1524)
				)
				(justify mirror)
			)
		)
		(property "Value" "VAL*"
			(at -0.0762 2.067306 90)
			(unlocked yes)
			(layer "B.Fab")
			(hide yes)
			(effects
				(font
					(size 0.7874 0.5842)
					(thickness 0.1524)
				)
				(justify mirror)
			)
		)
		(property "Tolerance" "TOL*"
			(at -0.0762 3.032506 90)
			(unlocked yes)
			(layer "Cmts.User")
			(hide yes)
			(effects
				(font
					(size 0.7874 0.5842)
					(thickness 0.1524)
				)
				(justify mirror)
			)
		)
		(property "User Part Number" "PARTNUM*"
			(at -0.1016 4.023106 90)
			(unlocked yes)
			(layer "Cmts.User")
			(hide yes)
			(effects
				(font
					(size 0.7874 0.5842)
					(thickness 0.1524)
				)
				(justify mirror)
			)
		)
		(property "Device Type" "CAPACITOR-G105-0B104-CK,0.1UF,A"
			(at -0.0508 1.127506 90)
			(unlocked yes)
			(layer "B.Fab")
			(hide yes)
			(effects
				(font
					(size 0.7874 0.5842)
					(thickness 0.1524)
				)
				(justify mirror)
			)
		)
		(duplicate_pad_numbers_are_jumpers no)
		(fp_line
			(start 1.143 -0.5588)
			(end 1.143 0.5588)
			(stroke
				(width 0.1)
				(type default)
			)
			(layer "B.SilkS")
		)
		(fp_line
			(start -1.143 -0.5588)
			(end 1.143 -0.5588)
			(stroke
				(width 0.1)
				(type default)
			)
			(layer "B.SilkS")
		)
		(fp_line
			(start 1.143 0.5588)
			(end -1.143 0.5588)
			(stroke
				(width 0.1)
				(type default)
			)
			(layer "B.SilkS")
		)
		(fp_line
			(start -1.143 0.5588)
			(end -1.143 -0.5588)
			(stroke
				(width 0.1)
				(type default)
			)
			(layer "B.SilkS")
		)
		(fp_rect
			(start 1.143 0.5588)
			(end -1.143 -0.5588)
			(stroke
				(width 0)
				(type default)
			)
			(fill no)
			(layer "B.CrtYd")
		)
		(fp_line
			(start 0.508 -0.3048)
			(end 0.508 0.3048)
			(stroke
				(width 0.1)
				(type default)
			)
			(layer "B.Fab")
		)
		(fp_line
			(start -0.508 -0.3048)
			(end 0.508 -0.3048)
			(stroke
				(width 0.1)
				(type default)
			)
			(layer "B.Fab")
		)
		(fp_line
			(start 0.508 0.3048)
			(end -0.508 0.3048)
			(stroke
				(width 0.1)
				(type default)
			)
			(layer "B.Fab")
		)
		(fp_line
			(start -0.508 0.3048)
			(end -0.508 -0.3048)
			(stroke
				(width 0.1)
				(type default)
			)
			(layer "B.Fab")
		)
		(pad "1" smd rect
			(at 0.5334 0 270)
			(size 0.7112 0.6096)
			(layers "B.Cu" "B.Mask" "B.Paste")
			(net "XP1R2V_FPGA")
		)
		(pad "2" smd rect
			(at -0.5334 0 270)
			(size 0.7112 0.6096)
			(layers "B.Cu" "B.Mask" "B.Paste")
			(net "SG")
		)
		(zone
			(layer "B.Cu")
			(hatch none 0.5)
			(connect_pads
				(clearance 0)
			)
			(min_thickness 0.25)
			(keepout
				(tracks allowed)
				(vias not_allowed)
				(pads allowed)
				(copperpour not_allowed)
				(footprints allowed)
			)
			(placement
				(enabled no)
				(sheetname "")
			)
			(fill
				(thermal_gap 0.5)
				(thermal_bridge_width 0.5)
				(island_removal_mode 0)
			)
			(polygon
				(pts
					(xy 89.7128 -34.4932) (xy 89.1032 -34.4932) (xy 89.1032 -34.3408) (xy 89.7128 -34.3408)
				)
			)
		)
	)
	(footprint ""
		(layer "B.Cu")
		(at 27.559 -91.059 -90)
		(property "Reference" "C98"
			(at -2.794 -0.21463 270)
			(unlocked yes)
			(layer "B.SilkS")
			(effects
				(font
					(size 0.7874 0.5842)
					(thickness 0.1524)
				)
				(justify mirror)
			)
		)
		(property "Value" "VAL*"
			(at -0.02032 2.13233 270)
			(unlocked yes)
			(layer "B.Fab")
			(hide yes)
			(effects
				(font
					(size 0.7874 0.5842)
					(thickness 0.1524)
				)
				(justify mirror)
			)
		)
		(property "Tolerance" "TOL*"
			(at -0.044704 3.05435 270)
			(unlocked yes)
			(layer "Cmts.User")
			(hide yes)
			(effects
				(font
					(size 0.7874 0.5842)
					(thickness 0.1524)
				)
				(justify mirror)
			)
		)
		(property "User Part Number" "PARTNUM*"
			(at -0.02032 4.024884 270)
			(unlocked yes)
			(layer "Cmts.User")
			(hide yes)
			(effects
				(font
					(size 0.7874 0.5842)
					(thickness 0.1524)
				)
				(justify mirror)
			)
		)
		(property "Device Type" "CAPACITOR-G105-0F475-BM,4.7UF,A"
			(at -0.008382 1.210564 270)
			(unlocked yes)
			(layer "B.Fab")
			(hide yes)
			(effects
				(font
					(size 0.7874 0.5842)
					(thickness 0.1524)
				)
				(justify mirror)
			)
		)
		(duplicate_pad_numbers_are_jumpers no)
		(fp_line
			(start -1.143 0.5588)
			(end -1.143 -0.5588)
			(stroke
				(width 0.1)
				(type default)
			)
			(layer "B.SilkS")
		)
		(fp_line
			(start 1.143 0.5588)
			(end -1.143 0.5588)
			(stroke
				(width 0.1)
				(type default)
			)
			(layer "B.SilkS")
		)
		(fp_line
			(start -1.143 -0.5588)
			(end 1.143 -0.5588)
			(stroke
				(width 0.1)
				(type default)
			)
			(layer "B.SilkS")
		)
		(fp_line
			(start 1.143 -0.5588)
			(end 1.143 0.5588)
			(stroke
				(width 0.1)
				(type default)
			)
			(layer "B.SilkS")
		)
		(fp_poly
			(pts
				(xy 1.143 0.5588) (xy -1.143 0.5588) (xy -1.143 -0.5588) (xy 1.143 -0.5588)
			)
			(stroke
				(width 0)
				(type default)
			)
			(fill no)
			(layer "B.CrtYd")
		)
		(fp_line
			(start -0.508 0.3048)
			(end -0.508 -0.3048)
			(stroke
				(width 0.1)
				(type default)
			)
			(layer "B.Fab")
		)
		(fp_line
			(start 0.508 0.3048)
			(end -0.508 0.3048)
			(stroke
				(width 0.1)
				(type default)
			)
			(layer "B.Fab")
		)
		(fp_line
			(start -0.508 -0.3048)
			(end 0.508 -0.3048)
			(stroke
				(width 0.1)
				(type default)
			)
			(layer "B.Fab")
		)
		(fp_line
			(start 0.508 -0.3048)
			(end 0.508 0.3048)
			(stroke
				(width 0.1)
				(type default)
			)
			(layer "B.Fab")
		)
		(pad "1" smd rect
			(at 0.5334 0 90)
			(size 0.7112 0.6096)
			(layers "B.Cu" "B.Mask" "B.Paste")
			(net "XP3R3V_VPLL")
		)
		(pad "2" smd rect
			(at -0.5334 0 90)
			(size 0.7112 0.6096)
			(layers "B.Cu" "B.Mask" "B.Paste")
			(net "SG")
		)
		(zone
			(layer "B.Cu")
			(hatch none 0.5)
			(connect_pads
				(clearance 0)
			)
			(min_thickness 0.25)
			(keepout
				(tracks allowed)
				(vias not_allowed)
				(pads allowed)
				(copperpour not_allowed)
				(footprints allowed)
			)
			(placement
				(enabled no)
				(sheetname "")
			)
			(fill
				(thermal_gap 0.5)
				(thermal_bridge_width 0.5)
				(island_removal_mode 0)
			)
			(polygon
				(pts
					(xy 27.2542 -90.9828) (xy 27.8638 -90.9828) (xy 27.8638 -91.1352) (xy 27.2542 -91.1352)
				)
			)
		)
		(zone
			(layer "B.Cu")
			(hatch none 0.5)
			(connect_pads
				(clearance 0)
			)
			(min_thickness 0.25)
			(keepout
				(tracks not_allowed)
				(vias allowed)
				(pads allowed)
				(copperpour not_allowed)
				(footprints allowed)
			)
			(placement
				(enabled no)
				(sheetname "")
			)
			(fill
				(thermal_gap 0.5)
				(thermal_bridge_width 0.5)
				(island_removal_mode 0)
			)
			(polygon
				(pts
					(xy 27.2542 -90.9828) (xy 27.8638 -90.9828) (xy 27.8638 -91.1352) (xy 27.2542 -91.1352)
				)
			)
		)
	)
	(footprint ""
		(layer "B.Cu")
		(at 124.587 -42.545 180)
		(property "Reference" "R218"
			(at -3.429 -0.16637 0)
			(unlocked yes)
			(layer "B.SilkS")
			(effects
				(font
					(size 0.7874 0.5842)
					(thickness 0.1524)
				)
				(justify mirror)
			)
		)
		(property "Value" "VAL*"
			(at -0.02032 2.13233 180)
			(unlocked yes)
			(layer "B.Fab")
			(hide yes)
			(effects
				(font
					(size 0.7874 0.5842)
					(thickness 0.1524)
				)
				(justify mirror)
			)
		)
		(property "Tolerance" "TOL*"
			(at -0.044704 3.05435 180)
			(unlocked yes)
			(layer "Cmts.User")
			(hide yes)
			(effects
				(font
					(size 0.7874 0.5842)
					(thickness 0.1524)
				)
				(justify mirror)
			)
		)
		(property "User Part Number" "PARTNUM*"
			(at -0.02032 4.024884 180)
			(unlocked yes)
			(layer "Cmts.User")
			(hide yes)
			(effects
				(font
					(size 0.7874 0.5842)
					(thickness 0.1524)
				)
				(justify mirror)
			)
		)
		(property "Device Type" "RESISTOR-G155-11000-01,100OHM,A"
			(at -0.008382 1.210564 180)
			(unlocked yes)
			(layer "B.Fab")
			(hide yes)
			(effects
				(font
					(size 0.7874 0.5842)
					(thickness 0.1524)
				)
				(justify mirror)
			)
		)
		(duplicate_pad_numbers_are_jumpers no)
		(fp_line
			(start 1.143 0.5588)
			(end -1.143 0.5588)
			(stroke
				(width 0.1)
				(type default)
			)
			(layer "B.SilkS")
		)
		(fp_line
			(start 1.143 -0.5588)
			(end 1.143 0.5588)
			(stroke
				(width 0.1)
				(type default)
			)
			(layer "B.SilkS")
		)
		(fp_line
			(start -1.143 0.5588)
			(end -1.143 -0.5588)
			(stroke
				(width 0.1)
				(type default)
			)
			(layer "B.SilkS")
		)
		(fp_line
			(start -1.143 -0.5588)
			(end 1.143 -0.5588)
			(stroke
				(width 0.1)
				(type default)
			)
			(layer "B.SilkS")
		)
		(fp_rect
			(start 1.143 0.5588)
			(end -1.143 -0.5588)
			(stroke
				(width 0)
				(type default)
			)
			(fill no)
			(layer "B.CrtYd")
		)
		(fp_line
			(start 0.508 0.3048)
			(end -0.508 0.3048)
			(stroke
				(width 0.1)
				(type default)
			)
			(layer "B.Fab")
		)
		(fp_line
			(start 0.508 -0.3048)
			(end 0.508 0.3048)
			(stroke
				(width 0.1)
				(type default)
			)
			(layer "B.Fab")
		)
		(fp_line
			(start -0.508 0.3048)
			(end -0.508 -0.3048)
			(stroke
				(width 0.1)
				(type default)
			)
			(layer "B.Fab")
		)
		(fp_line
			(start -0.508 -0.3048)
			(end 0.508 -0.3048)
			(stroke
				(width 0.1)
				(type default)
			)
			(layer "B.Fab")
		)
		(pad "1" smd rect
			(at 0.5334 0)
			(size 0.7112 0.6096)
			(layers "B.Cu" "B.Mask" "B.Paste")
			(net "FPGA_M1")
		)
		(pad "2" smd rect
			(at -0.5334 0)
			(size 0.7112 0.6096)
			(layers "B.Cu" "B.Mask" "B.Paste")
			(net "SG")
		)
		(zone
			(layer "B.Cu")
			(hatch none 0.5)
			(connect_pads
				(clearance 0)
			)
			(min_thickness 0.25)
			(keepout
				(tracks allowed)
				(vias not_allowed)
				(pads allowed)
				(copperpour not_allowed)
				(footprints allowed)
			)
			(placement
				(enabled no)
				(sheetname "")
			)
			(fill
				(thermal_gap 0.5)
				(thermal_bridge_width 0.5)
				(island_removal_mode 0)
			)
			(polygon
				(pts
					(xy 124.5108 -42.8498) (xy 124.5108 -42.2402) (xy 124.6632 -42.2402) (xy 124.6632 -42.8498)
				)
			)
		)
	)
	(footprint ""
		(layer "B.Cu")
		(at 155.956 -107.696 90)
		(property "Reference" "R280"
			(at 0.381 1.23063 270)
			(unlocked yes)
			(layer "B.SilkS")
			(effects
				(font
					(size 0.7874 0.5842)
					(thickness 0.1524)
				)
				(justify mirror)
			)
		)
		(property "Value" "VAL*"
			(at -0.02032 2.13233 90)
			(unlocked yes)
			(layer "B.Fab")
			(hide yes)
			(effects
				(font
					(size 0.7874 0.5842)
					(thickness 0.1524)
				)
				(justify mirror)
			)
		)
		(property "Tolerance" "TOL*"
			(at -0.044704 3.05435 90)
			(unlocked yes)
			(layer "Cmts.User")
			(hide yes)
			(effects
				(font
					(size 0.7874 0.5842)
					(thickness 0.1524)
				)
				(justify mirror)
			)
		)
		(property "User Part Number" "PARTNUM*"
			(at -0.02032 4.024884 90)
			(unlocked yes)
			(layer "Cmts.User")
			(hide yes)
			(effects
				(font
					(size 0.7874 0.5842)
					(thickness 0.1524)
				)
				(justify mirror)
			)
		)
		(property "Device Type" "RESISTOR-G155-13300-01,330OHM,A"
			(at -0.008382 1.210564 90)
			(unlocked yes)
			(layer "B.Fab")
			(hide yes)
			(effects
				(font
					(size 0.7874 0.5842)
					(thickness 0.1524)
				)
				(justify mirror)
			)
		)
		(duplicate_pad_numbers_are_jumpers no)
		(fp_line
			(start 1.143 -0.5588)
			(end 1.143 0.5588)
			(stroke
				(width 0.1)
				(type default)
			)
			(layer "B.SilkS")
		)
		(fp_line
			(start -1.143 -0.5588)
			(end 1.143 -0.5588)
			(stroke
				(width 0.1)
				(type default)
			)
			(layer "B.SilkS")
		)
		(fp_line
			(start 1.143 0.5588)
			(end -1.143 0.5588)
			(stroke
				(width 0.1)
				(type default)
			)
			(layer "B.SilkS")
		)
		(fp_line
			(start -1.143 0.5588)
			(end -1.143 -0.5588)
			(stroke
				(width 0.1)
				(type default)
			)
			(layer "B.SilkS")
		)
		(fp_rect
			(start -1.143 -0.5588)
			(end 1.143 0.5588)
			(stroke
				(width 0)
				(type default)
			)
			(fill no)
			(layer "B.CrtYd")
		)
		(fp_line
			(start 0.508 -0.3048)
			(end 0.508 0.3048)
			(stroke
				(width 0.1)
				(type default)
			)
			(layer "B.Fab")
		)
		(fp_line
			(start -0.508 -0.3048)
			(end 0.508 -0.3048)
			(stroke
				(width 0.1)
				(type default)
			)
			(layer "B.Fab")
		)
		(fp_line
			(start 0.508 0.3048)
			(end -0.508 0.3048)
			(stroke
				(width 0.1)
				(type default)
			)
			(layer "B.Fab")
		)
		(fp_line
			(start -0.508 0.3048)
			(end -0.508 -0.3048)
			(stroke
				(width 0.1)
				(type default)
			)
			(layer "B.Fab")
		)
		(pad "1" smd rect
			(at 0.5334 0 270)
			(size 0.7112 0.6096)
			(layers "B.Cu" "B.Mask" "B.Paste")
			(net "UNNAMED_14_OPTICAL_I139_A")
		)
		(pad "2" smd rect
			(at -0.5334 0 270)
			(size 0.7112 0.6096)
			(layers "B.Cu" "B.Mask" "B.Paste")
			(net "XP3R3V_FPGA")
		)
		(zone
			(layer "B.Cu")
			(hatch none 0.5)
			(connect_pads
				(clearance 0)
			)
			(min_thickness 0.25)
			(keepout
				(tracks allowed)
				(vias not_allowed)
				(pads allowed)
				(copperpour not_allowed)
				(footprints allowed)
			)
			(placement
				(enabled no)
				(sheetname "")
			)
			(fill
				(thermal_gap 0.5)
				(thermal_bridge_width 0.5)
				(island_removal_mode 0)
			)
			(polygon
				(pts
					(xy 155.6512 -107.6198) (xy 156.2608 -107.6198) (xy 156.2608 -107.7722) (xy 155.6512 -107.7722)
				)
			)
		)
	)
	(footprint ""
		(layer "B.Cu")
		(at 138.049 -105.283 -90)
		(property "Reference" "R138"
			(at 2.45237 0.254 0)
			(unlocked yes)
			(layer "B.SilkS")
			(effects
				(font
					(size 0.7874 0.5842)
					(thickness 0.1524)
				)
				(justify mirror)
			)
		)
		(property "Value" "VAL*"
			(at -0.02032 2.13233 270)
			(unlocked yes)
			(layer "B.Fab")
			(hide yes)
			(effects
				(font
					(size 0.7874 0.5842)
					(thickness 0.1524)
				)
				(justify mirror)
			)
		)
		(property "Tolerance" "TOL*"
			(at -0.044704 3.05435 270)
			(unlocked yes)
			(layer "Cmts.User")
			(hide yes)
			(effects
				(font
					(size 0.7874 0.5842)
					(thickness 0.1524)
				)
				(justify mirror)
			)
		)
		(property "User Part Number" "PARTNUM*"
			(at -0.02032 4.024884 270)
			(unlocked yes)
			(layer "Cmts.User")
			(hide yes)
			(effects
				(font
					(size 0.7874 0.5842)
					(thickness 0.1524)
				)
				(justify mirror)
			)
		)
		(property "Device Type" "RESISTOR-G155-13300-01,330OHM,A"
			(at -0.008382 1.210564 270)
			(unlocked yes)
			(layer "B.Fab")
			(hide yes)
			(effects
				(font
					(size 0.7874 0.5842)
					(thickness 0.1524)
				)
				(justify mirror)
			)
		)
		(duplicate_pad_numbers_are_jumpers no)
		(fp_line
			(start -1.143 0.5588)
			(end -1.143 -0.5588)
			(stroke
				(width 0.1)
				(type default)
			)
			(layer "B.SilkS")
		)
		(fp_line
			(start 1.143 0.5588)
			(end -1.143 0.5588)
			(stroke
				(width 0.1)
				(type default)
			)
			(layer "B.SilkS")
		)
		(fp_line
			(start -1.143 -0.5588)
			(end 1.143 -0.5588)
			(stroke
				(width 0.1)
				(type default)
			)
			(layer "B.SilkS")
		)
		(fp_line
			(start 1.143 -0.5588)
			(end 1.143 0.5588)
			(stroke
				(width 0.1)
				(type default)
			)
			(layer "B.SilkS")
		)
		(fp_rect
			(start -1.143 -0.5588)
			(end 1.143 0.5588)
			(stroke
				(width 0)
				(type default)
			)
			(fill no)
			(layer "B.CrtYd")
		)
		(fp_line
			(start -0.508 0.3048)
			(end -0.508 -0.3048)
			(stroke
				(width 0.1)
				(type default)
			)
			(layer "B.Fab")
		)
		(fp_line
			(start 0.508 0.3048)
			(end -0.508 0.3048)
			(stroke
				(width 0.1)
				(type default)
			)
			(layer "B.Fab")
		)
		(fp_line
			(start -0.508 -0.3048)
			(end 0.508 -0.3048)
			(stroke
				(width 0.1)
				(type default)
			)
			(layer "B.Fab")
		)
		(fp_line
			(start 0.508 -0.3048)
			(end 0.508 0.3048)
			(stroke
				(width 0.1)
				(type default)
			)
			(layer "B.Fab")
		)
		(pad "1" smd rect
			(at 0.5334 0 90)
			(size 0.7112 0.6096)
			(layers "B.Cu" "B.Mask" "B.Paste")
			(net "UNNAMED_14_OPTICAL_I140_A")
		)
		(pad "2" smd rect
			(at -0.5334 0 90)
			(size 0.7112 0.6096)
			(layers "B.Cu" "B.Mask" "B.Paste")
			(net "XP3R3V_FPGA")
		)
		(zone
			(layer "B.Cu")
			(hatch none 0.5)
			(connect_pads
				(clearance 0)
			)
			(min_thickness 0.25)
			(keepout
				(tracks allowed)
				(vias not_allowed)
				(pads allowed)
				(copperpour not_allowed)
				(footprints allowed)
			)
			(placement
				(enabled no)
				(sheetname "")
			)
			(fill
				(thermal_gap 0.5)
				(thermal_bridge_width 0.5)
				(island_removal_mode 0)
			)
			(polygon
				(pts
					(xy 138.3538 -105.3592) (xy 137.7442 -105.3592) (xy 137.7442 -105.2068) (xy 138.3538 -105.2068)
				)
			)
		)
	)
	(footprint ""
		(layer "B.Cu")
		(at 140.335 -70.358)
		(property "Reference" "R135"
			(at -4.572 -0.34163 0)
			(unlocked yes)
			(layer "B.SilkS")
			(effects
				(font
					(size 0.7874 0.5842)
					(thickness 0.1524)
				)
				(justify mirror)
			)
		)
		(property "Value" "VAL*"
			(at -0.02032 2.13233 0)
			(unlocked yes)
			(layer "B.Fab")
			(hide yes)
			(effects
				(font
					(size 0.7874 0.5842)
					(thickness 0.1524)
				)
				(justify mirror)
			)
		)
		(property "Device Type" "RESISTOR-G155-100R0-J0,0OHM,-"
			(at -0.008382 1.210564 0)
			(unlocked yes)
			(layer "B.Fab")
			(hide yes)
			(effects
				(font
					(size 0.7874 0.5842)
					(thickness 0.1524)
				)
				(justify mirror)
			)
		)
		(property "User Part Number" "PARTNUM*"
			(at -0.02032 4.024884 0)
			(unlocked yes)
			(layer "Cmts.User")
			(hide yes)
			(effects
				(font
					(size 0.7874 0.5842)
					(thickness 0.1524)
				)
				(justify mirror)
			)
		)
		(property "Tolerance" "TOL*"
			(at -0.044704 3.05435 0)
			(unlocked yes)
			(layer "Cmts.User")
			(hide yes)
			(effects
				(font
					(size 0.7874 0.5842)
					(thickness 0.1524)
				)
				(justify mirror)
			)
		)
		(duplicate_pad_numbers_are_jumpers no)
		(fp_line
			(start -1.143 -0.5588)
			(end 1.143 -0.5588)
			(stroke
				(width 0.1)
				(type default)
			)
			(layer "B.SilkS")
		)
		(fp_line
			(start -1.143 0.5588)
			(end -1.143 -0.5588)
			(stroke
				(width 0.1)
				(type default)
			)
			(layer "B.SilkS")
		)
		(fp_line
			(start 1.143 -0.5588)
			(end 1.143 0.5588)
			(stroke
				(width 0.1)
				(type default)
			)
			(layer "B.SilkS")
		)
		(fp_line
			(start 1.143 0.5588)
			(end -1.143 0.5588)
			(stroke
				(width 0.1)
				(type default)
			)
			(layer "B.SilkS")
		)
		(fp_rect
			(start -1.143 -0.5588)
			(end 1.143 0.5588)
			(stroke
				(width 0)
				(type default)
			)
			(fill no)
			(layer "B.CrtYd")
		)
		(fp_line
			(start -0.508 -0.3048)
			(end 0.508 -0.3048)
			(stroke
				(width 0.1)
				(type default)
			)
			(layer "B.Fab")
		)
		(fp_line
			(start -0.508 0.3048)
			(end -0.508 -0.3048)
			(stroke
				(width 0.1)
				(type default)
			)
			(layer "B.Fab")
		)
		(fp_line
			(start 0.508 -0.3048)
			(end 0.508 0.3048)
			(stroke
				(width 0.1)
				(type default)
			)
			(layer "B.Fab")
		)
		(fp_line
			(start 0.508 0.3048)
			(end -0.508 0.3048)
			(stroke
				(width 0.1)
				(type default)
			)
			(layer "B.Fab")
		)
		(pad "1" smd rect
			(at 0.5334 0 180)
			(size 0.7112 0.6096)
			(layers "B.Cu" "B.Mask" "B.Paste")
			(net "FT4232_FPGA_TDO")
		)
		(pad "2" smd rect
			(at -0.5334 0 180)
			(size 0.7112 0.6096)
			(layers "B.Cu" "B.Mask" "B.Paste")
			(net "FPGA_TDO")
		)
		(zone
			(layer "B.Cu")
			(hatch none 0.5)
			(connect_pads
				(clearance 0)
			)
			(min_thickness 0.25)
			(keepout
				(tracks allowed)
				(vias not_allowed)
				(pads allowed)
				(copperpour not_allowed)
				(footprints allowed)
			)
			(placement
				(enabled no)
				(sheetname "")
			)
			(fill
				(thermal_gap 0.5)
				(thermal_bridge_width 0.5)
				(island_removal_mode 0)
			)
			(polygon
				(pts
					(xy 140.2588 -70.6628) (xy 140.2588 -70.0532) (xy 140.4112 -70.0532) (xy 140.4112 -70.6628)
				)
			)
		)
	)
	(footprint ""
		(layer "B.Cu")
		(at 90.2716 -49.059846 180)
		(property "Reference" "R105"
			(at -0.762 2.500884 0)
			(unlocked yes)
			(layer "B.SilkS")
			(effects
				(font
					(size 0.7874 0.5842)
					(thickness 0.1524)
				)
				(justify mirror)
			)
		)
		(property "Value" "VAL*"
			(at -0.02032 2.13233 180)
			(unlocked yes)
			(layer "B.Fab")
			(hide yes)
			(effects
				(font
					(size 0.7874 0.5842)
					(thickness 0.1524)
				)
				(justify mirror)
			)
		)
		(property "Device Type" "RESISTOR-G155-100R0-J0,0OHM,-"
			(at -0.008382 1.210564 180)
			(unlocked yes)
			(layer "B.Fab")
			(hide yes)
			(effects
				(font
					(size 0.7874 0.5842)
					(thickness 0.1524)
				)
				(justify mirror)
			)
		)
		(property "User Part Number" "PARTNUM*"
			(at -0.02032 4.024884 180)
			(unlocked yes)
			(layer "Cmts.User")
			(hide yes)
			(effects
				(font
					(size 0.7874 0.5842)
					(thickness 0.1524)
				)
				(justify mirror)
			)
		)
		(property "Tolerance" "TOL*"
			(at -0.044704 3.05435 180)
			(unlocked yes)
			(layer "Cmts.User")
			(hide yes)
			(effects
				(font
					(size 0.7874 0.5842)
					(thickness 0.1524)
				)
				(justify mirror)
			)
		)
		(duplicate_pad_numbers_are_jumpers no)
		(fp_line
			(start 1.143 0.5588)
			(end -1.143 0.5588)
			(stroke
				(width 0.1)
				(type default)
			)
			(layer "B.SilkS")
		)
		(fp_line
			(start 1.143 -0.5588)
			(end 1.143 0.5588)
			(stroke
				(width 0.1)
				(type default)
			)
			(layer "B.SilkS")
		)
		(fp_line
			(start -1.143 0.5588)
			(end -1.143 -0.5588)
			(stroke
				(width 0.1)
				(type default)
			)
			(layer "B.SilkS")
		)
		(fp_line
			(start -1.143 -0.5588)
			(end 1.143 -0.5588)
			(stroke
				(width 0.1)
				(type default)
			)
			(layer "B.SilkS")
		)
		(fp_rect
			(start 1.143 -0.5588)
			(end -1.143 0.5588)
			(stroke
				(width 0)
				(type default)
			)
			(fill no)
			(layer "B.CrtYd")
		)
		(fp_line
			(start 0.508 0.3048)
			(end -0.508 0.3048)
			(stroke
				(width 0.1)
				(type default)
			)
			(layer "B.Fab")
		)
		(fp_line
			(start 0.508 -0.3048)
			(end 0.508 0.3048)
			(stroke
				(width 0.1)
				(type default)
			)
			(layer "B.Fab")
		)
		(fp_line
			(start -0.508 0.3048)
			(end -0.508 -0.3048)
			(stroke
				(width 0.1)
				(type default)
			)
			(layer "B.Fab")
		)
		(fp_line
			(start -0.508 -0.3048)
			(end 0.508 -0.3048)
			(stroke
				(width 0.1)
				(type default)
			)
			(layer "B.Fab")
		)
		(pad "1" smd rect
			(at 0.5334 0)
			(size 0.7112 0.6096)
			(layers "B.Cu" "B.Mask" "B.Paste")
			(net "MUX_USB_DM")
		)
		(pad "2" smd rect
			(at -0.5334 0)
			(size 0.7112 0.6096)
			(layers "B.Cu" "B.Mask" "B.Paste")
			(net "MAC_USB_DM")
		)
		(zone
			(layer "B.Cu")
			(hatch none 0.5)
			(connect_pads
				(clearance 0)
			)
			(min_thickness 0.25)
			(keepout
				(tracks allowed)
				(vias not_allowed)
				(pads allowed)
				(copperpour not_allowed)
				(footprints allowed)
			)
			(placement
				(enabled no)
				(sheetname "")
			)
			(fill
				(thermal_gap 0.5)
				(thermal_bridge_width 0.5)
				(island_removal_mode 0)
			)
			(polygon
				(pts
					(xy 90.1954 -48.755046) (xy 90.3478 -48.755046) (xy 90.3478 -49.364646) (xy 90.1954 -49.364646)
				)
			)
		)
	)
	(footprint ""
		(layer "B.Cu")
		(at 41.4274 -102.3874)
		(property "Reference" "SP1"
			(at 0.0762 1.18237 0)
			(unlocked yes)
			(layer "B.SilkS")
			(effects
				(font
					(size 0.7874 0.5842)
					(thickness 0.1524)
				)
				(justify mirror)
			)
		)
		(property "Value" ""
			(at 0 0 0)
			(layer "B.Fab")
			(effects
				(font
					(size 1.27 1.27)
				)
				(justify mirror)
			)
		)
		(duplicate_pad_numbers_are_jumpers no)
		(fp_rect
			(start 0.1778 -0.3048)
			(end -0.1778 0.3048)
			(stroke
				(width 0)
				(type default)
			)
			(fill yes)
			(layer "B.Paste")
		)
		(fp_rect
			(start 0.2286 -0.3556)
			(end -0.2286 0.3556)
			(stroke
				(width 0)
				(type default)
			)
			(fill no)
			(layer "B.CrtYd")
		)
		(fp_line
			(start -0.1397 -0.2413)
			(end -0.1397 0.2413)
			(stroke
				(width 0.1)
				(type default)
			)
			(layer "B.Fab")
		)
		(fp_line
			(start -0.1397 0.2413)
			(end 0.1397 0.2413)
			(stroke
				(width 0.1)
				(type default)
			)
			(layer "B.Fab")
		)
		(fp_line
			(start 0.1397 -0.2413)
			(end -0.1397 -0.2413)
			(stroke
				(width 0.1)
				(type default)
			)
			(layer "B.Fab")
		)
		(fp_line
			(start 0.1397 0.2413)
			(end 0.1397 -0.2413)
			(stroke
				(width 0.1)
				(type default)
			)
			(layer "B.Fab")
		)
		(pad "1" smd rect
			(at 0.1143 0 180)
			(size 0.127 0.6096)
			(layers "B.Cu" "B.Mask" "B.Paste")
			(net "SG")
		)
		(pad "2" smd rect
			(at -0.1143 0 180)
			(size 0.127 0.6096)
			(layers "B.Cu" "B.Mask" "B.Paste")
			(net "XP5R0V_AGND")
		)
	)
	(footprint ""
		(layer "B.Cu")
		(at 113.68659 -56.388)
		(property "Reference" "C163"
			(at 1.59766 -0.635 270)
			(unlocked yes)
			(layer "B.SilkS")
			(effects
				(font
					(size 0.635 0.4064)
					(thickness 0.1524)
				)
				(justify mirror)
			)
		)
		(property "Value" "VAL*"
			(at -0.02032 2.13233 0)
			(unlocked yes)
			(layer "B.Fab")
			(hide yes)
			(effects
				(font
					(size 0.7874 0.5842)
					(thickness 0.1524)
				)
				(justify mirror)
			)
		)
		(property "Device Type" "CAPACITOR-G105-0F475-BM,4.7UF,A"
			(at -0.008382 1.210564 0)
			(unlocked yes)
			(layer "B.Fab")
			(hide yes)
			(effects
				(font
					(size 0.7874 0.5842)
					(thickness 0.1524)
				)
				(justify mirror)
			)
		)
		(property "User Part Number" "PARTNUM*"
			(at -0.02032 4.024884 0)
			(unlocked yes)
			(layer "Cmts.User")
			(hide yes)
			(effects
				(font
					(size 0.7874 0.5842)
					(thickness 0.1524)
				)
				(justify mirror)
			)
		)
		(property "Tolerance" "TOL*"
			(at -0.044704 3.05435 0)
			(unlocked yes)
			(layer "Cmts.User")
			(hide yes)
			(effects
				(font
					(size 0.7874 0.5842)
					(thickness 0.1524)
				)
				(justify mirror)
			)
		)
		(duplicate_pad_numbers_are_jumpers no)
		(fp_line
			(start -1.143 -0.5588)
			(end 1.143 -0.5588)
			(stroke
				(width 0.1)
				(type default)
			)
			(layer "B.SilkS")
		)
		(fp_line
			(start -1.143 0.5588)
			(end -1.143 -0.5588)
			(stroke
				(width 0.1)
				(type default)
			)
			(layer "B.SilkS")
		)
		(fp_line
			(start 1.143 -0.5588)
			(end 1.143 0.5588)
			(stroke
				(width 0.1)
				(type default)
			)
			(layer "B.SilkS")
		)
		(fp_line
			(start 1.143 0.5588)
			(end -1.143 0.5588)
			(stroke
				(width 0.1)
				(type default)
			)
			(layer "B.SilkS")
		)
		(fp_rect
			(start -1.143 0.5588)
			(end 1.143 -0.5588)
			(stroke
				(width 0)
				(type default)
			)
			(fill no)
			(layer "B.CrtYd")
		)
		(fp_line
			(start -0.508 -0.3048)
			(end 0.508 -0.3048)
			(stroke
				(width 0.1)
				(type default)
			)
			(layer "B.Fab")
		)
		(fp_line
			(start -0.508 0.3048)
			(end -0.508 -0.3048)
			(stroke
				(width 0.1)
				(type default)
			)
			(layer "B.Fab")
		)
		(fp_line
			(start 0.508 -0.3048)
			(end 0.508 0.3048)
			(stroke
				(width 0.1)
				(type default)
			)
			(layer "B.Fab")
		)
		(fp_line
			(start 0.508 0.3048)
			(end -0.508 0.3048)
			(stroke
				(width 0.1)
				(type default)
			)
			(layer "B.Fab")
		)
		(pad "1" smd rect
			(at 0.5334 0 180)
			(size 0.7112 0.6096)
			(layers "B.Cu" "B.Mask" "B.Paste")
			(net "XP3R3V_FPGA")
		)
		(pad "2" smd rect
			(at -0.5334 0 180)
			(size 0.7112 0.6096)
			(layers "B.Cu" "B.Mask" "B.Paste")
			(net "SG")
		)
		(zone
			(layer "B.Cu")
			(hatch none 0.5)
			(connect_pads
				(clearance 0)
			)
			(min_thickness 0.25)
			(keepout
				(tracks allowed)
				(vias not_allowed)
				(pads allowed)
				(copperpour not_allowed)
				(footprints allowed)
			)
			(placement
				(enabled no)
				(sheetname "")
			)
			(fill
				(thermal_gap 0.5)
				(thermal_bridge_width 0.5)
				(island_removal_mode 0)
			)
			(polygon
				(pts
					(xy 113.61039 -56.0832) (xy 113.76279 -56.0832) (xy 113.76279 -56.6928) (xy 113.61039 -56.6928)
				)
			)
		)
	)
	(footprint ""
		(layer "B.Cu")
		(at 54.0512 -74.9808 90)
		(property "Reference" "R413"
			(at 4.064 0.08763 270)
			(unlocked yes)
			(layer "B.SilkS")
			(effects
				(font
					(size 0.7874 0.5842)
					(thickness 0.1524)
				)
				(justify mirror)
			)
		)
		(property "Value" "VAL*"
			(at -0.02032 2.13233 90)
			(unlocked yes)
			(layer "B.Fab")
			(hide yes)
			(effects
				(font
					(size 0.7874 0.5842)
					(thickness 0.1524)
				)
				(justify mirror)
			)
		)
		(property "Device Type" "RESISTOR-G155-11001-01,1KOHM,1%"
			(at -0.008382 1.210564 90)
			(unlocked yes)
			(layer "B.Fab")
			(hide yes)
			(effects
				(font
					(size 0.7874 0.5842)
					(thickness 0.1524)
				)
				(justify mirror)
			)
		)
		(property "User Part Number" "PARTNUM*"
			(at -0.02032 4.024884 90)
			(unlocked yes)
			(layer "Cmts.User")
			(hide yes)
			(effects
				(font
					(size 0.7874 0.5842)
					(thickness 0.1524)
				)
				(justify mirror)
			)
		)
		(property "Tolerance" "TOL*"
			(at -0.044704 3.05435 90)
			(unlocked yes)
			(layer "Cmts.User")
			(hide yes)
			(effects
				(font
					(size 0.7874 0.5842)
					(thickness 0.1524)
				)
				(justify mirror)
			)
		)
		(duplicate_pad_numbers_are_jumpers no)
		(fp_line
			(start 1.143 -0.5588)
			(end 1.143 0.5588)
			(stroke
				(width 0.1)
				(type default)
			)
			(layer "B.SilkS")
		)
		(fp_line
			(start -1.143 -0.5588)
			(end 1.143 -0.5588)
			(stroke
				(width 0.1)
				(type default)
			)
			(layer "B.SilkS")
		)
		(fp_line
			(start 1.143 0.5588)
			(end -1.143 0.5588)
			(stroke
				(width 0.1)
				(type default)
			)
			(layer "B.SilkS")
		)
		(fp_line
			(start -1.143 0.5588)
			(end -1.143 -0.5588)
			(stroke
				(width 0.1)
				(type default)
			)
			(layer "B.SilkS")
		)
		(fp_rect
			(start 1.143 0.5588)
			(end -1.143 -0.5588)
			(stroke
				(width 0)
				(type default)
			)
			(fill no)
			(layer "B.CrtYd")
		)
		(fp_line
			(start 0.508 -0.3048)
			(end 0.508 0.3048)
			(stroke
				(width 0.1)
				(type default)
			)
			(layer "B.Fab")
		)
		(fp_line
			(start -0.508 -0.3048)
			(end 0.508 -0.3048)
			(stroke
				(width 0.1)
				(type default)
			)
			(layer "B.Fab")
		)
		(fp_line
			(start 0.508 0.3048)
			(end -0.508 0.3048)
			(stroke
				(width 0.1)
				(type default)
			)
			(layer "B.Fab")
		)
		(fp_line
			(start -0.508 0.3048)
			(end -0.508 -0.3048)
			(stroke
				(width 0.1)
				(type default)
			)
			(layer "B.Fab")
		)
		(pad "1" smd rect
			(at 0.5334 0 270)
			(size 0.7112 0.6096)
			(layers "B.Cu" "B.Mask" "B.Paste")
			(net "UNNAMED_6_LM75BDPTSSOP8_I59_A1")
		)
		(pad "2" smd rect
			(at -0.5334 0 270)
			(size 0.7112 0.6096)
			(layers "B.Cu" "B.Mask" "B.Paste")
			(net "SG")
		)
		(zone
			(layer "B.Cu")
			(hatch none 0.5)
			(connect_pads
				(clearance 0)
			)
			(min_thickness 0.25)
			(keepout
				(tracks not_allowed)
				(vias allowed)
				(pads allowed)
				(copperpour not_allowed)
				(footprints allowed)
			)
			(placement
				(enabled no)
				(sheetname "")
			)
			(fill
				(thermal_gap 0.5)
				(thermal_bridge_width 0.5)
				(island_removal_mode 0)
			)
			(polygon
				(pts
					(xy 54.356 -75.057) (xy 53.7464 -75.057) (xy 53.7464 -74.9046) (xy 54.356 -74.9046)
				)
			)
		)
		(zone
			(layer "B.Cu")
			(hatch none 0.5)
			(connect_pads
				(clearance 0)
			)
			(min_thickness 0.25)
			(keepout
				(tracks allowed)
				(vias not_allowed)
				(pads allowed)
				(copperpour not_allowed)
				(footprints allowed)
			)
			(placement
				(enabled no)
				(sheetname "")
			)
			(fill
				(thermal_gap 0.5)
				(thermal_bridge_width 0.5)
				(island_removal_mode 0)
			)
			(polygon
				(pts
					(xy 54.356 -75.057) (xy 53.7464 -75.057) (xy 53.7464 -74.9046) (xy 54.356 -74.9046)
				)
			)
		)
	)
	(footprint ""
		(layer "B.Cu")
		(at 28.702 -91.059 -90)
		(property "Reference" "C100"
			(at -3.175 -0.08763 270)
			(unlocked yes)
			(layer "B.SilkS")
			(effects
				(font
					(size 0.7874 0.5842)
					(thickness 0.1524)
				)
				(justify mirror)
			)
		)
		(property "Value" "VAL*"
			(at -0.0762 2.067306 270)
			(unlocked yes)
			(layer "B.Fab")
			(hide yes)
			(effects
				(font
					(size 0.7874 0.5842)
					(thickness 0.1524)
				)
				(justify mirror)
			)
		)
		(property "Tolerance" "TOL*"
			(at -0.0762 3.032506 270)
			(unlocked yes)
			(layer "Cmts.User")
			(hide yes)
			(effects
				(font
					(size 0.7874 0.5842)
					(thickness 0.1524)
				)
				(justify mirror)
			)
		)
		(property "User Part Number" "PARTNUM*"
			(at -0.1016 4.023106 270)
			(unlocked yes)
			(layer "Cmts.User")
			(hide yes)
			(effects
				(font
					(size 0.7874 0.5842)
					(thickness 0.1524)
				)
				(justify mirror)
			)
		)
		(property "Device Type" "CAPACITOR-G105-0B104-EK,0.1UF,A"
			(at -0.0508 1.127506 270)
			(unlocked yes)
			(layer "B.Fab")
			(hide yes)
			(effects
				(font
					(size 0.7874 0.5842)
					(thickness 0.1524)
				)
				(justify mirror)
			)
		)
		(duplicate_pad_numbers_are_jumpers no)
		(fp_line
			(start -1.143 0.5588)
			(end -1.143 -0.5588)
			(stroke
				(width 0.1)
				(type default)
			)
			(layer "B.SilkS")
		)
		(fp_line
			(start 1.143 0.5588)
			(end -1.143 0.5588)
			(stroke
				(width 0.1)
				(type default)
			)
			(layer "B.SilkS")
		)
		(fp_line
			(start -1.143 -0.5588)
			(end 1.143 -0.5588)
			(stroke
				(width 0.1)
				(type default)
			)
			(layer "B.SilkS")
		)
		(fp_line
			(start 1.143 -0.5588)
			(end 1.143 0.5588)
			(stroke
				(width 0.1)
				(type default)
			)
			(layer "B.SilkS")
		)
		(fp_rect
			(start 1.143 -0.5588)
			(end -1.143 0.5588)
			(stroke
				(width 0)
				(type default)
			)
			(fill no)
			(layer "B.CrtYd")
		)
		(fp_line
			(start -0.508 0.3048)
			(end -0.508 -0.3048)
			(stroke
				(width 0.1)
				(type default)
			)
			(layer "B.Fab")
		)
		(fp_line
			(start 0.508 0.3048)
			(end -0.508 0.3048)
			(stroke
				(width 0.1)
				(type default)
			)
			(layer "B.Fab")
		)
		(fp_line
			(start -0.508 -0.3048)
			(end 0.508 -0.3048)
			(stroke
				(width 0.1)
				(type default)
			)
			(layer "B.Fab")
		)
		(fp_line
			(start 0.508 -0.3048)
			(end 0.508 0.3048)
			(stroke
				(width 0.1)
				(type default)
			)
			(layer "B.Fab")
		)
		(pad "1" smd rect
			(at 0.5334 0 90)
			(size 0.7112 0.6096)
			(layers "B.Cu" "B.Mask" "B.Paste")
			(net "XP3R3V_VPLL")
		)
		(pad "2" smd rect
			(at -0.5334 0 90)
			(size 0.7112 0.6096)
			(layers "B.Cu" "B.Mask" "B.Paste")
			(net "SG")
		)
		(zone
			(layer "B.Cu")
			(hatch none 0.5)
			(connect_pads
				(clearance 0)
			)
			(min_thickness 0.25)
			(keepout
				(tracks allowed)
				(vias not_allowed)
				(pads allowed)
				(copperpour not_allowed)
				(footprints allowed)
			)
			(placement
				(enabled no)
				(sheetname "")
			)
			(fill
				(thermal_gap 0.5)
				(thermal_bridge_width 0.5)
				(island_removal_mode 0)
			)
			(polygon
				(pts
					(xy 29.0068 -90.9828) (xy 29.0068 -91.1352) (xy 28.3972 -91.1352) (xy 28.3972 -90.9828)
				)
			)
		)
	)
	(footprint ""
		(layer "B.Cu")
		(at 98.044 -64.2874 90)
		(property "Reference" "R284"
			(at 3.4036 0.21463 270)
			(unlocked yes)
			(layer "B.SilkS")
			(effects
				(font
					(size 0.7874 0.5842)
					(thickness 0.1524)
				)
				(justify mirror)
			)
		)
		(property "Value" "VAL*"
			(at -0.02032 2.13233 90)
			(unlocked yes)
			(layer "B.Fab")
			(hide yes)
			(effects
				(font
					(size 0.7874 0.5842)
					(thickness 0.1524)
				)
				(justify mirror)
			)
		)
		(property "Tolerance" "TOL*"
			(at -0.044704 3.05435 90)
			(unlocked yes)
			(layer "Cmts.User")
			(hide yes)
			(effects
				(font
					(size 0.7874 0.5842)
					(thickness 0.1524)
				)
				(justify mirror)
			)
		)
		(property "User Part Number" "PARTNUM*"
			(at -0.02032 4.024884 90)
			(unlocked yes)
			(layer "Cmts.User")
			(hide yes)
			(effects
				(font
					(size 0.7874 0.5842)
					(thickness 0.1524)
				)
				(justify mirror)
			)
		)
		(property "Device Type" "RESISTOR-G155-14701-01,4.7KOHMA"
			(at -0.008382 1.210564 90)
			(unlocked yes)
			(layer "B.Fab")
			(hide yes)
			(effects
				(font
					(size 0.7874 0.5842)
					(thickness 0.1524)
				)
				(justify mirror)
			)
		)
		(duplicate_pad_numbers_are_jumpers no)
		(fp_line
			(start 1.143 -0.5588)
			(end 1.143 0.5588)
			(stroke
				(width 0.1)
				(type default)
			)
			(layer "B.SilkS")
		)
		(fp_line
			(start -1.143 -0.5588)
			(end 1.143 -0.5588)
			(stroke
				(width 0.1)
				(type default)
			)
			(layer "B.SilkS")
		)
		(fp_line
			(start 1.143 0.5588)
			(end -1.143 0.5588)
			(stroke
				(width 0.1)
				(type default)
			)
			(layer "B.SilkS")
		)
		(fp_line
			(start -1.143 0.5588)
			(end -1.143 -0.5588)
			(stroke
				(width 0.1)
				(type default)
			)
			(layer "B.SilkS")
		)
		(fp_poly
			(pts
				(xy 1.143 0.5588) (xy -1.143 0.5588) (xy -1.143 -0.5588) (xy 1.143 -0.5588)
			)
			(stroke
				(width 0)
				(type default)
			)
			(fill no)
			(layer "B.CrtYd")
		)
		(fp_line
			(start 0.508 -0.3048)
			(end 0.508 0.3048)
			(stroke
				(width 0.1)
				(type default)
			)
			(layer "B.Fab")
		)
		(fp_line
			(start -0.508 -0.3048)
			(end 0.508 -0.3048)
			(stroke
				(width 0.1)
				(type default)
			)
			(layer "B.Fab")
		)
		(fp_line
			(start 0.508 0.3048)
			(end -0.508 0.3048)
			(stroke
				(width 0.1)
				(type default)
			)
			(layer "B.Fab")
		)
		(fp_line
			(start -0.508 0.3048)
			(end -0.508 -0.3048)
			(stroke
				(width 0.1)
				(type default)
			)
			(layer "B.Fab")
		)
		(pad "1" smd rect
			(at 0.5334 0 270)
			(size 0.7112 0.6096)
			(layers "B.Cu" "B.Mask" "B.Paste")
			(net "SG")
		)
		(pad "2" smd rect
			(at -0.5334 0 270)
			(size 0.7112 0.6096)
			(layers "B.Cu" "B.Mask" "B.Paste")
			(net "FPGA_IO_2")
		)
		(zone
			(layer "B.Cu")
			(hatch none 0.5)
			(connect_pads
				(clearance 0)
			)
			(min_thickness 0.25)
			(keepout
				(tracks not_allowed)
				(vias allowed)
				(pads allowed)
				(copperpour not_allowed)
				(footprints allowed)
			)
			(placement
				(enabled no)
				(sheetname "")
			)
			(fill
				(thermal_gap 0.5)
				(thermal_bridge_width 0.5)
				(island_removal_mode 0)
			)
			(polygon
				(pts
					(xy 98.3488 -64.3636) (xy 97.7392 -64.3636) (xy 97.7392 -64.2112) (xy 98.3488 -64.2112)
				)
			)
		)
		(zone
			(layer "B.Cu")
			(hatch none 0.5)
			(connect_pads
				(clearance 0)
			)
			(min_thickness 0.25)
			(keepout
				(tracks allowed)
				(vias not_allowed)
				(pads allowed)
				(copperpour not_allowed)
				(footprints allowed)
			)
			(placement
				(enabled no)
				(sheetname "")
			)
			(fill
				(thermal_gap 0.5)
				(thermal_bridge_width 0.5)
				(island_removal_mode 0)
			)
			(polygon
				(pts
					(xy 98.3488 -64.3636) (xy 97.7392 -64.3636) (xy 97.7392 -64.2112) (xy 98.3488 -64.2112)
				)
			)
		)
	)
	(footprint ""
		(layer "B.Cu")
		(at 150.114 -104.394 90)
		(property "Reference" "R118"
			(at -1.397 1.10363 270)
			(unlocked yes)
			(layer "B.SilkS")
			(effects
				(font
					(size 0.7874 0.5842)
					(thickness 0.1524)
				)
				(justify mirror)
			)
		)
		(property "Value" "VAL*"
			(at -0.02032 2.13233 90)
			(unlocked yes)
			(layer "B.Fab")
			(hide yes)
			(effects
				(font
					(size 0.7874 0.5842)
					(thickness 0.1524)
				)
				(justify mirror)
			)
		)
		(property "Tolerance" "TOL*"
			(at -0.044704 3.05435 90)
			(unlocked yes)
			(layer "Cmts.User")
			(hide yes)
			(effects
				(font
					(size 0.7874 0.5842)
					(thickness 0.1524)
				)
				(justify mirror)
			)
		)
		(property "User Part Number" "PARTNUM*"
			(at -0.02032 4.024884 90)
			(unlocked yes)
			(layer "Cmts.User")
			(hide yes)
			(effects
				(font
					(size 0.7874 0.5842)
					(thickness 0.1524)
				)
				(justify mirror)
			)
		)
		(property "Device Type" "RESISTOR-G155-13300-01,330OHM,A"
			(at -0.008382 1.210564 90)
			(unlocked yes)
			(layer "B.Fab")
			(hide yes)
			(effects
				(font
					(size 0.7874 0.5842)
					(thickness 0.1524)
				)
				(justify mirror)
			)
		)
		(duplicate_pad_numbers_are_jumpers no)
		(fp_line
			(start 1.143 -0.5588)
			(end 1.143 0.5588)
			(stroke
				(width 0.1)
				(type default)
			)
			(layer "B.SilkS")
		)
		(fp_line
			(start -1.143 -0.5588)
			(end 1.143 -0.5588)
			(stroke
				(width 0.1)
				(type default)
			)
			(layer "B.SilkS")
		)
		(fp_line
			(start 1.143 0.5588)
			(end -1.143 0.5588)
			(stroke
				(width 0.1)
				(type default)
			)
			(layer "B.SilkS")
		)
		(fp_line
			(start -1.143 0.5588)
			(end -1.143 -0.5588)
			(stroke
				(width 0.1)
				(type default)
			)
			(layer "B.SilkS")
		)
		(fp_poly
			(pts
				(xy 1.143 0.5588) (xy -1.143 0.5588) (xy -1.143 -0.5588) (xy 1.143 -0.5588)
			)
			(stroke
				(width 0)
				(type default)
			)
			(fill no)
			(layer "B.CrtYd")
		)
		(fp_line
			(start 0.508 -0.3048)
			(end 0.508 0.3048)
			(stroke
				(width 0.1)
				(type default)
			)
			(layer "B.Fab")
		)
		(fp_line
			(start -0.508 -0.3048)
			(end 0.508 -0.3048)
			(stroke
				(width 0.1)
				(type default)
			)
			(layer "B.Fab")
		)
		(fp_line
			(start 0.508 0.3048)
			(end -0.508 0.3048)
			(stroke
				(width 0.1)
				(type default)
			)
			(layer "B.Fab")
		)
		(fp_line
			(start -0.508 0.3048)
			(end -0.508 -0.3048)
			(stroke
				(width 0.1)
				(type default)
			)
			(layer "B.Fab")
		)
		(pad "1" smd rect
			(at 0.5334 0 270)
			(size 0.7112 0.6096)
			(layers "B.Cu" "B.Mask" "B.Paste")
			(net "UNNAMED_14_OPTICAL_I191_A")
		)
		(pad "2" smd rect
			(at -0.5334 0 270)
			(size 0.7112 0.6096)
			(layers "B.Cu" "B.Mask" "B.Paste")
			(net "XP3R3V_PCIE")
		)
		(zone
			(layer "B.Cu")
			(hatch none 0.5)
			(connect_pads
				(clearance 0)
			)
			(min_thickness 0.25)
			(keepout
				(tracks allowed)
				(vias not_allowed)
				(pads allowed)
				(copperpour not_allowed)
				(footprints allowed)
			)
			(placement
				(enabled no)
				(sheetname "")
			)
			(fill
				(thermal_gap 0.5)
				(thermal_bridge_width 0.5)
				(island_removal_mode 0)
			)
			(polygon
				(pts
					(xy 150.4188 -104.4702) (xy 149.8092 -104.4702) (xy 149.8092 -104.3178) (xy 150.4188 -104.3178)
				)
			)
		)
		(zone
			(layer "B.Cu")
			(hatch none 0.5)
			(connect_pads
				(clearance 0)
			)
			(min_thickness 0.25)
			(keepout
				(tracks not_allowed)
				(vias allowed)
				(pads allowed)
				(copperpour not_allowed)
				(footprints allowed)
			)
			(placement
				(enabled no)
				(sheetname "")
			)
			(fill
				(thermal_gap 0.5)
				(thermal_bridge_width 0.5)
				(island_removal_mode 0)
			)
			(polygon
				(pts
					(xy 150.4188 -104.4702) (xy 149.8092 -104.4702) (xy 149.8092 -104.3178) (xy 150.4188 -104.3178)
				)
			)
		)
	)
	(footprint ""
		(layer "B.Cu")
		(at 140.335 -71.501)
		(property "Reference" "R42"
			(at -4.191 -0.21463 0)
			(unlocked yes)
			(layer "B.SilkS")
			(effects
				(font
					(size 0.7874 0.5842)
					(thickness 0.1524)
				)
				(justify mirror)
			)
		)
		(property "Value" "VAL*"
			(at -0.02032 2.13233 0)
			(unlocked yes)
			(layer "B.Fab")
			(hide yes)
			(effects
				(font
					(size 0.7874 0.5842)
					(thickness 0.1524)
				)
				(justify mirror)
			)
		)
		(property "Tolerance" "TOL*"
			(at -0.044704 3.05435 0)
			(unlocked yes)
			(layer "Cmts.User")
			(hide yes)
			(effects
				(font
					(size 0.7874 0.5842)
					(thickness 0.1524)
				)
				(justify mirror)
			)
		)
		(property "User Part Number" "PARTNUM*"
			(at -0.02032 4.024884 0)
			(unlocked yes)
			(layer "Cmts.User")
			(hide yes)
			(effects
				(font
					(size 0.7874 0.5842)
					(thickness 0.1524)
				)
				(justify mirror)
			)
		)
		(property "Device Type" "RESISTOR-G155-100R0-J0,0OHM,-"
			(at -0.008382 1.210564 0)
			(unlocked yes)
			(layer "B.Fab")
			(hide yes)
			(effects
				(font
					(size 0.7874 0.5842)
					(thickness 0.1524)
				)
				(justify mirror)
			)
		)
		(duplicate_pad_numbers_are_jumpers no)
		(fp_line
			(start -1.143 -0.5588)
			(end 1.143 -0.5588)
			(stroke
				(width 0.1)
				(type default)
			)
			(layer "B.SilkS")
		)
		(fp_line
			(start -1.143 0.5588)
			(end -1.143 -0.5588)
			(stroke
				(width 0.1)
				(type default)
			)
			(layer "B.SilkS")
		)
		(fp_line
			(start 1.143 -0.5588)
			(end 1.143 0.5588)
			(stroke
				(width 0.1)
				(type default)
			)
			(layer "B.SilkS")
		)
		(fp_line
			(start 1.143 0.5588)
			(end -1.143 0.5588)
			(stroke
				(width 0.1)
				(type default)
			)
			(layer "B.SilkS")
		)
		(fp_rect
			(start 1.143 0.5588)
			(end -1.143 -0.5588)
			(stroke
				(width 0)
				(type default)
			)
			(fill no)
			(layer "B.CrtYd")
		)
		(fp_line
			(start -0.508 -0.3048)
			(end 0.508 -0.3048)
			(stroke
				(width 0.1)
				(type default)
			)
			(layer "B.Fab")
		)
		(fp_line
			(start -0.508 0.3048)
			(end -0.508 -0.3048)
			(stroke
				(width 0.1)
				(type default)
			)
			(layer "B.Fab")
		)
		(fp_line
			(start 0.508 -0.3048)
			(end 0.508 0.3048)
			(stroke
				(width 0.1)
				(type default)
			)
			(layer "B.Fab")
		)
		(fp_line
			(start 0.508 0.3048)
			(end -0.508 0.3048)
			(stroke
				(width 0.1)
				(type default)
			)
			(layer "B.Fab")
		)
		(pad "1" smd rect
			(at 0.5334 0 180)
			(size 0.7112 0.6096)
			(layers "B.Cu" "B.Mask" "B.Paste")
			(net "PCIE_CONN_TDO")
		)
		(pad "2" smd rect
			(at -0.5334 0 180)
			(size 0.7112 0.6096)
			(layers "B.Cu" "B.Mask" "B.Paste")
			(net "FPGA_TDO")
		)
		(zone
			(layer "B.Cu")
			(hatch none 0.5)
			(connect_pads
				(clearance 0)
			)
			(min_thickness 0.25)
			(keepout
				(tracks allowed)
				(vias not_allowed)
				(pads allowed)
				(copperpour not_allowed)
				(footprints allowed)
			)
			(placement
				(enabled no)
				(sheetname "")
			)
			(fill
				(thermal_gap 0.5)
				(thermal_bridge_width 0.5)
				(island_removal_mode 0)
			)
			(polygon
				(pts
					(xy 140.4112 -71.1962) (xy 140.4112 -71.8058) (xy 140.2588 -71.8058) (xy 140.2588 -71.1962)
				)
			)
		)
	)
	(footprint ""
		(layer "B.Cu")
		(at 109.475524 -48.704246 -90)
		(property "Reference" "C144"
			(at -0.063754 -0.982726 270)
			(unlocked yes)
			(layer "B.SilkS")
			(effects
				(font
					(size 0.635 0.4064)
					(thickness 0.1524)
				)
				(justify mirror)
			)
		)
		(property "Value" "VAL*"
			(at 0 3.718306 270)
			(unlocked yes)
			(layer "B.Fab")
			(hide yes)
			(effects
				(font
					(size 0.7874 0.5842)
					(thickness 0.127)
				)
				(justify mirror)
			)
		)
		(property "Device Type" "CAPACITOR-G105-0B104-CK,0.1UF,A"
			(at 0 1.432306 270)
			(unlocked yes)
			(layer "B.Fab")
			(hide yes)
			(effects
				(font
					(size 0.7874 0.5842)
					(thickness 0.127)
				)
				(justify mirror)
			)
		)
		(property "User Part Number" "PARTNUM*"
			(at 0 2.575306 270)
			(unlocked yes)
			(layer "Cmts.User")
			(hide yes)
			(effects
				(font
					(size 0.7874 0.5842)
					(thickness 0.127)
				)
				(justify mirror)
			)
		)
		(property "Tolerance" "TOL*"
			(at 0 4.861306 270)
			(unlocked yes)
			(layer "Cmts.User")
			(hide yes)
			(effects
				(font
					(size 0.7874 0.5842)
					(thickness 0.127)
				)
				(justify mirror)
			)
		)
		(duplicate_pad_numbers_are_jumpers no)
		(fp_line
			(start -0.970026 0.4699)
			(end 0.970026 0.4699)
			(stroke
				(width 0.1)
				(type default)
			)
			(layer "B.SilkS")
		)
		(fp_line
			(start 0.970026 0.4699)
			(end 0.970026 -0.4699)
			(stroke
				(width 0.1)
				(type default)
			)
			(layer "B.SilkS")
		)
		(fp_line
			(start -0.970026 -0.4699)
			(end -0.970026 0.4699)
			(stroke
				(width 0.1)
				(type default)
			)
			(layer "B.SilkS")
		)
		(fp_line
			(start 0.970026 -0.4699)
			(end -0.970026 -0.4699)
			(stroke
				(width 0.1)
				(type default)
			)
			(layer "B.SilkS")
		)
		(fp_poly
			(pts
				(xy 0.970026 0.4699) (xy -0.970026 0.4699) (xy -0.970026 -0.4699) (xy 0.970026 -0.4699)
			)
			(stroke
				(width 0)
				(type default)
			)
			(fill no)
			(layer "B.CrtYd")
		)
		(fp_line
			(start -0.508 0.3048)
			(end 0.508 0.3048)
			(stroke
				(width 0.1)
				(type default)
			)
			(layer "B.Fab")
		)
		(fp_line
			(start 0.508 0.3048)
			(end 0.508 -0.3048)
			(stroke
				(width 0.1)
				(type default)
			)
			(layer "B.Fab")
		)
		(fp_line
			(start -0.508 -0.3048)
			(end -0.508 0.3048)
			(stroke
				(width 0.1)
				(type default)
			)
			(layer "B.Fab")
		)
		(fp_line
			(start 0.508 -0.3048)
			(end -0.508 -0.3048)
			(stroke
				(width 0.1)
				(type default)
			)
			(layer "B.Fab")
		)
		(pad "1" smd circle
			(at 0.500126 0 90)
			(size 0.635 0.635)
			(layers "B.Cu" "B.Mask" "B.Paste")
			(net "XP3R3V_FPGA")
		)
		(pad "2" smd circle
			(at -0.500126 0 90)
			(size 0.635 0.635)
			(layers "B.Cu" "B.Mask" "B.Paste")
			(net "SG")
		)
	)
	(footprint ""
		(layer "B.Cu")
		(at 152.883108 -49.01311 90)
		(property "Reference" "R300"
			(at 3.94589 -0.649478 270)
			(unlocked yes)
			(layer "B.SilkS")
			(effects
				(font
					(size 0.7874 0.5842)
					(thickness 0.1524)
				)
				(justify mirror)
			)
		)
		(property "Value" "VAL*"
			(at -0.02032 2.13233 90)
			(unlocked yes)
			(layer "B.Fab")
			(hide yes)
			(effects
				(font
					(size 0.7874 0.5842)
					(thickness 0.1524)
				)
				(justify mirror)
			)
		)
		(property "Device Type" "RESISTOR-G155-14701-01,4.7KOHMA"
			(at -0.008382 1.210564 90)
			(unlocked yes)
			(layer "B.Fab")
			(hide yes)
			(effects
				(font
					(size 0.7874 0.5842)
					(thickness 0.1524)
				)
				(justify mirror)
			)
		)
		(property "User Part Number" "PARTNUM*"
			(at -0.02032 4.024884 90)
			(unlocked yes)
			(layer "Cmts.User")
			(hide yes)
			(effects
				(font
					(size 0.7874 0.5842)
					(thickness 0.1524)
				)
				(justify mirror)
			)
		)
		(property "Tolerance" "TOL*"
			(at -0.044704 3.05435 90)
			(unlocked yes)
			(layer "Cmts.User")
			(hide yes)
			(effects
				(font
					(size 0.7874 0.5842)
					(thickness 0.1524)
				)
				(justify mirror)
			)
		)
		(duplicate_pad_numbers_are_jumpers no)
		(fp_line
			(start 1.143 -0.5588)
			(end 1.143 0.5588)
			(stroke
				(width 0.1)
				(type default)
			)
			(layer "B.SilkS")
		)
		(fp_line
			(start -1.143 -0.5588)
			(end 1.143 -0.5588)
			(stroke
				(width 0.1)
				(type default)
			)
			(layer "B.SilkS")
		)
		(fp_line
			(start 1.143 0.5588)
			(end -1.143 0.5588)
			(stroke
				(width 0.1)
				(type default)
			)
			(layer "B.SilkS")
		)
		(fp_line
			(start -1.143 0.5588)
			(end -1.143 -0.5588)
			(stroke
				(width 0.1)
				(type default)
			)
			(layer "B.SilkS")
		)
		(fp_rect
			(start 1.143 0.5588)
			(end -1.143 -0.5588)
			(stroke
				(width 0)
				(type default)
			)
			(fill no)
			(layer "B.CrtYd")
		)
		(fp_line
			(start 0.508 -0.3048)
			(end 0.508 0.3048)
			(stroke
				(width 0.1)
				(type default)
			)
			(layer "B.Fab")
		)
		(fp_line
			(start -0.508 -0.3048)
			(end 0.508 -0.3048)
			(stroke
				(width 0.1)
				(type default)
			)
			(layer "B.Fab")
		)
		(fp_line
			(start 0.508 0.3048)
			(end -0.508 0.3048)
			(stroke
				(width 0.1)
				(type default)
			)
			(layer "B.Fab")
		)
		(fp_line
			(start -0.508 0.3048)
			(end -0.508 -0.3048)
			(stroke
				(width 0.1)
				(type default)
			)
			(layer "B.Fab")
		)
		(pad "1" smd rect
			(at 0.5334 0 270)
			(size 0.7112 0.6096)
			(layers "B.Cu" "B.Mask" "B.Paste")
			(net "XP3R3V_FPGA")
		)
		(pad "2" smd rect
			(at -0.5334 0 270)
			(size 0.7112 0.6096)
			(layers "B.Cu" "B.Mask" "B.Paste")
			(net "FPGA_IN_SHT3X_ALERT_N")
		)
		(zone
			(layer "B.Cu")
			(hatch none 0.5)
			(connect_pads
				(clearance 0)
			)
			(min_thickness 0.25)
			(keepout
				(tracks allowed)
				(vias not_allowed)
				(pads allowed)
				(copperpour not_allowed)
				(footprints allowed)
			)
			(placement
				(enabled no)
				(sheetname "")
			)
			(fill
				(thermal_gap 0.5)
				(thermal_bridge_width 0.5)
				(island_removal_mode 0)
			)
			(polygon
				(pts
					(xy 153.187908 -49.08931) (xy 152.578308 -49.08931) (xy 152.578308 -48.93691) (xy 153.187908 -48.93691)
				)
			)
		)
	)
	(footprint ""
		(layer "B.Cu")
		(at 105.847134 -40.323008 90)
		(property "Reference" "C121"
			(at -1.143508 -41.383204 270)
			(unlocked yes)
			(layer "B.SilkS")
			(effects
				(font
					(size 0.635 0.4064)
					(thickness 0.1524)
				)
				(justify mirror)
			)
		)
		(property "Value" "VAL*"
			(at 0 3.718306 90)
			(unlocked yes)
			(layer "B.Fab")
			(hide yes)
			(effects
				(font
					(size 0.7874 0.5842)
					(thickness 0.127)
				)
				(justify mirror)
			)
		)
		(property "Device Type" "CAPACITOR-G105-0B104-CK,0.1UF,A"
			(at 0 1.432306 90)
			(unlocked yes)
			(layer "B.Fab")
			(hide yes)
			(effects
				(font
					(size 0.7874 0.5842)
					(thickness 0.127)
				)
				(justify mirror)
			)
		)
		(property "User Part Number" "PARTNUM*"
			(at 0 2.575306 90)
			(unlocked yes)
			(layer "Cmts.User")
			(hide yes)
			(effects
				(font
					(size 0.7874 0.5842)
					(thickness 0.127)
				)
				(justify mirror)
			)
		)
		(property "Tolerance" "TOL*"
			(at 0 4.861306 90)
			(unlocked yes)
			(layer "Cmts.User")
			(hide yes)
			(effects
				(font
					(size 0.7874 0.5842)
					(thickness 0.127)
				)
				(justify mirror)
			)
		)
		(duplicate_pad_numbers_are_jumpers no)
		(fp_line
			(start 0.970026 -0.4699)
			(end -0.970026 -0.4699)
			(stroke
				(width 0.1)
				(type default)
			)
			(layer "B.SilkS")
		)
		(fp_line
			(start -0.970026 -0.4699)
			(end -0.970026 0.4699)
			(stroke
				(width 0.1)
				(type default)
			)
			(layer "B.SilkS")
		)
		(fp_line
			(start 0.970026 0.4699)
			(end 0.970026 -0.4699)
			(stroke
				(width 0.1)
				(type default)
			)
			(layer "B.SilkS")
		)
		(fp_line
			(start -0.970026 0.4699)
			(end 0.970026 0.4699)
			(stroke
				(width 0.1)
				(type default)
			)
			(layer "B.SilkS")
		)
		(fp_poly
			(pts
				(xy 0.970026 0.4699) (xy -0.970026 0.4699) (xy -0.970026 -0.4699) (xy 0.970026 -0.4699)
			)
			(stroke
				(width 0)
				(type default)
			)
			(fill no)
			(layer "B.CrtYd")
		)
		(fp_line
			(start 0.508 -0.3048)
			(end -0.508 -0.3048)
			(stroke
				(width 0.1)
				(type default)
			)
			(layer "B.Fab")
		)
		(fp_line
			(start -0.508 -0.3048)
			(end -0.508 0.3048)
			(stroke
				(width 0.1)
				(type default)
			)
			(layer "B.Fab")
		)
		(fp_line
			(start 0.508 0.3048)
			(end 0.508 -0.3048)
			(stroke
				(width 0.1)
				(type default)
			)
			(layer "B.Fab")
		)
		(fp_line
			(start -0.508 0.3048)
			(end 0.508 0.3048)
			(stroke
				(width 0.1)
				(type default)
			)
			(layer "B.Fab")
		)
		(pad "1" smd circle
			(at 0.500126 0 270)
			(size 0.635 0.635)
			(layers "B.Cu" "B.Mask" "B.Paste")
			(net "XP1R0V_FPGA_VCCINT")
		)
		(pad "2" smd circle
			(at -0.500126 0 270)
			(size 0.635 0.635)
			(layers "B.Cu" "B.Mask" "B.Paste")
			(net "SG")
		)
	)
	(footprint ""
		(layer "B.Cu")
		(at 162.56 -25.908 180)
		(property "Reference" "R415"
			(at 0.508 2.62763 0)
			(unlocked yes)
			(layer "B.SilkS")
			(effects
				(font
					(size 0.7874 0.5842)
					(thickness 0.1524)
				)
				(justify mirror)
			)
		)
		(property "Value" "VAL*"
			(at -0.02032 2.13233 180)
			(unlocked yes)
			(layer "B.Fab")
			(hide yes)
			(effects
				(font
					(size 0.7874 0.5842)
					(thickness 0.1524)
				)
				(justify mirror)
			)
		)
		(property "Tolerance" "TOL*"
			(at -0.044704 3.05435 180)
			(unlocked yes)
			(layer "Cmts.User")
			(hide yes)
			(effects
				(font
					(size 0.7874 0.5842)
					(thickness 0.1524)
				)
				(justify mirror)
			)
		)
		(property "User Part Number" "PARTNUM*"
			(at -0.02032 4.024884 180)
			(unlocked yes)
			(layer "Cmts.User")
			(hide yes)
			(effects
				(font
					(size 0.7874 0.5842)
					(thickness 0.1524)
				)
				(justify mirror)
			)
		)
		(property "Device Type" "RESISTOR-G155-11001-01,1KOHM,1%"
			(at -0.008382 1.210564 180)
			(unlocked yes)
			(layer "B.Fab")
			(hide yes)
			(effects
				(font
					(size 0.7874 0.5842)
					(thickness 0.1524)
				)
				(justify mirror)
			)
		)
		(duplicate_pad_numbers_are_jumpers no)
		(fp_line
			(start 1.143 0.5588)
			(end -1.143 0.5588)
			(stroke
				(width 0.1)
				(type default)
			)
			(layer "B.SilkS")
		)
		(fp_line
			(start 1.143 -0.5588)
			(end 1.143 0.5588)
			(stroke
				(width 0.1)
				(type default)
			)
			(layer "B.SilkS")
		)
		(fp_line
			(start -1.143 0.5588)
			(end -1.143 -0.5588)
			(stroke
				(width 0.1)
				(type default)
			)
			(layer "B.SilkS")
		)
		(fp_line
			(start -1.143 -0.5588)
			(end 1.143 -0.5588)
			(stroke
				(width 0.1)
				(type default)
			)
			(layer "B.SilkS")
		)
		(fp_rect
			(start 1.143 -0.5588)
			(end -1.143 0.5588)
			(stroke
				(width 0)
				(type default)
			)
			(fill no)
			(layer "B.CrtYd")
		)
		(fp_line
			(start 0.508 0.3048)
			(end -0.508 0.3048)
			(stroke
				(width 0.1)
				(type default)
			)
			(layer "B.Fab")
		)
		(fp_line
			(start 0.508 -0.3048)
			(end 0.508 0.3048)
			(stroke
				(width 0.1)
				(type default)
			)
			(layer "B.Fab")
		)
		(fp_line
			(start -0.508 0.3048)
			(end -0.508 -0.3048)
			(stroke
				(width 0.1)
				(type default)
			)
			(layer "B.Fab")
		)
		(fp_line
			(start -0.508 -0.3048)
			(end 0.508 -0.3048)
			(stroke
				(width 0.1)
				(type default)
			)
			(layer "B.Fab")
		)
		(pad "1" smd rect
			(at 0.5334 0)
			(size 0.7112 0.6096)
			(layers "B.Cu" "B.Mask" "B.Paste")
			(net "UNNAMED_6_LM75BDPTSSOP8_I81_A1")
		)
		(pad "2" smd rect
			(at -0.5334 0)
			(size 0.7112 0.6096)
			(layers "B.Cu" "B.Mask" "B.Paste")
			(net "SG")
		)
		(zone
			(layer "B.Cu")
			(hatch none 0.5)
			(connect_pads
				(clearance 0)
			)
			(min_thickness 0.25)
			(keepout
				(tracks allowed)
				(vias not_allowed)
				(pads allowed)
				(copperpour not_allowed)
				(footprints allowed)
			)
			(placement
				(enabled no)
				(sheetname "")
			)
			(fill
				(thermal_gap 0.5)
				(thermal_bridge_width 0.5)
				(island_removal_mode 0)
			)
			(polygon
				(pts
					(xy 162.4838 -25.6032) (xy 162.6362 -25.6032) (xy 162.6362 -26.2128) (xy 162.4838 -26.2128)
				)
			)
		)
		(zone
			(layer "B.Cu")
			(hatch none 0.5)
			(connect_pads
				(clearance 0)
			)
			(min_thickness 0.25)
			(keepout
				(tracks not_allowed)
				(vias allowed)
				(pads allowed)
				(copperpour not_allowed)
				(footprints allowed)
			)
			(placement
				(enabled no)
				(sheetname "")
			)
			(fill
				(thermal_gap 0.5)
				(thermal_bridge_width 0.5)
				(island_removal_mode 0)
			)
			(polygon
				(pts
					(xy 162.4838 -25.6032) (xy 162.6362 -25.6032) (xy 162.6362 -26.2128) (xy 162.4838 -26.2128)
				)
			)
		)
	)
	(footprint ""
		(layer "B.Cu")
		(at 156.083 -104.521 90)
		(property "Reference" "R169"
			(at -1.27 1.23063 270)
			(unlocked yes)
			(layer "B.SilkS")
			(effects
				(font
					(size 0.7874 0.5842)
					(thickness 0.1524)
				)
				(justify mirror)
			)
		)
		(property "Value" "VAL*"
			(at -0.02032 2.13233 90)
			(unlocked yes)
			(layer "B.Fab")
			(hide yes)
			(effects
				(font
					(size 0.7874 0.5842)
					(thickness 0.1524)
				)
				(justify mirror)
			)
		)
		(property "Tolerance" "TOL*"
			(at -0.044704 3.05435 90)
			(unlocked yes)
			(layer "Cmts.User")
			(hide yes)
			(effects
				(font
					(size 0.7874 0.5842)
					(thickness 0.1524)
				)
				(justify mirror)
			)
		)
		(property "User Part Number" "PARTNUM*"
			(at -0.02032 4.024884 90)
			(unlocked yes)
			(layer "Cmts.User")
			(hide yes)
			(effects
				(font
					(size 0.7874 0.5842)
					(thickness 0.1524)
				)
				(justify mirror)
			)
		)
		(property "Device Type" "RESISTOR-G155-13300-01,330OHM,A"
			(at -0.008382 1.210564 90)
			(unlocked yes)
			(layer "B.Fab")
			(hide yes)
			(effects
				(font
					(size 0.7874 0.5842)
					(thickness 0.1524)
				)
				(justify mirror)
			)
		)
		(duplicate_pad_numbers_are_jumpers no)
		(fp_line
			(start 1.143 -0.5588)
			(end 1.143 0.5588)
			(stroke
				(width 0.1)
				(type default)
			)
			(layer "B.SilkS")
		)
		(fp_line
			(start -1.143 -0.5588)
			(end 1.143 -0.5588)
			(stroke
				(width 0.1)
				(type default)
			)
			(layer "B.SilkS")
		)
		(fp_line
			(start 1.143 0.5588)
			(end -1.143 0.5588)
			(stroke
				(width 0.1)
				(type default)
			)
			(layer "B.SilkS")
		)
		(fp_line
			(start -1.143 0.5588)
			(end -1.143 -0.5588)
			(stroke
				(width 0.1)
				(type default)
			)
			(layer "B.SilkS")
		)
		(fp_rect
			(start -1.143 0.5588)
			(end 1.143 -0.5588)
			(stroke
				(width 0)
				(type default)
			)
			(fill no)
			(layer "B.CrtYd")
		)
		(fp_line
			(start 0.508 -0.3048)
			(end 0.508 0.3048)
			(stroke
				(width 0.1)
				(type default)
			)
			(layer "B.Fab")
		)
		(fp_line
			(start -0.508 -0.3048)
			(end 0.508 -0.3048)
			(stroke
				(width 0.1)
				(type default)
			)
			(layer "B.Fab")
		)
		(fp_line
			(start 0.508 0.3048)
			(end -0.508 0.3048)
			(stroke
				(width 0.1)
				(type default)
			)
			(layer "B.Fab")
		)
		(fp_line
			(start -0.508 0.3048)
			(end -0.508 -0.3048)
			(stroke
				(width 0.1)
				(type default)
			)
			(layer "B.Fab")
		)
		(pad "1" smd rect
			(at 0.5334 0 270)
			(size 0.7112 0.6096)
			(layers "B.Cu" "B.Mask" "B.Paste")
			(net "UNNAMED_14_OPTICAL_I289_A")
		)
		(pad "2" smd rect
			(at -0.5334 0 270)
			(size 0.7112 0.6096)
			(layers "B.Cu" "B.Mask" "B.Paste")
			(net "XP3R3V_FT4232")
		)
		(zone
			(layer "B.Cu")
			(hatch none 0.5)
			(connect_pads
				(clearance 0)
			)
			(min_thickness 0.25)
			(keepout
				(tracks allowed)
				(vias not_allowed)
				(pads allowed)
				(copperpour not_allowed)
				(footprints allowed)
			)
			(placement
				(enabled no)
				(sheetname "")
			)
			(fill
				(thermal_gap 0.5)
				(thermal_bridge_width 0.5)
				(island_removal_mode 0)
			)
			(polygon
				(pts
					(xy 156.3878 -104.4448) (xy 156.3878 -104.5972) (xy 155.7782 -104.5972) (xy 155.7782 -104.4448)
				)
			)
		)
	)
	(footprint ""
		(layer "B.Cu")
		(at 33.77438 -17.9832)
		(property "Reference" "R176"
			(at 3.18262 1.25857 0)
			(unlocked yes)
			(layer "B.SilkS")
			(effects
				(font
					(size 0.7874 0.5842)
					(thickness 0.1524)
				)
				(justify mirror)
			)
		)
		(property "Value" "VAL*"
			(at -0.02032 2.13233 0)
			(unlocked yes)
			(layer "B.Fab")
			(hide yes)
			(effects
				(font
					(size 0.7874 0.5842)
					(thickness 0.1524)
				)
				(justify mirror)
			)
		)
		(property "Tolerance" "TOL*"
			(at -0.044704 3.05435 0)
			(unlocked yes)
			(layer "Cmts.User")
			(hide yes)
			(effects
				(font
					(size 0.7874 0.5842)
					(thickness 0.1524)
				)
				(justify mirror)
			)
		)
		(property "User Part Number" "PARTNUM*"
			(at -0.02032 4.024884 0)
			(unlocked yes)
			(layer "Cmts.User")
			(hide yes)
			(effects
				(font
					(size 0.7874 0.5842)
					(thickness 0.1524)
				)
				(justify mirror)
			)
		)
		(property "Device Type" "RESISTOR-G155-133R0-01,33OHM,1%"
			(at -0.008382 1.210564 0)
			(unlocked yes)
			(layer "B.Fab")
			(hide yes)
			(effects
				(font
					(size 0.7874 0.5842)
					(thickness 0.1524)
				)
				(justify mirror)
			)
		)
		(duplicate_pad_numbers_are_jumpers no)
		(fp_line
			(start -1.143 -0.5588)
			(end 1.143 -0.5588)
			(stroke
				(width 0.1)
				(type default)
			)
			(layer "B.SilkS")
		)
		(fp_line
			(start -1.143 0.5588)
			(end -1.143 -0.5588)
			(stroke
				(width 0.1)
				(type default)
			)
			(layer "B.SilkS")
		)
		(fp_line
			(start 1.143 -0.5588)
			(end 1.143 0.5588)
			(stroke
				(width 0.1)
				(type default)
			)
			(layer "B.SilkS")
		)
		(fp_line
			(start 1.143 0.5588)
			(end -1.143 0.5588)
			(stroke
				(width 0.1)
				(type default)
			)
			(layer "B.SilkS")
		)
		(fp_rect
			(start -1.143 0.5588)
			(end 1.143 -0.5588)
			(stroke
				(width 0)
				(type default)
			)
			(fill no)
			(layer "B.CrtYd")
		)
		(fp_line
			(start -0.508 -0.3048)
			(end 0.508 -0.3048)
			(stroke
				(width 0.1)
				(type default)
			)
			(layer "B.Fab")
		)
		(fp_line
			(start -0.508 0.3048)
			(end -0.508 -0.3048)
			(stroke
				(width 0.1)
				(type default)
			)
			(layer "B.Fab")
		)
		(fp_line
			(start 0.508 -0.3048)
			(end 0.508 0.3048)
			(stroke
				(width 0.1)
				(type default)
			)
			(layer "B.Fab")
		)
		(fp_line
			(start 0.508 0.3048)
			(end -0.508 0.3048)
			(stroke
				(width 0.1)
				(type default)
			)
			(layer "B.Fab")
		)
		(pad "1" smd rect
			(at 0.5334 0 180)
			(size 0.7112 0.6096)
			(layers "B.Cu" "B.Mask" "B.Paste")
			(net "PCIE_SMCLK")
		)
		(pad "2" smd rect
			(at -0.5334 0 180)
			(size 0.7112 0.6096)
			(layers "B.Cu" "B.Mask" "B.Paste")
			(net "EEPROM_SCL")
		)
		(zone
			(layer "B.Cu")
			(hatch none 0.5)
			(connect_pads
				(clearance 0)
			)
			(min_thickness 0.25)
			(keepout
				(tracks allowed)
				(vias not_allowed)
				(pads allowed)
				(copperpour not_allowed)
				(footprints allowed)
			)
			(placement
				(enabled no)
				(sheetname "")
			)
			(fill
				(thermal_gap 0.5)
				(thermal_bridge_width 0.5)
				(island_removal_mode 0)
			)
			(polygon
				(pts
					(xy 33.69818 -17.6784) (xy 33.85058 -17.6784) (xy 33.85058 -18.288) (xy 33.69818 -18.288)
				)
			)
		)
	)
	(footprint ""
		(layer "B.Cu")
		(at 21.844 -20.6248 -90)
		(property "Reference" "C1"
			(at 0.9398 -1.10363 270)
			(unlocked yes)
			(layer "B.SilkS")
			(effects
				(font
					(size 0.7874 0.5842)
					(thickness 0.1524)
				)
				(justify mirror)
			)
		)
		(property "Value" "VAL*"
			(at -0.0762 2.067306 270)
			(unlocked yes)
			(layer "B.Fab")
			(hide yes)
			(effects
				(font
					(size 0.7874 0.5842)
					(thickness 0.1524)
				)
				(justify mirror)
			)
		)
		(property "Device Type" "CAPACITOR-G105-0B104-EK,0.1UF,A"
			(at -0.0508 1.127506 270)
			(unlocked yes)
			(layer "B.Fab")
			(hide yes)
			(effects
				(font
					(size 0.7874 0.5842)
					(thickness 0.1524)
				)
				(justify mirror)
			)
		)
		(property "User Part Number" "PARTNUM*"
			(at -0.1016 4.023106 270)
			(unlocked yes)
			(layer "Cmts.User")
			(hide yes)
			(effects
				(font
					(size 0.7874 0.5842)
					(thickness 0.1524)
				)
				(justify mirror)
			)
		)
		(property "Tolerance" "TOL*"
			(at -0.0762 3.032506 270)
			(unlocked yes)
			(layer "Cmts.User")
			(hide yes)
			(effects
				(font
					(size 0.7874 0.5842)
					(thickness 0.1524)
				)
				(justify mirror)
			)
		)
		(duplicate_pad_numbers_are_jumpers no)
		(fp_line
			(start -1.143 0.5588)
			(end -1.143 -0.5588)
			(stroke
				(width 0.1)
				(type default)
			)
			(layer "B.SilkS")
		)
		(fp_line
			(start 1.143 0.5588)
			(end -1.143 0.5588)
			(stroke
				(width 0.1)
				(type default)
			)
			(layer "B.SilkS")
		)
		(fp_line
			(start -1.143 -0.5588)
			(end 1.143 -0.5588)
			(stroke
				(width 0.1)
				(type default)
			)
			(layer "B.SilkS")
		)
		(fp_line
			(start 1.143 -0.5588)
			(end 1.143 0.5588)
			(stroke
				(width 0.1)
				(type default)
			)
			(layer "B.SilkS")
		)
		(fp_rect
			(start 1.143 0.5588)
			(end -1.143 -0.5588)
			(stroke
				(width 0)
				(type default)
			)
			(fill no)
			(layer "B.CrtYd")
		)
		(fp_line
			(start -0.508 0.3048)
			(end -0.508 -0.3048)
			(stroke
				(width 0.1)
				(type default)
			)
			(layer "B.Fab")
		)
		(fp_line
			(start 0.508 0.3048)
			(end -0.508 0.3048)
			(stroke
				(width 0.1)
				(type default)
			)
			(layer "B.Fab")
		)
		(fp_line
			(start -0.508 -0.3048)
			(end 0.508 -0.3048)
			(stroke
				(width 0.1)
				(type default)
			)
			(layer "B.Fab")
		)
		(fp_line
			(start 0.508 -0.3048)
			(end 0.508 0.3048)
			(stroke
				(width 0.1)
				(type default)
			)
			(layer "B.Fab")
		)
		(pad "1" smd rect
			(at 0.5334 0 90)
			(size 0.7112 0.6096)
			(layers "B.Cu" "B.Mask" "B.Paste")
			(net "XP3R3V_FPGA")
		)
		(pad "2" smd rect
			(at -0.5334 0 90)
			(size 0.7112 0.6096)
			(layers "B.Cu" "B.Mask" "B.Paste")
			(net "SG")
		)
		(zone
			(layer "B.Cu")
			(hatch none 0.5)
			(connect_pads
				(clearance 0)
			)
			(min_thickness 0.25)
			(keepout
				(tracks not_allowed)
				(vias allowed)
				(pads allowed)
				(copperpour not_allowed)
				(footprints allowed)
			)
			(placement
				(enabled no)
				(sheetname "")
			)
			(fill
				(thermal_gap 0.5)
				(thermal_bridge_width 0.5)
				(island_removal_mode 0)
			)
			(polygon
				(pts
					(xy 21.5392 -20.5486) (xy 22.1488 -20.5486) (xy 22.1488 -20.701) (xy 21.5392 -20.701)
				)
			)
		)
		(zone
			(layer "B.Cu")
			(hatch none 0.5)
			(connect_pads
				(clearance 0)
			)
			(min_thickness 0.25)
			(keepout
				(tracks allowed)
				(vias not_allowed)
				(pads allowed)
				(copperpour not_allowed)
				(footprints allowed)
			)
			(placement
				(enabled no)
				(sheetname "")
			)
			(fill
				(thermal_gap 0.5)
				(thermal_bridge_width 0.5)
				(island_removal_mode 0)
			)
			(polygon
				(pts
					(xy 21.5392 -20.5486) (xy 22.1488 -20.5486) (xy 22.1488 -20.701) (xy 21.5392 -20.701)
				)
			)
		)
	)
	(footprint ""
		(layer "B.Cu")
		(at 141.097 -59.563 -90)
		(property "Reference" "R246"
			(at -3.175 0.16637 270)
			(unlocked yes)
			(layer "B.SilkS")
			(effects
				(font
					(size 0.7874 0.5842)
					(thickness 0.1524)
				)
				(justify mirror)
			)
		)
		(property "Value" "VAL*"
			(at -0.02032 2.13233 270)
			(unlocked yes)
			(layer "B.Fab")
			(hide yes)
			(effects
				(font
					(size 0.7874 0.5842)
					(thickness 0.1524)
				)
				(justify mirror)
			)
		)
		(property "Device Type" "RESISTOR-A155-05101-DL,5.1KOHMA"
			(at -0.008382 1.210564 270)
			(unlocked yes)
			(layer "B.Fab")
			(hide yes)
			(effects
				(font
					(size 0.7874 0.5842)
					(thickness 0.1524)
				)
				(justify mirror)
			)
		)
		(property "User Part Number" "PARTNUM*"
			(at -0.02032 4.024884 270)
			(unlocked yes)
			(layer "Cmts.User")
			(hide yes)
			(effects
				(font
					(size 0.7874 0.5842)
					(thickness 0.1524)
				)
				(justify mirror)
			)
		)
		(property "Tolerance" "TOL*"
			(at -0.044704 3.05435 270)
			(unlocked yes)
			(layer "Cmts.User")
			(hide yes)
			(effects
				(font
					(size 0.7874 0.5842)
					(thickness 0.1524)
				)
				(justify mirror)
			)
		)
		(duplicate_pad_numbers_are_jumpers no)
		(fp_line
			(start -1.143 0.5588)
			(end -1.143 -0.5588)
			(stroke
				(width 0.1)
				(type default)
			)
			(layer "B.SilkS")
		)
		(fp_line
			(start 1.143 0.5588)
			(end -1.143 0.5588)
			(stroke
				(width 0.1)
				(type default)
			)
			(layer "B.SilkS")
		)
		(fp_line
			(start -1.143 -0.5588)
			(end 1.143 -0.5588)
			(stroke
				(width 0.1)
				(type default)
			)
			(layer "B.SilkS")
		)
		(fp_line
			(start 1.143 -0.5588)
			(end 1.143 0.5588)
			(stroke
				(width 0.1)
				(type default)
			)
			(layer "B.SilkS")
		)
		(fp_rect
			(start 1.143 0.5588)
			(end -1.143 -0.5588)
			(stroke
				(width 0)
				(type default)
			)
			(fill no)
			(layer "B.CrtYd")
		)
		(fp_line
			(start -0.508 0.3048)
			(end -0.508 -0.3048)
			(stroke
				(width 0.1)
				(type default)
			)
			(layer "B.Fab")
		)
		(fp_line
			(start 0.508 0.3048)
			(end -0.508 0.3048)
			(stroke
				(width 0.1)
				(type default)
			)
			(layer "B.Fab")
		)
		(fp_line
			(start -0.508 -0.3048)
			(end 0.508 -0.3048)
			(stroke
				(width 0.1)
				(type default)
			)
			(layer "B.Fab")
		)
		(fp_line
			(start 0.508 -0.3048)
			(end 0.508 0.3048)
			(stroke
				(width 0.1)
				(type default)
			)
			(layer "B.Fab")
		)
		(pad "1" smd rect
			(at 0.5334 0 90)
			(size 0.7112 0.6096)
			(layers "B.Cu" "B.Mask" "B.Paste")
			(net "UNNAMED_523_CAPACITOR_I7_1")
		)
		(pad "2" smd rect
			(at -0.5334 0 90)
			(size 0.7112 0.6096)
			(layers "B.Cu" "B.Mask" "B.Paste")
			(net "SG")
		)
		(zone
			(layer "B.Cu")
			(hatch none 0.5)
			(connect_pads
				(clearance 0)
			)
			(min_thickness 0.25)
			(keepout
				(tracks allowed)
				(vias not_allowed)
				(pads allowed)
				(copperpour not_allowed)
				(footprints allowed)
			)
			(placement
				(enabled no)
				(sheetname "")
			)
			(fill
				(thermal_gap 0.5)
				(thermal_bridge_width 0.5)
				(island_removal_mode 0)
			)
			(polygon
				(pts
					(xy 140.7922 -59.4868) (xy 141.4018 -59.4868) (xy 141.4018 -59.6392) (xy 140.7922 -59.6392)
				)
			)
		)
	)
	(footprint ""
		(layer "B.Cu")
		(at 72.39 -58.674 90)
		(property "Reference" "R357"
			(at 3.175 7.32663 270)
			(unlocked yes)
			(layer "B.SilkS")
			(effects
				(font
					(size 0.7874 0.5842)
					(thickness 0.1524)
				)
				(justify mirror)
			)
		)
		(property "Value" "VAL*"
			(at -0.0508 3.159506 90)
			(unlocked yes)
			(layer "B.Fab")
			(hide yes)
			(effects
				(font
					(size 0.7874 0.5842)
					(thickness 0.1524)
				)
				(justify mirror)
			)
		)
		(property "Tolerance" "TOL*"
			(at -0.0508 4.124706 90)
			(unlocked yes)
			(layer "Cmts.User")
			(hide yes)
			(effects
				(font
					(size 0.7874 0.5842)
					(thickness 0.1524)
				)
				(justify mirror)
			)
		)
		(property "User Part Number" "PARTNUM*"
			(at -0.0508 5.089906 90)
			(unlocked yes)
			(layer "Cmts.User")
			(hide yes)
			(effects
				(font
					(size 0.7874 0.5842)
					(thickness 0.1524)
				)
				(justify mirror)
			)
		)
		(property "Device Type" "RESISTOR-G157-100R0-J0,0OHM,-"
			(at 0 2.194306 90)
			(unlocked yes)
			(layer "B.Fab")
			(hide yes)
			(effects
				(font
					(size 0.7874 0.5842)
					(thickness 0.1524)
				)
				(justify mirror)
			)
		)
		(duplicate_pad_numbers_are_jumpers no)
		(fp_line
			(start 1.5748 -0.9398)
			(end 1.5748 0.9398)
			(stroke
				(width 0.1)
				(type default)
			)
			(layer "B.SilkS")
		)
		(fp_line
			(start -1.5748 -0.9398)
			(end 1.5748 -0.9398)
			(stroke
				(width 0.1)
				(type default)
			)
			(layer "B.SilkS")
		)
		(fp_line
			(start 1.5748 0.9398)
			(end -1.5748 0.9398)
			(stroke
				(width 0.1)
				(type default)
			)
			(layer "B.SilkS")
		)
		(fp_line
			(start -1.5748 0.9398)
			(end -1.5748 -0.9398)
			(stroke
				(width 0.1)
				(type default)
			)
			(layer "B.SilkS")
		)
		(fp_rect
			(start 1.5748 0.9398)
			(end -1.5748 -0.9398)
			(stroke
				(width 0)
				(type default)
			)
			(fill no)
			(layer "B.CrtYd")
		)
		(fp_line
			(start 1.016 -0.635)
			(end 1.016 0.635)
			(stroke
				(width 0.1)
				(type default)
			)
			(layer "B.Fab")
		)
		(fp_line
			(start -1.016 -0.635)
			(end 1.016 -0.635)
			(stroke
				(width 0.1)
				(type default)
			)
			(layer "B.Fab")
		)
		(fp_line
			(start 1.016 0.635)
			(end -1.016 0.635)
			(stroke
				(width 0.1)
				(type default)
			)
			(layer "B.Fab")
		)
		(fp_line
			(start -1.016 0.635)
			(end -1.016 -0.635)
			(stroke
				(width 0.1)
				(type default)
			)
			(layer "B.Fab")
		)
		(pad "1" smd rect
			(at 0.8382 0 270)
			(size 0.9652 1.3716)
			(layers "B.Cu" "B.Mask" "B.Paste")
			(net "XP5R0V_MAC")
		)
		(pad "2" smd rect
			(at -0.8382 0 270)
			(size 0.9652 1.3716)
			(layers "B.Cu" "B.Mask" "B.Paste")
			(net "UNNAMED_527_FUSE_I244_1")
		)
		(zone
			(layer "B.Cu")
			(hatch none 0.5)
			(connect_pads
				(clearance 0)
			)
			(min_thickness 0.25)
			(keepout
				(tracks not_allowed)
				(vias allowed)
				(pads allowed)
				(copperpour not_allowed)
				(footprints allowed)
			)
			(placement
				(enabled no)
				(sheetname "")
			)
			(fill
				(thermal_gap 0.5)
				(thermal_bridge_width 0.5)
				(island_removal_mode 0)
			)
			(polygon
				(pts
					(xy 73.025 -58.9026) (xy 71.755 -58.9026) (xy 71.755 -58.4454) (xy 73.025 -58.4454)
				)
			)
		)
		(zone
			(layer "B.Cu")
			(hatch none 0.5)
			(connect_pads
				(clearance 0)
			)
			(min_thickness 0.25)
			(keepout
				(tracks allowed)
				(vias not_allowed)
				(pads allowed)
				(copperpour not_allowed)
				(footprints allowed)
			)
			(placement
				(enabled no)
				(sheetname "")
			)
			(fill
				(thermal_gap 0.5)
				(thermal_bridge_width 0.5)
				(island_removal_mode 0)
			)
			(polygon
				(pts
					(xy 73.025 -58.9026) (xy 71.755 -58.9026) (xy 71.755 -58.4454) (xy 73.025 -58.4454)
				)
			)
		)
	)
	(footprint ""
		(layer "B.Cu")
		(at 143.383 -59.563 90)
		(property "Reference" "C263"
			(at 3.429 0.08763 270)
			(unlocked yes)
			(layer "B.SilkS")
			(effects
				(font
					(size 0.7874 0.5842)
					(thickness 0.1524)
				)
				(justify mirror)
			)
		)
		(property "Value" "VAL*"
			(at -0.193548 2.13614 90)
			(unlocked yes)
			(layer "B.Fab")
			(hide yes)
			(effects
				(font
					(size 0.7874 0.5842)
					(thickness 0.1524)
				)
				(justify mirror)
			)
		)
		(property "User Part Number" "PARTNUM*"
			(at -0.216154 4.185666 90)
			(unlocked yes)
			(layer "Cmts.User")
			(hide yes)
			(effects
				(font
					(size 0.7874 0.5842)
					(thickness 0.1524)
				)
				(justify mirror)
			)
		)
		(property "Device Type" "CAPACITOR-G104-0B472-EK,4700PFA"
			(at -0.184404 1.180592 90)
			(unlocked yes)
			(layer "B.Fab")
			(hide yes)
			(effects
				(font
					(size 0.7874 0.5842)
					(thickness 0.1524)
				)
				(justify mirror)
			)
		)
		(property "Tolerance" "TOL*"
			(at -0.216154 3.1496 90)
			(unlocked yes)
			(layer "Cmts.User")
			(hide yes)
			(effects
				(font
					(size 0.7874 0.5842)
					(thickness 0.1524)
				)
				(justify mirror)
			)
		)
		(duplicate_pad_numbers_are_jumpers no)
		(fp_line
			(start 0.671322 -0.4445)
			(end -0.671322 -0.4445)
			(stroke
				(width 0.1)
				(type default)
			)
			(layer "B.SilkS")
		)
		(fp_line
			(start -0.671322 -0.4445)
			(end -0.671322 0.4445)
			(stroke
				(width 0.1)
				(type default)
			)
			(layer "B.SilkS")
		)
		(fp_line
			(start 0.671322 0.4445)
			(end 0.671322 -0.4445)
			(stroke
				(width 0.1)
				(type default)
			)
			(layer "B.SilkS")
		)
		(fp_line
			(start -0.671322 0.4445)
			(end 0.671322 0.4445)
			(stroke
				(width 0.1)
				(type default)
			)
			(layer "B.SilkS")
		)
		(fp_rect
			(start 0.671322 0.4445)
			(end -0.671322 -0.4445)
			(stroke
				(width 0)
				(type default)
			)
			(fill no)
			(layer "B.CrtYd")
		)
		(fp_line
			(start 0.31496 -0.1651)
			(end 0.31496 0.1651)
			(stroke
				(width 0.1)
				(type default)
			)
			(layer "B.Fab")
		)
		(fp_line
			(start -0.31496 -0.1651)
			(end 0.31496 -0.1651)
			(stroke
				(width 0.1)
				(type default)
			)
			(layer "B.Fab")
		)
		(fp_line
			(start 0.31496 0.1651)
			(end -0.31496 0.1651)
			(stroke
				(width 0.1)
				(type default)
			)
			(layer "B.Fab")
		)
		(fp_line
			(start -0.31496 0.1651)
			(end -0.31496 -0.1651)
			(stroke
				(width 0.1)
				(type default)
			)
			(layer "B.Fab")
		)
		(pad "1" smd rect
			(at 0.264922 0 270)
			(size 0.3048 0.381)
			(layers "B.Cu" "B.Mask" "B.Paste")
			(net "UNNAMED_523_CAPACITOR_I9_1")
		)
		(pad "2" smd rect
			(at -0.264922 0 270)
			(size 0.3048 0.381)
			(layers "B.Cu" "B.Mask" "B.Paste")
			(net "XP1R0V_AGND")
		)
		(zone
			(layer "B.Cu")
			(hatch none 0.5)
			(connect_pads
				(clearance 0)
			)
			(min_thickness 0.25)
			(keepout
				(tracks allowed)
				(vias not_allowed)
				(pads allowed)
				(copperpour not_allowed)
				(footprints allowed)
			)
			(placement
				(enabled no)
				(sheetname "")
			)
			(fill
				(thermal_gap 0.5)
				(thermal_bridge_width 0.5)
				(island_removal_mode 0)
			)
			(polygon
				(pts
					(xy 143.1925 -59.675522) (xy 143.5735 -59.675522) (xy 143.5735 -59.450478) (xy 143.1925 -59.450478)
				)
			)
		)
		(zone
			(layer "B.Cu")
			(hatch none 0.5)
			(connect_pads
				(clearance 0)
			)
			(min_thickness 0.25)
			(keepout
				(tracks not_allowed)
				(vias allowed)
				(pads allowed)
				(copperpour not_allowed)
				(footprints allowed)
			)
			(placement
				(enabled no)
				(sheetname "")
			)
			(fill
				(thermal_gap 0.5)
				(thermal_bridge_width 0.5)
				(island_removal_mode 0)
			)
			(polygon
				(pts
					(xy 143.5735 -59.675522) (xy 143.5735 -59.450478) (xy 143.1925 -59.450478) (xy 143.1925 -59.675522)
				)
			)
		)
	)
	(footprint ""
		(layer "B.Cu")
		(at 107.347258 -39.823136 180)
		(property "Reference" "C141"
			(at 41.274238 -1.251966 0)
			(unlocked yes)
			(layer "B.SilkS")
			(effects
				(font
					(size 0.635 0.4064)
					(thickness 0.1524)
				)
				(justify mirror)
			)
		)
		(property "Value" "VAL*"
			(at 0 3.718306 180)
			(unlocked yes)
			(layer "B.Fab")
			(hide yes)
			(effects
				(font
					(size 0.7874 0.5842)
					(thickness 0.127)
				)
				(justify mirror)
			)
		)
		(property "Device Type" "CAPACITOR-G105-0B104-CK,0.1UF,A"
			(at 0 1.432306 180)
			(unlocked yes)
			(layer "B.Fab")
			(hide yes)
			(effects
				(font
					(size 0.7874 0.5842)
					(thickness 0.127)
				)
				(justify mirror)
			)
		)
		(property "User Part Number" "PARTNUM*"
			(at 0 2.575306 180)
			(unlocked yes)
			(layer "Cmts.User")
			(hide yes)
			(effects
				(font
					(size 0.7874 0.5842)
					(thickness 0.127)
				)
				(justify mirror)
			)
		)
		(property "Tolerance" "TOL*"
			(at 0 4.861306 180)
			(unlocked yes)
			(layer "Cmts.User")
			(hide yes)
			(effects
				(font
					(size 0.7874 0.5842)
					(thickness 0.127)
				)
				(justify mirror)
			)
		)
		(duplicate_pad_numbers_are_jumpers no)
		(fp_line
			(start 0.970026 0.4699)
			(end 0.970026 -0.4699)
			(stroke
				(width 0.1)
				(type default)
			)
			(layer "B.SilkS")
		)
		(fp_line
			(start 0.970026 -0.4699)
			(end -0.970026 -0.4699)
			(stroke
				(width 0.1)
				(type default)
			)
			(layer "B.SilkS")
		)
		(fp_line
			(start -0.970026 0.4699)
			(end 0.970026 0.4699)
			(stroke
				(width 0.1)
				(type default)
			)
			(layer "B.SilkS")
		)
		(fp_line
			(start -0.970026 -0.4699)
			(end -0.970026 0.4699)
			(stroke
				(width 0.1)
				(type default)
			)
			(layer "B.SilkS")
		)
		(fp_poly
			(pts
				(xy 0.970026 0.4699) (xy -0.970026 0.4699) (xy -0.970026 -0.4699) (xy 0.970026 -0.4699)
			)
			(stroke
				(width 0)
				(type default)
			)
			(fill no)
			(layer "B.CrtYd")
		)
		(fp_line
			(start 0.508 0.3048)
			(end 0.508 -0.3048)
			(stroke
				(width 0.1)
				(type default)
			)
			(layer "B.Fab")
		)
		(fp_line
			(start 0.508 -0.3048)
			(end -0.508 -0.3048)
			(stroke
				(width 0.1)
				(type default)
			)
			(layer "B.Fab")
		)
		(fp_line
			(start -0.508 0.3048)
			(end 0.508 0.3048)
			(stroke
				(width 0.1)
				(type default)
			)
			(layer "B.Fab")
		)
		(fp_line
			(start -0.508 -0.3048)
			(end -0.508 0.3048)
			(stroke
				(width 0.1)
				(type default)
			)
			(layer "B.Fab")
		)
		(pad "1" smd circle
			(at 0.500126 0)
			(size 0.635 0.635)
			(layers "B.Cu" "B.Mask" "B.Paste")
			(net "XP1R0V_FPGA_VCCINT")
		)
		(pad "2" smd circle
			(at -0.500126 0)
			(size 0.635 0.635)
			(layers "B.Cu" "B.Mask" "B.Paste")
			(net "SG")
		)
	)
	(footprint ""
		(layer "B.Cu")
		(at 144.9832 -75.3364 -90)
		(property "Reference" "CR6"
			(at 1.1684 -3.44043 270)
			(unlocked yes)
			(layer "B.SilkS")
			(effects
				(font
					(size 0.7874 0.5842)
					(thickness 0.1524)
				)
				(justify mirror)
			)
		)
		(property "Value" ""
			(at 0 0 90)
			(layer "B.Fab")
			(effects
				(font
					(size 1.27 1.27)
				)
				(justify mirror)
			)
		)
		(property "User Part Number" "PARTNUM*"
			(at -0.254 3.718306 270)
			(unlocked yes)
			(layer "Cmts.User")
			(hide yes)
			(effects
				(font
					(size 0.7874 0.5842)
					(thickness 0.1524)
				)
				(justify mirror)
			)
		)
		(property "Device Type" "DIODE_4_V1-G122-10123-01"
			(at -0.254 2.702306 270)
			(unlocked yes)
			(layer "B.Fab")
			(hide yes)
			(effects
				(font
					(size 0.7874 0.5842)
					(thickness 0.1524)
				)
				(justify mirror)
			)
		)
		(duplicate_pad_numbers_are_jumpers no)
		(fp_line
			(start -2.0828 1.7018)
			(end 2.0828 1.7018)
			(stroke
				(width 0.1)
				(type default)
			)
			(layer "B.SilkS")
		)
		(fp_line
			(start 2.0828 1.7018)
			(end 2.0828 -1.7018)
			(stroke
				(width 0.1)
				(type default)
			)
			(layer "B.SilkS")
		)
		(fp_line
			(start -2.0828 -1.7018)
			(end -2.0828 1.7018)
			(stroke
				(width 0.1)
				(type default)
			)
			(layer "B.SilkS")
		)
		(fp_line
			(start 2.0828 -1.7018)
			(end -2.0828 -1.7018)
			(stroke
				(width 0.1)
				(type default)
			)
			(layer "B.SilkS")
		)
		(fp_poly
			(pts
				(arc
					(start 2.6162 -1.27)
					(mid 2.6162 -0.508)
					(end 2.6162 -1.27)
				)
			)
			(stroke
				(width 0)
				(type default)
			)
			(fill yes)
			(layer "B.SilkS")
		)
		(fp_rect
			(start -2.3368 1.9304)
			(end 2.3368 -1.9304)
			(stroke
				(width 0)
				(type default)
			)
			(fill no)
			(layer "B.CrtYd")
		)
		(fp_line
			(start -0.6477 1.42875)
			(end 0.6477 1.42875)
			(stroke
				(width 0.1)
				(type default)
			)
			(layer "B.Fab")
		)
		(fp_line
			(start 0.6477 1.42875)
			(end 0.6477 -1.42875)
			(stroke
				(width 0.1)
				(type default)
			)
			(layer "B.Fab")
		)
		(fp_line
			(start -1.143 1.1811)
			(end -0.6477 1.1811)
			(stroke
				(width 0.1)
				(type default)
			)
			(layer "B.Fab")
		)
		(fp_line
			(start -0.6477 1.1811)
			(end -0.6477 0.7239)
			(stroke
				(width 0.1)
				(type default)
			)
			(layer "B.Fab")
		)
		(fp_line
			(start 0.6477 1.1811)
			(end 1.143 1.1811)
			(stroke
				(width 0.1)
				(type default)
			)
			(layer "B.Fab")
		)
		(fp_line
			(start 1.143 1.1811)
			(end 1.143 0.7239)
			(stroke
				(width 0.1)
				(type default)
			)
			(layer "B.Fab")
		)
		(fp_line
			(start -1.143 0.7239)
			(end -1.143 1.1811)
			(stroke
				(width 0.1)
				(type default)
			)
			(layer "B.Fab")
		)
		(fp_line
			(start -0.6477 0.7239)
			(end -1.143 0.7239)
			(stroke
				(width 0.1)
				(type default)
			)
			(layer "B.Fab")
		)
		(fp_line
			(start 0.6477 0.7239)
			(end 0.6477 1.1811)
			(stroke
				(width 0.1)
				(type default)
			)
			(layer "B.Fab")
		)
		(fp_line
			(start 1.143 0.7239)
			(end 0.6477 0.7239)
			(stroke
				(width 0.1)
				(type default)
			)
			(layer "B.Fab")
		)
		(fp_line
			(start 0.6477 -0.3175)
			(end 1.143 -0.3175)
			(stroke
				(width 0.1)
				(type default)
			)
			(layer "B.Fab")
		)
		(fp_line
			(start 1.143 -0.3175)
			(end 1.143 -1.1811)
			(stroke
				(width 0.1)
				(type default)
			)
			(layer "B.Fab")
		)
		(fp_line
			(start -1.143 -0.7239)
			(end -0.6477 -0.7239)
			(stroke
				(width 0.1)
				(type default)
			)
			(layer "B.Fab")
		)
		(fp_line
			(start -0.6477 -0.7239)
			(end -0.6477 -1.1811)
			(stroke
				(width 0.1)
				(type default)
			)
			(layer "B.Fab")
		)
		(fp_line
			(start -1.143 -1.1811)
			(end -1.143 -0.7239)
			(stroke
				(width 0.1)
				(type default)
			)
			(layer "B.Fab")
		)
		(fp_line
			(start -0.6477 -1.1811)
			(end -1.143 -1.1811)
			(stroke
				(width 0.1)
				(type default)
			)
			(layer "B.Fab")
		)
		(fp_line
			(start 0.6477 -1.1811)
			(end 0.6477 -0.3175)
			(stroke
				(width 0.1)
				(type default)
			)
			(layer "B.Fab")
		)
		(fp_line
			(start 1.143 -1.1811)
			(end 0.6477 -1.1811)
			(stroke
				(width 0.1)
				(type default)
			)
			(layer "B.Fab")
		)
		(fp_line
			(start -0.6477 -1.42875)
			(end -0.6477 1.42875)
			(stroke
				(width 0.1)
				(type default)
			)
			(layer "B.Fab")
		)
		(fp_line
			(start 0.6477 -1.42875)
			(end -0.6477 -1.42875)
			(stroke
				(width 0.1)
				(type default)
			)
			(layer "B.Fab")
		)
		(fp_poly
			(pts
				(arc
					(start 0.381 -0.9398)
					(mid 0.381 -0.5588)
					(end 0.381 -0.9398)
				)
			)
			(stroke
				(width 0)
				(type default)
			)
			(fill yes)
			(layer "B.Fab")
		)
		(fp_text user "3"
			(at -2.72923 1.0541 0)
			(unlocked yes)
			(layer "B.SilkS")
			(effects
				(font
					(size 0.7874 0.5842)
					(thickness 0.1524)
				)
				(justify left mirror)
			)
		)
		(fp_text user "2"
			(at 2.85877 0.9271 0)
			(unlocked yes)
			(layer "B.SilkS")
			(effects
				(font
					(size 0.7874 0.5842)
					(thickness 0.1524)
				)
				(justify left mirror)
			)
		)
		(fp_text user "4"
			(at -2.72923 -1.7399 0)
			(unlocked yes)
			(layer "B.SilkS")
			(effects
				(font
					(size 0.7874 0.5842)
					(thickness 0.1524)
				)
				(justify left mirror)
			)
		)
		(fp_text user "2"
			(at 2.08407 0.7112 0)
			(unlocked yes)
			(layer "B.Fab")
			(effects
				(font
					(size 0.7874 0.5842)
					(thickness 0.1524)
				)
				(justify left mirror)
			)
		)
		(fp_text user "3"
			(at -1.89103 0.669036 0)
			(unlocked yes)
			(layer "B.Fab")
			(effects
				(font
					(size 0.7874 0.5842)
					(thickness 0.1524)
				)
				(justify left mirror)
			)
		)
		(fp_text user "4"
			(at -1.91643 -1.261618 0)
			(unlocked yes)
			(layer "B.Fab")
			(effects
				(font
					(size 0.7874 0.5842)
					(thickness 0.1524)
				)
				(justify left mirror)
			)
		)
		(pad "1" smd rect
			(at 1.1049 -0.7493 90)
			(size 1.4478 1.0922)
			(layers "B.Cu" "B.Mask" "B.Paste")
			(net "SG")
		)
		(pad "2" smd rect
			(at 1.1049 0.9525 90)
			(size 1.4478 0.9906)
			(layers "B.Cu" "B.Mask" "B.Paste")
			(net "FT4232_FPGA_TMS")
		)
		(pad "3" smd rect
			(at -1.1049 0.9525 90)
			(size 1.4478 0.9906)
			(layers "B.Cu" "B.Mask" "B.Paste")
			(net "FT4232_FPGA_TDI")
		)
		(pad "4" smd rect
			(at -1.1049 -0.9525 90)
			(size 1.4478 0.9906)
			(layers "B.Cu" "B.Mask" "B.Paste")
			(net "Net_623")
		)
		(zone
			(layer "B.Cu")
			(hatch none 0.5)
			(connect_pads
				(clearance 0)
			)
			(min_thickness 0.25)
			(keepout
				(tracks allowed)
				(vias not_allowed)
				(pads allowed)
				(copperpour not_allowed)
				(footprints allowed)
			)
			(placement
				(enabled no)
				(sheetname "")
			)
			(fill
				(thermal_gap 0.5)
				(thermal_bridge_width 0.5)
				(island_removal_mode 0)
			)
			(polygon
				(pts
					(xy 146.2786 -74.6887) (xy 146.4183 -74.6887) (xy 146.4183 -75.7174) (xy 145.4404 -75.7174) (xy 145.4404 -75.9841)
					(xy 144.526 -75.9841) (xy 144.526 -75.7174) (xy 143.5481 -75.7174) (xy 143.5481 -74.9554) (xy 144.526 -74.9554)
					(xy 144.526 -74.6887) (xy 145.1864 -74.6887) (xy 145.1864 -74.9554) (xy 146.2786 -74.9554)
				)
			)
		)
	)
	(footprint ""
		(layer "B.Cu")
		(at 89.9922 -103.5558)
		(property "Reference" "R53"
			(at 3.7338 0.09017 0)
			(unlocked yes)
			(layer "B.SilkS")
			(effects
				(font
					(size 0.7874 0.5842)
					(thickness 0.1524)
				)
				(justify mirror)
			)
		)
		(property "Value" "VAL*"
			(at -0.02032 2.13233 0)
			(unlocked yes)
			(layer "B.Fab")
			(hide yes)
			(effects
				(font
					(size 0.7874 0.5842)
					(thickness 0.1524)
				)
				(justify mirror)
			)
		)
		(property "Tolerance" "TOL*"
			(at -0.044704 3.05435 0)
			(unlocked yes)
			(layer "Cmts.User")
			(hide yes)
			(effects
				(font
					(size 0.7874 0.5842)
					(thickness 0.1524)
				)
				(justify mirror)
			)
		)
		(property "User Part Number" "PARTNUM*"
			(at -0.02032 4.024884 0)
			(unlocked yes)
			(layer "Cmts.User")
			(hide yes)
			(effects
				(font
					(size 0.7874 0.5842)
					(thickness 0.1524)
				)
				(justify mirror)
			)
		)
		(property "Device Type" "RESISTOR-G152-10344-01,30KOHM,A"
			(at -0.008382 1.210564 0)
			(unlocked yes)
			(layer "B.Fab")
			(hide yes)
			(effects
				(font
					(size 0.7874 0.5842)
					(thickness 0.1524)
				)
				(justify mirror)
			)
		)
		(duplicate_pad_numbers_are_jumpers no)
		(fp_line
			(start -1.143 -0.5588)
			(end 1.143 -0.5588)
			(stroke
				(width 0.1)
				(type default)
			)
			(layer "B.SilkS")
		)
		(fp_line
			(start -1.143 0.5588)
			(end -1.143 -0.5588)
			(stroke
				(width 0.1)
				(type default)
			)
			(layer "B.SilkS")
		)
		(fp_line
			(start 1.143 -0.5588)
			(end 1.143 0.5588)
			(stroke
				(width 0.1)
				(type default)
			)
			(layer "B.SilkS")
		)
		(fp_line
			(start 1.143 0.5588)
			(end -1.143 0.5588)
			(stroke
				(width 0.1)
				(type default)
			)
			(layer "B.SilkS")
		)
		(fp_rect
			(start -1.143 0.5588)
			(end 1.143 -0.5588)
			(stroke
				(width 0)
				(type default)
			)
			(fill no)
			(layer "B.CrtYd")
		)
		(fp_line
			(start -0.508 -0.3048)
			(end 0.508 -0.3048)
			(stroke
				(width 0.1)
				(type default)
			)
			(layer "B.Fab")
		)
		(fp_line
			(start -0.508 0.3048)
			(end -0.508 -0.3048)
			(stroke
				(width 0.1)
				(type default)
			)
			(layer "B.Fab")
		)
		(fp_line
			(start 0.508 -0.3048)
			(end 0.508 0.3048)
			(stroke
				(width 0.1)
				(type default)
			)
			(layer "B.Fab")
		)
		(fp_line
			(start 0.508 0.3048)
			(end -0.508 0.3048)
			(stroke
				(width 0.1)
				(type default)
			)
			(layer "B.Fab")
		)
		(pad "1" smd rect
			(at 0.5334 0 180)
			(size 0.7112 0.6096)
			(layers "B.Cu" "B.Mask" "B.Paste")
			(net "VIN_XP3R3")
		)
		(pad "2" smd rect
			(at -0.5334 0 180)
			(size 0.7112 0.6096)
			(layers "B.Cu" "B.Mask" "B.Paste")
			(net "XP3R3V_EN")
		)
		(zone
			(layer "B.Cu")
			(hatch none 0.5)
			(connect_pads
				(clearance 0)
			)
			(min_thickness 0.25)
			(keepout
				(tracks not_allowed)
				(vias allowed)
				(pads allowed)
				(copperpour not_allowed)
				(footprints allowed)
			)
			(placement
				(enabled no)
				(sheetname "")
			)
			(fill
				(thermal_gap 0.5)
				(thermal_bridge_width 0.5)
				(island_removal_mode 0)
			)
			(polygon
				(pts
					(xy 89.916 -103.251) (xy 90.0684 -103.251) (xy 90.0684 -103.8606) (xy 89.916 -103.8606)
				)
			)
		)
		(zone
			(layer "B.Cu")
			(hatch none 0.5)
			(connect_pads
				(clearance 0)
			)
			(min_thickness 0.25)
			(keepout
				(tracks allowed)
				(vias not_allowed)
				(pads allowed)
				(copperpour not_allowed)
				(footprints allowed)
			)
			(placement
				(enabled no)
				(sheetname "")
			)
			(fill
				(thermal_gap 0.5)
				(thermal_bridge_width 0.5)
				(island_removal_mode 0)
			)
			(polygon
				(pts
					(xy 89.916 -103.251) (xy 90.0684 -103.251) (xy 90.0684 -103.8606) (xy 89.916 -103.8606)
				)
			)
		)
	)
	(footprint ""
		(layer "B.Cu")
		(at 119.34698 -42.82313)
		(property "Reference" "R500"
			(at 2.79527 0.78613 270)
			(unlocked yes)
			(layer "B.SilkS")
			(effects
				(font
					(size 0.635 0.4064)
					(thickness 0.1524)
				)
				(justify mirror)
			)
		)
		(property "Value" "VAL*"
			(at 0 3.718306 0)
			(unlocked yes)
			(layer "B.Fab")
			(hide yes)
			(effects
				(font
					(size 0.7874 0.5842)
					(thickness 0.127)
				)
				(justify mirror)
			)
		)
		(property "Tolerance" "TOL*"
			(at 0 4.861306 0)
			(unlocked yes)
			(layer "Cmts.User")
			(hide yes)
			(effects
				(font
					(size 0.7874 0.5842)
					(thickness 0.127)
				)
				(justify mirror)
			)
		)
		(property "User Part Number" "PARTNUM*"
			(at 0 2.575306 0)
			(unlocked yes)
			(layer "Cmts.User")
			(hide yes)
			(effects
				(font
					(size 0.7874 0.5842)
					(thickness 0.127)
				)
				(justify mirror)
			)
		)
		(property "Device Type" "RESISTOR-G155-14701-01,4.7KOHMA"
			(at 0 1.432306 0)
			(unlocked yes)
			(layer "B.Fab")
			(hide yes)
			(effects
				(font
					(size 0.7874 0.5842)
					(thickness 0.127)
				)
				(justify mirror)
			)
		)
		(duplicate_pad_numbers_are_jumpers no)
		(fp_line
			(start -0.970026 -0.4699)
			(end -0.970026 0.4699)
			(stroke
				(width 0.1)
				(type default)
			)
			(layer "B.SilkS")
		)
		(fp_line
			(start -0.970026 0.4699)
			(end 0.970026 0.4699)
			(stroke
				(width 0.1)
				(type default)
			)
			(layer "B.SilkS")
		)
		(fp_line
			(start 0.970026 -0.4699)
			(end -0.970026 -0.4699)
			(stroke
				(width 0.1)
				(type default)
			)
			(layer "B.SilkS")
		)
		(fp_line
			(start 0.970026 0.4699)
			(end 0.970026 -0.4699)
			(stroke
				(width 0.1)
				(type default)
			)
			(layer "B.SilkS")
		)
		(fp_poly
			(pts
				(xy 0.970026 0.4699) (xy -0.970026 0.4699) (xy -0.970026 -0.4699) (xy 0.970026 -0.4699)
			)
			(stroke
				(width 0)
				(type default)
			)
			(fill no)
			(layer "B.CrtYd")
		)
		(fp_line
			(start -0.508 -0.3048)
			(end -0.508 0.3048)
			(stroke
				(width 0.1)
				(type default)
			)
			(layer "B.Fab")
		)
		(fp_line
			(start -0.508 0.3048)
			(end 0.508 0.3048)
			(stroke
				(width 0.1)
				(type default)
			)
			(layer "B.Fab")
		)
		(fp_line
			(start 0.508 -0.3048)
			(end -0.508 -0.3048)
			(stroke
				(width 0.1)
				(type default)
			)
			(layer "B.Fab")
		)
		(fp_line
			(start 0.508 0.3048)
			(end 0.508 -0.3048)
			(stroke
				(width 0.1)
				(type default)
			)
			(layer "B.Fab")
		)
		(pad "1" smd circle
			(at 0.500126 0 180)
			(size 0.635 0.635)
			(layers "B.Cu" "B.Mask" "B.Paste")
			(net "SG")
		)
		(pad "2" smd circle
			(at -0.500126 0 180)
			(size 0.635 0.635)
			(layers "B.Cu" "B.Mask" "B.Paste")
			(net "ANT3_IN")
		)
	)
	(footprint ""
		(layer "B.Cu")
		(at 114.847116 -42.323004 90)
		(property "Reference" "C207"
			(at -1.302004 -41.726866 270)
			(unlocked yes)
			(layer "B.SilkS")
			(effects
				(font
					(size 0.635 0.4064)
					(thickness 0.1524)
				)
				(justify mirror)
			)
		)
		(property "Value" "VAL*"
			(at 0 3.718306 90)
			(unlocked yes)
			(layer "B.Fab")
			(hide yes)
			(effects
				(font
					(size 0.7874 0.5842)
					(thickness 0.127)
				)
				(justify mirror)
			)
		)
		(property "Device Type" "CAPACITOR-G105-0B104-CK,0.1UF,A"
			(at 0 1.432306 90)
			(unlocked yes)
			(layer "B.Fab")
			(hide yes)
			(effects
				(font
					(size 0.7874 0.5842)
					(thickness 0.127)
				)
				(justify mirror)
			)
		)
		(property "User Part Number" "PARTNUM*"
			(at 0 2.575306 90)
			(unlocked yes)
			(layer "Cmts.User")
			(hide yes)
			(effects
				(font
					(size 0.7874 0.5842)
					(thickness 0.127)
				)
				(justify mirror)
			)
		)
		(property "Tolerance" "TOL*"
			(at 0 4.861306 90)
			(unlocked yes)
			(layer "Cmts.User")
			(hide yes)
			(effects
				(font
					(size 0.7874 0.5842)
					(thickness 0.127)
				)
				(justify mirror)
			)
		)
		(duplicate_pad_numbers_are_jumpers no)
		(fp_line
			(start 0.970026 -0.4699)
			(end -0.970026 -0.4699)
			(stroke
				(width 0.1)
				(type default)
			)
			(layer "B.SilkS")
		)
		(fp_line
			(start -0.970026 -0.4699)
			(end -0.970026 0.4699)
			(stroke
				(width 0.1)
				(type default)
			)
			(layer "B.SilkS")
		)
		(fp_line
			(start 0.970026 0.4699)
			(end 0.970026 -0.4699)
			(stroke
				(width 0.1)
				(type default)
			)
			(layer "B.SilkS")
		)
		(fp_line
			(start -0.970026 0.4699)
			(end 0.970026 0.4699)
			(stroke
				(width 0.1)
				(type default)
			)
			(layer "B.SilkS")
		)
		(fp_poly
			(pts
				(xy 0.970026 0.4699) (xy -0.970026 0.4699) (xy -0.970026 -0.4699) (xy 0.970026 -0.4699)
			)
			(stroke
				(width 0)
				(type default)
			)
			(fill no)
			(layer "B.CrtYd")
		)
		(fp_line
			(start 0.508 -0.3048)
			(end -0.508 -0.3048)
			(stroke
				(width 0.1)
				(type default)
			)
			(layer "B.Fab")
		)
		(fp_line
			(start -0.508 -0.3048)
			(end -0.508 0.3048)
			(stroke
				(width 0.1)
				(type default)
			)
			(layer "B.Fab")
		)
		(fp_line
			(start 0.508 0.3048)
			(end 0.508 -0.3048)
			(stroke
				(width 0.1)
				(type default)
			)
			(layer "B.Fab")
		)
		(fp_line
			(start -0.508 0.3048)
			(end 0.508 0.3048)
			(stroke
				(width 0.1)
				(type default)
			)
			(layer "B.Fab")
		)
		(pad "1" smd circle
			(at 0.500126 0 270)
			(size 0.635 0.635)
			(layers "B.Cu" "B.Mask" "B.Paste")
			(net "XP1R0V_FPGA_VCCINT")
		)
		(pad "2" smd circle
			(at -0.500126 0 270)
			(size 0.635 0.635)
			(layers "B.Cu" "B.Mask" "B.Paste")
			(net "SG")
		)
	)
	(footprint ""
		(layer "B.Cu")
		(at 83.2358 -83.693 180)
		(property "Reference" "R153"
			(at 0.6858 5.67563 0)
			(unlocked yes)
			(layer "B.SilkS")
			(effects
				(font
					(size 0.7874 0.5842)
					(thickness 0.1524)
				)
				(justify mirror)
			)
		)
		(property "Value" "VAL*"
			(at -0.02032 2.13233 180)
			(unlocked yes)
			(layer "B.Fab")
			(hide yes)
			(effects
				(font
					(size 0.7874 0.5842)
					(thickness 0.1524)
				)
				(justify mirror)
			)
		)
		(property "Tolerance" "TOL*"
			(at -0.044704 3.05435 180)
			(unlocked yes)
			(layer "Cmts.User")
			(hide yes)
			(effects
				(font
					(size 0.7874 0.5842)
					(thickness 0.1524)
				)
				(justify mirror)
			)
		)
		(property "User Part Number" "PARTNUM*"
			(at -0.02032 4.024884 180)
			(unlocked yes)
			(layer "Cmts.User")
			(hide yes)
			(effects
				(font
					(size 0.7874 0.5842)
					(thickness 0.1524)
				)
				(justify mirror)
			)
		)
		(property "Device Type" "RESISTOR-G155-14701-01,4.7KOHMA"
			(at -0.008382 1.210564 180)
			(unlocked yes)
			(layer "B.Fab")
			(hide yes)
			(effects
				(font
					(size 0.7874 0.5842)
					(thickness 0.1524)
				)
				(justify mirror)
			)
		)
		(duplicate_pad_numbers_are_jumpers no)
		(fp_line
			(start 1.143 0.5588)
			(end -1.143 0.5588)
			(stroke
				(width 0.1)
				(type default)
			)
			(layer "B.SilkS")
		)
		(fp_line
			(start 1.143 -0.5588)
			(end 1.143 0.5588)
			(stroke
				(width 0.1)
				(type default)
			)
			(layer "B.SilkS")
		)
		(fp_line
			(start -1.143 0.5588)
			(end -1.143 -0.5588)
			(stroke
				(width 0.1)
				(type default)
			)
			(layer "B.SilkS")
		)
		(fp_line
			(start -1.143 -0.5588)
			(end 1.143 -0.5588)
			(stroke
				(width 0.1)
				(type default)
			)
			(layer "B.SilkS")
		)
		(fp_rect
			(start -1.143 0.5588)
			(end 1.143 -0.5588)
			(stroke
				(width 0)
				(type default)
			)
			(fill no)
			(layer "B.CrtYd")
		)
		(fp_line
			(start 0.508 0.3048)
			(end -0.508 0.3048)
			(stroke
				(width 0.1)
				(type default)
			)
			(layer "B.Fab")
		)
		(fp_line
			(start 0.508 -0.3048)
			(end 0.508 0.3048)
			(stroke
				(width 0.1)
				(type default)
			)
			(layer "B.Fab")
		)
		(fp_line
			(start -0.508 0.3048)
			(end -0.508 -0.3048)
			(stroke
				(width 0.1)
				(type default)
			)
			(layer "B.Fab")
		)
		(fp_line
			(start -0.508 -0.3048)
			(end 0.508 -0.3048)
			(stroke
				(width 0.1)
				(type default)
			)
			(layer "B.Fab")
		)
		(pad "1" smd rect
			(at 0.5334 0)
			(size 0.7112 0.6096)
			(layers "B.Cu" "B.Mask" "B.Paste")
			(net "SG")
		)
		(pad "2" smd rect
			(at -0.5334 0)
			(size 0.7112 0.6096)
			(layers "B.Cu" "B.Mask" "B.Paste")
			(net "UNNAMED_5_PCA9546APWTSSOP16_I_1")
		)
		(zone
			(layer "B.Cu")
			(hatch none 0.5)
			(connect_pads
				(clearance 0)
			)
			(min_thickness 0.25)
			(keepout
				(tracks allowed)
				(vias not_allowed)
				(pads allowed)
				(copperpour not_allowed)
				(footprints allowed)
			)
			(placement
				(enabled no)
				(sheetname "")
			)
			(fill
				(thermal_gap 0.5)
				(thermal_bridge_width 0.5)
				(island_removal_mode 0)
			)
			(polygon
				(pts
					(xy 83.312 -83.9978) (xy 83.1596 -83.9978) (xy 83.1596 -83.3882) (xy 83.312 -83.3882)
				)
			)
		)
	)
	(footprint ""
		(layer "B.Cu")
		(at 118.364 -44.577)
		(property "Reference" "R501"
			(at 2.286 0.92075 0)
			(unlocked yes)
			(layer "B.SilkS")
			(effects
				(font
					(size 0.635 0.4064)
					(thickness 0.1524)
				)
				(justify mirror)
			)
		)
		(property "Value" "VAL*"
			(at -0.02032 2.13233 0)
			(unlocked yes)
			(layer "B.Fab")
			(hide yes)
			(effects
				(font
					(size 0.7874 0.5842)
					(thickness 0.1524)
				)
				(justify mirror)
			)
		)
		(property "Tolerance" "TOL*"
			(at -0.044704 3.05435 0)
			(unlocked yes)
			(layer "Cmts.User")
			(hide yes)
			(effects
				(font
					(size 0.7874 0.5842)
					(thickness 0.1524)
				)
				(justify mirror)
			)
		)
		(property "User Part Number" "PARTNUM*"
			(at -0.02032 4.024884 0)
			(unlocked yes)
			(layer "Cmts.User")
			(hide yes)
			(effects
				(font
					(size 0.7874 0.5842)
					(thickness 0.1524)
				)
				(justify mirror)
			)
		)
		(property "Device Type" "RESISTOR-G155-14701-01,4.7KOHMA"
			(at -0.008382 1.210564 0)
			(unlocked yes)
			(layer "B.Fab")
			(hide yes)
			(effects
				(font
					(size 0.7874 0.5842)
					(thickness 0.1524)
				)
				(justify mirror)
			)
		)
		(duplicate_pad_numbers_are_jumpers no)
		(fp_line
			(start -1.143 -0.5588)
			(end 1.143 -0.5588)
			(stroke
				(width 0.1)
				(type default)
			)
			(layer "B.SilkS")
		)
		(fp_line
			(start -1.143 0.5588)
			(end -1.143 -0.5588)
			(stroke
				(width 0.1)
				(type default)
			)
			(layer "B.SilkS")
		)
		(fp_line
			(start 1.143 -0.5588)
			(end 1.143 0.5588)
			(stroke
				(width 0.1)
				(type default)
			)
			(layer "B.SilkS")
		)
		(fp_line
			(start 1.143 0.5588)
			(end -1.143 0.5588)
			(stroke
				(width 0.1)
				(type default)
			)
			(layer "B.SilkS")
		)
		(fp_poly
			(pts
				(xy 1.143 0.5588) (xy -1.143 0.5588) (xy -1.143 -0.5588) (xy 1.143 -0.5588)
			)
			(stroke
				(width 0)
				(type default)
			)
			(fill no)
			(layer "B.CrtYd")
		)
		(fp_line
			(start -0.508 -0.3048)
			(end 0.508 -0.3048)
			(stroke
				(width 0.1)
				(type default)
			)
			(layer "B.Fab")
		)
		(fp_line
			(start -0.508 0.3048)
			(end -0.508 -0.3048)
			(stroke
				(width 0.1)
				(type default)
			)
			(layer "B.Fab")
		)
		(fp_line
			(start 0.508 -0.3048)
			(end 0.508 0.3048)
			(stroke
				(width 0.1)
				(type default)
			)
			(layer "B.Fab")
		)
		(fp_line
			(start 0.508 0.3048)
			(end -0.508 0.3048)
			(stroke
				(width 0.1)
				(type default)
			)
			(layer "B.Fab")
		)
		(pad "1" smd rect
			(at 0.5334 0 180)
			(size 0.7112 0.6096)
			(layers "B.Cu" "B.Mask" "B.Paste")
			(net "SG")
		)
		(pad "2" smd rect
			(at -0.5334 0 180)
			(size 0.7112 0.6096)
			(layers "B.Cu" "B.Mask" "B.Paste")
			(net "ANT4_IN")
		)
		(zone
			(layer "B.Cu")
			(hatch none 0.5)
			(connect_pads
				(clearance 0)
			)
			(min_thickness 0.25)
			(keepout
				(tracks allowed)
				(vias not_allowed)
				(pads allowed)
				(copperpour not_allowed)
				(footprints allowed)
			)
			(placement
				(enabled no)
				(sheetname "")
			)
			(fill
				(thermal_gap 0.5)
				(thermal_bridge_width 0.5)
				(island_removal_mode 0)
			)
			(polygon
				(pts
					(xy 118.4402 -44.2722) (xy 118.4402 -44.8818) (xy 118.2878 -44.8818) (xy 118.2878 -44.2722)
				)
			)
		)
		(zone
			(layer "B.Cu")
			(hatch none 0.5)
			(connect_pads
				(clearance 0)
			)
			(min_thickness 0.25)
			(keepout
				(tracks not_allowed)
				(vias allowed)
				(pads allowed)
				(copperpour not_allowed)
				(footprints allowed)
			)
			(placement
				(enabled no)
				(sheetname "")
			)
			(fill
				(thermal_gap 0.5)
				(thermal_bridge_width 0.5)
				(island_removal_mode 0)
			)
			(polygon
				(pts
					(xy 118.4402 -44.2722) (xy 118.4402 -44.8818) (xy 118.2878 -44.8818) (xy 118.2878 -44.2722)
				)
			)
		)
	)
	(footprint ""
		(layer "B.Cu")
		(at 157.734 -50.513996 90)
		(property "Reference" "R103"
			(at -7.874 1.35763 270)
			(unlocked yes)
			(layer "B.SilkS")
			(effects
				(font
					(size 0.7874 0.5842)
					(thickness 0.1524)
				)
				(justify mirror)
			)
		)
		(property "Value" "VAL*"
			(at -0.02032 2.13233 90)
			(unlocked yes)
			(layer "B.Fab")
			(hide yes)
			(effects
				(font
					(size 0.7874 0.5842)
					(thickness 0.1524)
				)
				(justify mirror)
			)
		)
		(property "Device Type" "RESISTOR-G155-11001-01,1KOHM,1%"
			(at -0.008382 1.210564 90)
			(unlocked yes)
			(layer "B.Fab")
			(hide yes)
			(effects
				(font
					(size 0.7874 0.5842)
					(thickness 0.1524)
				)
				(justify mirror)
			)
		)
		(property "User Part Number" "PARTNUM*"
			(at -0.02032 4.024884 90)
			(unlocked yes)
			(layer "Cmts.User")
			(hide yes)
			(effects
				(font
					(size 0.7874 0.5842)
					(thickness 0.1524)
				)
				(justify mirror)
			)
		)
		(property "Tolerance" "TOL*"
			(at -0.044704 3.05435 90)
			(unlocked yes)
			(layer "Cmts.User")
			(hide yes)
			(effects
				(font
					(size 0.7874 0.5842)
					(thickness 0.1524)
				)
				(justify mirror)
			)
		)
		(duplicate_pad_numbers_are_jumpers no)
		(fp_line
			(start 1.143 -0.5588)
			(end 1.143 0.5588)
			(stroke
				(width 0.1)
				(type default)
			)
			(layer "B.SilkS")
		)
		(fp_line
			(start -1.143 -0.5588)
			(end 1.143 -0.5588)
			(stroke
				(width 0.1)
				(type default)
			)
			(layer "B.SilkS")
		)
		(fp_line
			(start 1.143 0.5588)
			(end -1.143 0.5588)
			(stroke
				(width 0.1)
				(type default)
			)
			(layer "B.SilkS")
		)
		(fp_line
			(start -1.143 0.5588)
			(end -1.143 -0.5588)
			(stroke
				(width 0.1)
				(type default)
			)
			(layer "B.SilkS")
		)
		(fp_rect
			(start 1.143 0.5588)
			(end -1.143 -0.5588)
			(stroke
				(width 0)
				(type default)
			)
			(fill no)
			(layer "B.CrtYd")
		)
		(fp_line
			(start 0.508 -0.3048)
			(end 0.508 0.3048)
			(stroke
				(width 0.1)
				(type default)
			)
			(layer "B.Fab")
		)
		(fp_line
			(start -0.508 -0.3048)
			(end 0.508 -0.3048)
			(stroke
				(width 0.1)
				(type default)
			)
			(layer "B.Fab")
		)
		(fp_line
			(start 0.508 0.3048)
			(end -0.508 0.3048)
			(stroke
				(width 0.1)
				(type default)
			)
			(layer "B.Fab")
		)
		(fp_line
			(start -0.508 0.3048)
			(end -0.508 -0.3048)
			(stroke
				(width 0.1)
				(type default)
			)
			(layer "B.Fab")
		)
		(pad "1" smd rect
			(at 0.5334 0 270)
			(size 0.7112 0.6096)
			(layers "B.Cu" "B.Mask" "B.Paste")
			(net "UNNAMED_527_RESISTOR_I201_2")
		)
		(pad "2" smd rect
			(at -0.5334 0 270)
			(size 0.7112 0.6096)
			(layers "B.Cu" "B.Mask" "B.Paste")
			(net "SG")
		)
		(zone
			(layer "B.Cu")
			(hatch none 0.5)
			(connect_pads
				(clearance 0)
			)
			(min_thickness 0.25)
			(keepout
				(tracks allowed)
				(vias not_allowed)
				(pads allowed)
				(copperpour not_allowed)
				(footprints allowed)
			)
			(placement
				(enabled no)
				(sheetname "")
			)
			(fill
				(thermal_gap 0.5)
				(thermal_bridge_width 0.5)
				(island_removal_mode 0)
			)
			(polygon
				(pts
					(xy 158.0388 -50.590196) (xy 157.4292 -50.590196) (xy 157.4292 -50.437796) (xy 158.0388 -50.437796)
				)
			)
		)
	)
	(footprint ""
		(layer "B.Cu")
		(at 85.09 -57.277)
		(property "Reference" "R75"
			(at -0.254 -1.10363 0)
			(unlocked yes)
			(layer "B.SilkS")
			(effects
				(font
					(size 0.7874 0.5842)
					(thickness 0.1524)
				)
				(justify mirror)
			)
		)
		(property "Value" "VAL*"
			(at -0.02032 2.13233 0)
			(unlocked yes)
			(layer "B.Fab")
			(hide yes)
			(effects
				(font
					(size 0.7874 0.5842)
					(thickness 0.1524)
				)
				(justify mirror)
			)
		)
		(property "Device Type" "RESISTOR-G155-14701-01,4.7KOHMA"
			(at -0.008382 1.210564 0)
			(unlocked yes)
			(layer "B.Fab")
			(hide yes)
			(effects
				(font
					(size 0.7874 0.5842)
					(thickness 0.1524)
				)
				(justify mirror)
			)
		)
		(property "User Part Number" "PARTNUM*"
			(at -0.02032 4.024884 0)
			(unlocked yes)
			(layer "Cmts.User")
			(hide yes)
			(effects
				(font
					(size 0.7874 0.5842)
					(thickness 0.1524)
				)
				(justify mirror)
			)
		)
		(property "Tolerance" "TOL*"
			(at -0.044704 3.05435 0)
			(unlocked yes)
			(layer "Cmts.User")
			(hide yes)
			(effects
				(font
					(size 0.7874 0.5842)
					(thickness 0.1524)
				)
				(justify mirror)
			)
		)
		(duplicate_pad_numbers_are_jumpers no)
		(fp_line
			(start -1.143 -0.5588)
			(end 1.143 -0.5588)
			(stroke
				(width 0.1)
				(type default)
			)
			(layer "B.SilkS")
		)
		(fp_line
			(start -1.143 0.5588)
			(end -1.143 -0.5588)
			(stroke
				(width 0.1)
				(type default)
			)
			(layer "B.SilkS")
		)
		(fp_line
			(start 1.143 -0.5588)
			(end 1.143 0.5588)
			(stroke
				(width 0.1)
				(type default)
			)
			(layer "B.SilkS")
		)
		(fp_line
			(start 1.143 0.5588)
			(end -1.143 0.5588)
			(stroke
				(width 0.1)
				(type default)
			)
			(layer "B.SilkS")
		)
		(fp_rect
			(start -1.143 -0.5588)
			(end 1.143 0.5588)
			(stroke
				(width 0)
				(type default)
			)
			(fill no)
			(layer "B.CrtYd")
		)
		(fp_line
			(start -0.508 -0.3048)
			(end 0.508 -0.3048)
			(stroke
				(width 0.1)
				(type default)
			)
			(layer "B.Fab")
		)
		(fp_line
			(start -0.508 0.3048)
			(end -0.508 -0.3048)
			(stroke
				(width 0.1)
				(type default)
			)
			(layer "B.Fab")
		)
		(fp_line
			(start 0.508 -0.3048)
			(end 0.508 0.3048)
			(stroke
				(width 0.1)
				(type default)
			)
			(layer "B.Fab")
		)
		(fp_line
			(start 0.508 0.3048)
			(end -0.508 0.3048)
			(stroke
				(width 0.1)
				(type default)
			)
			(layer "B.Fab")
		)
		(pad "1" smd rect
			(at 0.5334 0 180)
			(size 0.7112 0.6096)
			(layers "B.Cu" "B.Mask" "B.Paste")
			(net "XP3R3V_FPGA")
		)
		(pad "2" smd rect
			(at -0.5334 0 180)
			(size 0.7112 0.6096)
			(layers "B.Cu" "B.Mask" "B.Paste")
			(net "BNO080_I2C_SCL")
		)
		(zone
			(layer "B.Cu")
			(hatch none 0.5)
			(connect_pads
				(clearance 0)
			)
			(min_thickness 0.25)
			(keepout
				(tracks allowed)
				(vias not_allowed)
				(pads allowed)
				(copperpour not_allowed)
				(footprints allowed)
			)
			(placement
				(enabled no)
				(sheetname "")
			)
			(fill
				(thermal_gap 0.5)
				(thermal_bridge_width 0.5)
				(island_removal_mode 0)
			)
			(polygon
				(pts
					(xy 85.0138 -57.5818) (xy 85.0138 -56.9722) (xy 85.1662 -56.9722) (xy 85.1662 -57.5818)
				)
			)
		)
	)
	(footprint ""
		(layer "B.Cu")
		(at 34.544 -82.169 180)
		(property "Reference" "R349"
			(at 0.381 2.37363 0)
			(unlocked yes)
			(layer "B.SilkS")
			(effects
				(font
					(size 0.7874 0.5842)
					(thickness 0.1524)
				)
				(justify mirror)
			)
		)
		(property "Value" "VAL*"
			(at -0.02032 2.13233 180)
			(unlocked yes)
			(layer "B.Fab")
			(hide yes)
			(effects
				(font
					(size 0.7874 0.5842)
					(thickness 0.1524)
				)
				(justify mirror)
			)
		)
		(property "Tolerance" "TOL*"
			(at -0.044704 3.05435 180)
			(unlocked yes)
			(layer "Cmts.User")
			(hide yes)
			(effects
				(font
					(size 0.7874 0.5842)
					(thickness 0.1524)
				)
				(justify mirror)
			)
		)
		(property "User Part Number" "PARTNUM*"
			(at -0.02032 4.024884 180)
			(unlocked yes)
			(layer "Cmts.User")
			(hide yes)
			(effects
				(font
					(size 0.7874 0.5842)
					(thickness 0.1524)
				)
				(justify mirror)
			)
		)
		(property "Device Type" "RESISTOR-G155-11003-01,100KOHMA"
			(at -0.008382 1.210564 180)
			(unlocked yes)
			(layer "B.Fab")
			(hide yes)
			(effects
				(font
					(size 0.7874 0.5842)
					(thickness 0.1524)
				)
				(justify mirror)
			)
		)
		(duplicate_pad_numbers_are_jumpers no)
		(fp_line
			(start 1.143 0.5588)
			(end -1.143 0.5588)
			(stroke
				(width 0.1)
				(type default)
			)
			(layer "B.SilkS")
		)
		(fp_line
			(start 1.143 -0.5588)
			(end 1.143 0.5588)
			(stroke
				(width 0.1)
				(type default)
			)
			(layer "B.SilkS")
		)
		(fp_line
			(start -1.143 0.5588)
			(end -1.143 -0.5588)
			(stroke
				(width 0.1)
				(type default)
			)
			(layer "B.SilkS")
		)
		(fp_line
			(start -1.143 -0.5588)
			(end 1.143 -0.5588)
			(stroke
				(width 0.1)
				(type default)
			)
			(layer "B.SilkS")
		)
		(fp_rect
			(start 1.143 0.5588)
			(end -1.143 -0.5588)
			(stroke
				(width 0)
				(type default)
			)
			(fill no)
			(layer "B.CrtYd")
		)
		(fp_line
			(start 0.508 0.3048)
			(end -0.508 0.3048)
			(stroke
				(width 0.1)
				(type default)
			)
			(layer "B.Fab")
		)
		(fp_line
			(start 0.508 -0.3048)
			(end 0.508 0.3048)
			(stroke
				(width 0.1)
				(type default)
			)
			(layer "B.Fab")
		)
		(fp_line
			(start -0.508 0.3048)
			(end -0.508 -0.3048)
			(stroke
				(width 0.1)
				(type default)
			)
			(layer "B.Fab")
		)
		(fp_line
			(start -0.508 -0.3048)
			(end 0.508 -0.3048)
			(stroke
				(width 0.1)
				(type default)
			)
			(layer "B.Fab")
		)
		(pad "1" smd rect
			(at 0.5334 0)
			(size 0.7112 0.6096)
			(layers "B.Cu" "B.Mask" "B.Paste")
			(net "R_FT4232_CHD_RX")
		)
		(pad "2" smd rect
			(at -0.5334 0)
			(size 0.7112 0.6096)
			(layers "B.Cu" "B.Mask" "B.Paste")
			(net "XP3R3V_FT4232")
		)
		(zone
			(layer "B.Cu")
			(hatch none 0.5)
			(connect_pads
				(clearance 0)
			)
			(min_thickness 0.25)
			(keepout
				(tracks allowed)
				(vias not_allowed)
				(pads allowed)
				(copperpour not_allowed)
				(footprints allowed)
			)
			(placement
				(enabled no)
				(sheetname "")
			)
			(fill
				(thermal_gap 0.5)
				(thermal_bridge_width 0.5)
				(island_removal_mode 0)
			)
			(polygon
				(pts
					(xy 34.4678 -82.4738) (xy 34.4678 -81.8642) (xy 34.6202 -81.8642) (xy 34.6202 -82.4738)
				)
			)
		)
		(zone
			(layer "B.Cu")
			(hatch none 0.5)
			(connect_pads
				(clearance 0)
			)
			(min_thickness 0.25)
			(keepout
				(tracks not_allowed)
				(vias allowed)
				(pads allowed)
				(copperpour not_allowed)
				(footprints allowed)
			)
			(placement
				(enabled no)
				(sheetname "")
			)
			(fill
				(thermal_gap 0.5)
				(thermal_bridge_width 0.5)
				(island_removal_mode 0)
			)
			(polygon
				(pts
					(xy 34.4678 -82.4738) (xy 34.4678 -81.8642) (xy 34.6202 -81.8642) (xy 34.6202 -82.4738)
				)
			)
		)
	)
	(footprint ""
		(layer "B.Cu")
		(at 22.606 -86.614 180)
		(property "Reference" "R470"
			(at -1.016 -3.34137 0)
			(unlocked yes)
			(layer "B.SilkS")
			(effects
				(font
					(size 0.7874 0.5842)
					(thickness 0.1524)
				)
				(justify mirror)
			)
		)
		(property "Value" "VAL*"
			(at -0.02032 2.13233 180)
			(unlocked yes)
			(layer "B.Fab")
			(hide yes)
			(effects
				(font
					(size 0.7874 0.5842)
					(thickness 0.1524)
				)
				(justify mirror)
			)
		)
		(property "Tolerance" "TOL*"
			(at -0.044704 3.05435 180)
			(unlocked yes)
			(layer "Cmts.User")
			(hide yes)
			(effects
				(font
					(size 0.7874 0.5842)
					(thickness 0.1524)
				)
				(justify mirror)
			)
		)
		(property "User Part Number" "PARTNUM*"
			(at -0.02032 4.024884 180)
			(unlocked yes)
			(layer "Cmts.User")
			(hide yes)
			(effects
				(font
					(size 0.7874 0.5842)
					(thickness 0.1524)
				)
				(justify mirror)
			)
		)
		(property "Device Type" "RESISTOR-G155-133R0-01,33OHM,1%"
			(at -0.008382 1.210564 180)
			(unlocked yes)
			(layer "B.Fab")
			(hide yes)
			(effects
				(font
					(size 0.7874 0.5842)
					(thickness 0.1524)
				)
				(justify mirror)
			)
		)
		(duplicate_pad_numbers_are_jumpers no)
		(fp_line
			(start 1.143 0.5588)
			(end -1.143 0.5588)
			(stroke
				(width 0.1)
				(type default)
			)
			(layer "B.SilkS")
		)
		(fp_line
			(start 1.143 -0.5588)
			(end 1.143 0.5588)
			(stroke
				(width 0.1)
				(type default)
			)
			(layer "B.SilkS")
		)
		(fp_line
			(start -1.143 0.5588)
			(end -1.143 -0.5588)
			(stroke
				(width 0.1)
				(type default)
			)
			(layer "B.SilkS")
		)
		(fp_line
			(start -1.143 -0.5588)
			(end 1.143 -0.5588)
			(stroke
				(width 0.1)
				(type default)
			)
			(layer "B.SilkS")
		)
		(fp_poly
			(pts
				(xy 1.143 0.5588) (xy -1.143 0.5588) (xy -1.143 -0.5588) (xy 1.143 -0.5588)
			)
			(stroke
				(width 0)
				(type default)
			)
			(fill no)
			(layer "B.CrtYd")
		)
		(fp_line
			(start 0.508 0.3048)
			(end -0.508 0.3048)
			(stroke
				(width 0.1)
				(type default)
			)
			(layer "B.Fab")
		)
		(fp_line
			(start 0.508 -0.3048)
			(end 0.508 0.3048)
			(stroke
				(width 0.1)
				(type default)
			)
			(layer "B.Fab")
		)
		(fp_line
			(start -0.508 0.3048)
			(end -0.508 -0.3048)
			(stroke
				(width 0.1)
				(type default)
			)
			(layer "B.Fab")
		)
		(fp_line
			(start -0.508 -0.3048)
			(end 0.508 -0.3048)
			(stroke
				(width 0.1)
				(type default)
			)
			(layer "B.Fab")
		)
		(pad "1" smd rect
			(at 0.5334 0)
			(size 0.7112 0.6096)
			(layers "B.Cu" "B.Mask" "B.Paste")
			(net "R_FT4232_TMS")
		)
		(pad "2" smd rect
			(at -0.5334 0)
			(size 0.7112 0.6096)
			(layers "B.Cu" "B.Mask" "B.Paste")
			(net "FT4232_TMS_SPICS_N")
		)
		(zone
			(layer "B.Cu")
			(hatch none 0.5)
			(connect_pads
				(clearance 0)
			)
			(min_thickness 0.25)
			(keepout
				(tracks not_allowed)
				(vias allowed)
				(pads allowed)
				(copperpour not_allowed)
				(footprints allowed)
			)
			(placement
				(enabled no)
				(sheetname "")
			)
			(fill
				(thermal_gap 0.5)
				(thermal_bridge_width 0.5)
				(island_removal_mode 0)
			)
			(polygon
				(pts
					(xy 22.5298 -86.9188) (xy 22.5298 -86.3092) (xy 22.6822 -86.3092) (xy 22.6822 -86.9188)
				)
			)
		)
		(zone
			(layer "B.Cu")
			(hatch none 0.5)
			(connect_pads
				(clearance 0)
			)
			(min_thickness 0.25)
			(keepout
				(tracks allowed)
				(vias not_allowed)
				(pads allowed)
				(copperpour not_allowed)
				(footprints allowed)
			)
			(placement
				(enabled no)
				(sheetname "")
			)
			(fill
				(thermal_gap 0.5)
				(thermal_bridge_width 0.5)
				(island_removal_mode 0)
			)
			(polygon
				(pts
					(xy 22.5298 -86.9188) (xy 22.5298 -86.3092) (xy 22.6822 -86.3092) (xy 22.6822 -86.9188)
				)
			)
		)
	)
	(footprint ""
		(layer "B.Cu")
		(at 22.606 -87.757 180)
		(property "Reference" "R466"
			(at -1.016 -3.46837 0)
			(unlocked yes)
			(layer "B.SilkS")
			(effects
				(font
					(size 0.7874 0.5842)
					(thickness 0.1524)
				)
				(justify mirror)
			)
		)
		(property "Value" "VAL*"
			(at -0.02032 2.13233 180)
			(unlocked yes)
			(layer "B.Fab")
			(hide yes)
			(effects
				(font
					(size 0.7874 0.5842)
					(thickness 0.1524)
				)
				(justify mirror)
			)
		)
		(property "Tolerance" "TOL*"
			(at -0.044704 3.05435 180)
			(unlocked yes)
			(layer "Cmts.User")
			(hide yes)
			(effects
				(font
					(size 0.7874 0.5842)
					(thickness 0.1524)
				)
				(justify mirror)
			)
		)
		(property "User Part Number" "PARTNUM*"
			(at -0.02032 4.024884 180)
			(unlocked yes)
			(layer "Cmts.User")
			(hide yes)
			(effects
				(font
					(size 0.7874 0.5842)
					(thickness 0.1524)
				)
				(justify mirror)
			)
		)
		(property "Device Type" "RESISTOR-G155-11003-01,100KOHMA"
			(at -0.008382 1.210564 180)
			(unlocked yes)
			(layer "B.Fab")
			(hide yes)
			(effects
				(font
					(size 0.7874 0.5842)
					(thickness 0.1524)
				)
				(justify mirror)
			)
		)
		(duplicate_pad_numbers_are_jumpers no)
		(fp_line
			(start 1.143 0.5588)
			(end -1.143 0.5588)
			(stroke
				(width 0.1)
				(type default)
			)
			(layer "B.SilkS")
		)
		(fp_line
			(start 1.143 -0.5588)
			(end 1.143 0.5588)
			(stroke
				(width 0.1)
				(type default)
			)
			(layer "B.SilkS")
		)
		(fp_line
			(start -1.143 0.5588)
			(end -1.143 -0.5588)
			(stroke
				(width 0.1)
				(type default)
			)
			(layer "B.SilkS")
		)
		(fp_line
			(start -1.143 -0.5588)
			(end 1.143 -0.5588)
			(stroke
				(width 0.1)
				(type default)
			)
			(layer "B.SilkS")
		)
		(fp_poly
			(pts
				(xy 1.143 0.5588) (xy -1.143 0.5588) (xy -1.143 -0.5588) (xy 1.143 -0.5588)
			)
			(stroke
				(width 0)
				(type default)
			)
			(fill no)
			(layer "B.CrtYd")
		)
		(fp_line
			(start 0.508 0.3048)
			(end -0.508 0.3048)
			(stroke
				(width 0.1)
				(type default)
			)
			(layer "B.Fab")
		)
		(fp_line
			(start 0.508 -0.3048)
			(end 0.508 0.3048)
			(stroke
				(width 0.1)
				(type default)
			)
			(layer "B.Fab")
		)
		(fp_line
			(start -0.508 0.3048)
			(end -0.508 -0.3048)
			(stroke
				(width 0.1)
				(type default)
			)
			(layer "B.Fab")
		)
		(fp_line
			(start -0.508 -0.3048)
			(end 0.508 -0.3048)
			(stroke
				(width 0.1)
				(type default)
			)
			(layer "B.Fab")
		)
		(pad "1" smd rect
			(at 0.5334 0)
			(size 0.7112 0.6096)
			(layers "B.Cu" "B.Mask" "B.Paste")
			(net "R_FT4232_TDO")
		)
		(pad "2" smd rect
			(at -0.5334 0)
			(size 0.7112 0.6096)
			(layers "B.Cu" "B.Mask" "B.Paste")
			(net "XP3R3V_FT4232")
		)
		(zone
			(layer "B.Cu")
			(hatch none 0.5)
			(connect_pads
				(clearance 0)
			)
			(min_thickness 0.25)
			(keepout
				(tracks allowed)
				(vias not_allowed)
				(pads allowed)
				(copperpour not_allowed)
				(footprints allowed)
			)
			(placement
				(enabled no)
				(sheetname "")
			)
			(fill
				(thermal_gap 0.5)
				(thermal_bridge_width 0.5)
				(island_removal_mode 0)
			)
			(polygon
				(pts
					(xy 22.5298 -88.0618) (xy 22.5298 -87.4522) (xy 22.6822 -87.4522) (xy 22.6822 -88.0618)
				)
			)
		)
		(zone
			(layer "B.Cu")
			(hatch none 0.5)
			(connect_pads
				(clearance 0)
			)
			(min_thickness 0.25)
			(keepout
				(tracks not_allowed)
				(vias allowed)
				(pads allowed)
				(copperpour not_allowed)
				(footprints allowed)
			)
			(placement
				(enabled no)
				(sheetname "")
			)
			(fill
				(thermal_gap 0.5)
				(thermal_bridge_width 0.5)
				(island_removal_mode 0)
			)
			(polygon
				(pts
					(xy 22.5298 -88.0618) (xy 22.5298 -87.4522) (xy 22.6822 -87.4522) (xy 22.6822 -88.0618)
				)
			)
		)
	)
	(footprint ""
		(layer "B.Cu")
		(at 120.8278 -90.1954)
		(property "Reference" "R115"
			(at -0.4318 -1.20523 0)
			(unlocked yes)
			(layer "B.SilkS")
			(effects
				(font
					(size 0.7874 0.5842)
					(thickness 0.1524)
				)
				(justify mirror)
			)
		)
		(property "Value" "VAL*"
			(at -0.02032 2.13233 0)
			(unlocked yes)
			(layer "B.Fab")
			(hide yes)
			(effects
				(font
					(size 0.7874 0.5842)
					(thickness 0.1524)
				)
				(justify mirror)
			)
		)
		(property "Device Type" "RESISTOR-G155-14701-01,4.7KOHMA"
			(at -0.008382 1.210564 0)
			(unlocked yes)
			(layer "B.Fab")
			(hide yes)
			(effects
				(font
					(size 0.7874 0.5842)
					(thickness 0.1524)
				)
				(justify mirror)
			)
		)
		(property "User Part Number" "PARTNUM*"
			(at -0.02032 4.024884 0)
			(unlocked yes)
			(layer "Cmts.User")
			(hide yes)
			(effects
				(font
					(size 0.7874 0.5842)
					(thickness 0.1524)
				)
				(justify mirror)
			)
		)
		(property "Tolerance" "TOL*"
			(at -0.044704 3.05435 0)
			(unlocked yes)
			(layer "Cmts.User")
			(hide yes)
			(effects
				(font
					(size 0.7874 0.5842)
					(thickness 0.1524)
				)
				(justify mirror)
			)
		)
		(duplicate_pad_numbers_are_jumpers no)
		(fp_line
			(start -1.143 -0.5588)
			(end 1.143 -0.5588)
			(stroke
				(width 0.1)
				(type default)
			)
			(layer "B.SilkS")
		)
		(fp_line
			(start -1.143 0.5588)
			(end -1.143 -0.5588)
			(stroke
				(width 0.1)
				(type default)
			)
			(layer "B.SilkS")
		)
		(fp_line
			(start 1.143 -0.5588)
			(end 1.143 0.5588)
			(stroke
				(width 0.1)
				(type default)
			)
			(layer "B.SilkS")
		)
		(fp_line
			(start 1.143 0.5588)
			(end -1.143 0.5588)
			(stroke
				(width 0.1)
				(type default)
			)
			(layer "B.SilkS")
		)
		(fp_rect
			(start 1.143 -0.5588)
			(end -1.143 0.5588)
			(stroke
				(width 0)
				(type default)
			)
			(fill no)
			(layer "B.CrtYd")
		)
		(fp_line
			(start -0.508 -0.3048)
			(end 0.508 -0.3048)
			(stroke
				(width 0.1)
				(type default)
			)
			(layer "B.Fab")
		)
		(fp_line
			(start -0.508 0.3048)
			(end -0.508 -0.3048)
			(stroke
				(width 0.1)
				(type default)
			)
			(layer "B.Fab")
		)
		(fp_line
			(start 0.508 -0.3048)
			(end 0.508 0.3048)
			(stroke
				(width 0.1)
				(type default)
			)
			(layer "B.Fab")
		)
		(fp_line
			(start 0.508 0.3048)
			(end -0.508 0.3048)
			(stroke
				(width 0.1)
				(type default)
			)
			(layer "B.Fab")
		)
		(pad "1" smd rect
			(at 0.5334 0 180)
			(size 0.7112 0.6096)
			(layers "B.Cu" "B.Mask" "B.Paste")
			(net "XP3R3V_GPS")
		)
		(pad "2" smd rect
			(at -0.5334 0 180)
			(size 0.7112 0.6096)
			(layers "B.Cu" "B.Mask" "B.Paste")
			(net "GPS_RST_N")
		)
		(zone
			(layer "B.Cu")
			(hatch none 0.5)
			(connect_pads
				(clearance 0)
			)
			(min_thickness 0.25)
			(keepout
				(tracks allowed)
				(vias not_allowed)
				(pads allowed)
				(copperpour not_allowed)
				(footprints allowed)
			)
			(placement
				(enabled no)
				(sheetname "")
			)
			(fill
				(thermal_gap 0.5)
				(thermal_bridge_width 0.5)
				(island_removal_mode 0)
			)
			(polygon
				(pts
					(xy 120.904 -90.5002) (xy 120.7516 -90.5002) (xy 120.7516 -89.8906) (xy 120.904 -89.8906)
				)
			)
		)
	)
	(footprint ""
		(layer "B.Cu")
		(at 139.954 -59.563 90)
		(property "Reference" "R244"
			(at 3.175 -0.16637 270)
			(unlocked yes)
			(layer "B.SilkS")
			(effects
				(font
					(size 0.7874 0.5842)
					(thickness 0.1524)
				)
				(justify mirror)
			)
		)
		(property "Value" "VAL*"
			(at -0.02032 2.13233 90)
			(unlocked yes)
			(layer "B.Fab")
			(hide yes)
			(effects
				(font
					(size 0.7874 0.5842)
					(thickness 0.1524)
				)
				(justify mirror)
			)
		)
		(property "Device Type" "RESISTOR-G155-100R0-J0,0OHM,-"
			(at -0.008382 1.210564 90)
			(unlocked yes)
			(layer "B.Fab")
			(hide yes)
			(effects
				(font
					(size 0.7874 0.5842)
					(thickness 0.1524)
				)
				(justify mirror)
			)
		)
		(property "User Part Number" "PARTNUM*"
			(at -0.02032 4.024884 90)
			(unlocked yes)
			(layer "Cmts.User")
			(hide yes)
			(effects
				(font
					(size 0.7874 0.5842)
					(thickness 0.1524)
				)
				(justify mirror)
			)
		)
		(property "Tolerance" "TOL*"
			(at -0.044704 3.05435 90)
			(unlocked yes)
			(layer "Cmts.User")
			(hide yes)
			(effects
				(font
					(size 0.7874 0.5842)
					(thickness 0.1524)
				)
				(justify mirror)
			)
		)
		(duplicate_pad_numbers_are_jumpers no)
		(fp_line
			(start 1.143 -0.5588)
			(end 1.143 0.5588)
			(stroke
				(width 0.1)
				(type default)
			)
			(layer "B.SilkS")
		)
		(fp_line
			(start -1.143 -0.5588)
			(end 1.143 -0.5588)
			(stroke
				(width 0.1)
				(type default)
			)
			(layer "B.SilkS")
		)
		(fp_line
			(start 1.143 0.5588)
			(end -1.143 0.5588)
			(stroke
				(width 0.1)
				(type default)
			)
			(layer "B.SilkS")
		)
		(fp_line
			(start -1.143 0.5588)
			(end -1.143 -0.5588)
			(stroke
				(width 0.1)
				(type default)
			)
			(layer "B.SilkS")
		)
		(fp_rect
			(start -1.143 -0.5588)
			(end 1.143 0.5588)
			(stroke
				(width 0)
				(type default)
			)
			(fill no)
			(layer "B.CrtYd")
		)
		(fp_line
			(start 0.508 -0.3048)
			(end 0.508 0.3048)
			(stroke
				(width 0.1)
				(type default)
			)
			(layer "B.Fab")
		)
		(fp_line
			(start -0.508 -0.3048)
			(end 0.508 -0.3048)
			(stroke
				(width 0.1)
				(type default)
			)
			(layer "B.Fab")
		)
		(fp_line
			(start 0.508 0.3048)
			(end -0.508 0.3048)
			(stroke
				(width 0.1)
				(type default)
			)
			(layer "B.Fab")
		)
		(fp_line
			(start -0.508 0.3048)
			(end -0.508 -0.3048)
			(stroke
				(width 0.1)
				(type default)
			)
			(layer "B.Fab")
		)
		(pad "1" smd rect
			(at 0.5334 0 270)
			(size 0.7112 0.6096)
			(layers "B.Cu" "B.Mask" "B.Paste")
			(net "XP3R3V_PG")
		)
		(pad "2" smd rect
			(at -0.5334 0 270)
			(size 0.7112 0.6096)
			(layers "B.Cu" "B.Mask" "B.Paste")
			(net "UNNAMED_523_CAPACITOR_I7_1")
		)
		(zone
			(layer "B.Cu")
			(hatch none 0.5)
			(connect_pads
				(clearance 0)
			)
			(min_thickness 0.25)
			(keepout
				(tracks allowed)
				(vias not_allowed)
				(pads allowed)
				(copperpour not_allowed)
				(footprints allowed)
			)
			(placement
				(enabled no)
				(sheetname "")
			)
			(fill
				(thermal_gap 0.5)
				(thermal_bridge_width 0.5)
				(island_removal_mode 0)
			)
			(polygon
				(pts
					(xy 139.6492 -59.4868) (xy 140.2588 -59.4868) (xy 140.2588 -59.6392) (xy 139.6492 -59.6392)
				)
			)
		)
	)
	(footprint ""
		(layer "B.Cu")
		(at 141.097 -15.9766 -90)
		(property "Reference" "R229"
			(at -5.7404 0.16637 270)
			(unlocked yes)
			(layer "B.SilkS")
			(effects
				(font
					(size 0.7874 0.5842)
					(thickness 0.1524)
				)
				(justify mirror)
			)
		)
		(property "Value" "VAL*"
			(at -0.02032 2.13233 270)
			(unlocked yes)
			(layer "B.Fab")
			(hide yes)
			(effects
				(font
					(size 0.7874 0.5842)
					(thickness 0.1524)
				)
				(justify mirror)
			)
		)
		(property "Tolerance" "TOL*"
			(at -0.044704 3.05435 270)
			(unlocked yes)
			(layer "Cmts.User")
			(hide yes)
			(effects
				(font
					(size 0.7874 0.5842)
					(thickness 0.1524)
				)
				(justify mirror)
			)
		)
		(property "User Part Number" "PARTNUM*"
			(at -0.02032 4.024884 270)
			(unlocked yes)
			(layer "Cmts.User")
			(hide yes)
			(effects
				(font
					(size 0.7874 0.5842)
					(thickness 0.1524)
				)
				(justify mirror)
			)
		)
		(property "Device Type" "RESISTOR-G155-14701-01,4.7KOHMA"
			(at -0.008382 1.210564 270)
			(unlocked yes)
			(layer "B.Fab")
			(hide yes)
			(effects
				(font
					(size 0.7874 0.5842)
					(thickness 0.1524)
				)
				(justify mirror)
			)
		)
		(duplicate_pad_numbers_are_jumpers no)
		(fp_line
			(start -1.143 0.5588)
			(end -1.143 -0.5588)
			(stroke
				(width 0.1)
				(type default)
			)
			(layer "B.SilkS")
		)
		(fp_line
			(start 1.143 0.5588)
			(end -1.143 0.5588)
			(stroke
				(width 0.1)
				(type default)
			)
			(layer "B.SilkS")
		)
		(fp_line
			(start -1.143 -0.5588)
			(end 1.143 -0.5588)
			(stroke
				(width 0.1)
				(type default)
			)
			(layer "B.SilkS")
		)
		(fp_line
			(start 1.143 -0.5588)
			(end 1.143 0.5588)
			(stroke
				(width 0.1)
				(type default)
			)
			(layer "B.SilkS")
		)
		(fp_rect
			(start -1.143 -0.5588)
			(end 1.143 0.5588)
			(stroke
				(width 0)
				(type default)
			)
			(fill no)
			(layer "B.CrtYd")
		)
		(fp_line
			(start -0.508 0.3048)
			(end -0.508 -0.3048)
			(stroke
				(width 0.1)
				(type default)
			)
			(layer "B.Fab")
		)
		(fp_line
			(start 0.508 0.3048)
			(end -0.508 0.3048)
			(stroke
				(width 0.1)
				(type default)
			)
			(layer "B.Fab")
		)
		(fp_line
			(start -0.508 -0.3048)
			(end 0.508 -0.3048)
			(stroke
				(width 0.1)
				(type default)
			)
			(layer "B.Fab")
		)
		(fp_line
			(start 0.508 -0.3048)
			(end 0.508 0.3048)
			(stroke
				(width 0.1)
				(type default)
			)
			(layer "B.Fab")
		)
		(pad "1" smd rect
			(at 0.5334 0 90)
			(size 0.7112 0.6096)
			(layers "B.Cu" "B.Mask" "B.Paste")
			(net "XP3R3V_FPGA")
		)
		(pad "2" smd rect
			(at -0.5334 0 90)
			(size 0.7112 0.6096)
			(layers "B.Cu" "B.Mask" "B.Paste")
			(net "UNNAMED_515_CAPACITOR_I138_1")
		)
		(zone
			(layer "B.Cu")
			(hatch none 0.5)
			(connect_pads
				(clearance 0)
			)
			(min_thickness 0.25)
			(keepout
				(tracks allowed)
				(vias not_allowed)
				(pads allowed)
				(copperpour not_allowed)
				(footprints allowed)
			)
			(placement
				(enabled no)
				(sheetname "")
			)
			(fill
				(thermal_gap 0.5)
				(thermal_bridge_width 0.5)
				(island_removal_mode 0)
			)
			(polygon
				(pts
					(xy 141.4018 -16.0528) (xy 140.7922 -16.0528) (xy 140.7922 -15.9004) (xy 141.4018 -15.9004)
				)
			)
		)
	)
	(footprint ""
		(layer "B.Cu")
		(at 114.847116 -35.322764 -90)
		(property "Reference" "C160"
			(at 0.778764 0.959866 270)
			(unlocked yes)
			(layer "B.SilkS")
			(effects
				(font
					(size 0.635 0.4064)
					(thickness 0.1524)
				)
				(justify mirror)
			)
		)
		(property "Value" "VAL*"
			(at 0 3.718306 270)
			(unlocked yes)
			(layer "B.Fab")
			(hide yes)
			(effects
				(font
					(size 0.7874 0.5842)
					(thickness 0.127)
				)
				(justify mirror)
			)
		)
		(property "Device Type" "CAPACITOR-G105-0F475-BM,4.7UF,A"
			(at 0 1.432306 270)
			(unlocked yes)
			(layer "B.Fab")
			(hide yes)
			(effects
				(font
					(size 0.7874 0.5842)
					(thickness 0.127)
				)
				(justify mirror)
			)
		)
		(property "User Part Number" "PARTNUM*"
			(at 0 2.575306 270)
			(unlocked yes)
			(layer "Cmts.User")
			(hide yes)
			(effects
				(font
					(size 0.7874 0.5842)
					(thickness 0.127)
				)
				(justify mirror)
			)
		)
		(property "Tolerance" "TOL*"
			(at 0 4.861306 270)
			(unlocked yes)
			(layer "Cmts.User")
			(hide yes)
			(effects
				(font
					(size 0.7874 0.5842)
					(thickness 0.127)
				)
				(justify mirror)
			)
		)
		(duplicate_pad_numbers_are_jumpers no)
		(fp_line
			(start -0.970026 0.4699)
			(end 0.970026 0.4699)
			(stroke
				(width 0.1)
				(type default)
			)
			(layer "B.SilkS")
		)
		(fp_line
			(start 0.970026 0.4699)
			(end 0.970026 -0.4699)
			(stroke
				(width 0.1)
				(type default)
			)
			(layer "B.SilkS")
		)
		(fp_line
			(start -0.970026 -0.4699)
			(end -0.970026 0.4699)
			(stroke
				(width 0.1)
				(type default)
			)
			(layer "B.SilkS")
		)
		(fp_line
			(start 0.970026 -0.4699)
			(end -0.970026 -0.4699)
			(stroke
				(width 0.1)
				(type default)
			)
			(layer "B.SilkS")
		)
		(fp_poly
			(pts
				(xy 0.970026 0.4699) (xy -0.970026 0.4699) (xy -0.970026 -0.4699) (xy 0.970026 -0.4699)
			)
			(stroke
				(width 0)
				(type default)
			)
			(fill no)
			(layer "B.CrtYd")
		)
		(fp_line
			(start -0.508 0.3048)
			(end 0.508 0.3048)
			(stroke
				(width 0.1)
				(type default)
			)
			(layer "B.Fab")
		)
		(fp_line
			(start 0.508 0.3048)
			(end 0.508 -0.3048)
			(stroke
				(width 0.1)
				(type default)
			)
			(layer "B.Fab")
		)
		(fp_line
			(start -0.508 -0.3048)
			(end -0.508 0.3048)
			(stroke
				(width 0.1)
				(type default)
			)
			(layer "B.Fab")
		)
		(fp_line
			(start 0.508 -0.3048)
			(end -0.508 -0.3048)
			(stroke
				(width 0.1)
				(type default)
			)
			(layer "B.Fab")
		)
		(pad "1" smd circle
			(at 0.500126 0 90)
			(size 0.635 0.635)
			(layers "B.Cu" "B.Mask" "B.Paste")
			(net "XP2R5V_FPGA")
		)
		(pad "2" smd circle
			(at -0.500126 0 90)
			(size 0.635 0.635)
			(layers "B.Cu" "B.Mask" "B.Paste")
			(net "SG")
		)
	)
	(footprint ""
		(layer "B.Cu")
		(at 29.845 -88.265 180)
		(property "Reference" "C95"
			(at -0.381 -1.30937 0)
			(unlocked yes)
			(layer "B.SilkS")
			(effects
				(font
					(size 0.7874 0.5842)
					(thickness 0.1524)
				)
				(justify mirror)
			)
		)
		(property "Value" "VAL*"
			(at -0.0762 2.067306 180)
			(unlocked yes)
			(layer "B.Fab")
			(hide yes)
			(effects
				(font
					(size 0.7874 0.5842)
					(thickness 0.1524)
				)
				(justify mirror)
			)
		)
		(property "Tolerance" "TOL*"
			(at -0.0762 3.032506 180)
			(unlocked yes)
			(layer "Cmts.User")
			(hide yes)
			(effects
				(font
					(size 0.7874 0.5842)
					(thickness 0.1524)
				)
				(justify mirror)
			)
		)
		(property "User Part Number" "PARTNUM*"
			(at -0.1016 4.023106 180)
			(unlocked yes)
			(layer "Cmts.User")
			(hide yes)
			(effects
				(font
					(size 0.7874 0.5842)
					(thickness 0.1524)
				)
				(justify mirror)
			)
		)
		(property "Device Type" "CAPACITOR-G105-0B104-CK,0.1UF,A"
			(at -0.0508 1.127506 180)
			(unlocked yes)
			(layer "B.Fab")
			(hide yes)
			(effects
				(font
					(size 0.7874 0.5842)
					(thickness 0.1524)
				)
				(justify mirror)
			)
		)
		(duplicate_pad_numbers_are_jumpers no)
		(fp_line
			(start 1.143 0.5588)
			(end -1.143 0.5588)
			(stroke
				(width 0.1)
				(type default)
			)
			(layer "B.SilkS")
		)
		(fp_line
			(start 1.143 -0.5588)
			(end 1.143 0.5588)
			(stroke
				(width 0.1)
				(type default)
			)
			(layer "B.SilkS")
		)
		(fp_line
			(start -1.143 0.5588)
			(end -1.143 -0.5588)
			(stroke
				(width 0.1)
				(type default)
			)
			(layer "B.SilkS")
		)
		(fp_line
			(start -1.143 -0.5588)
			(end 1.143 -0.5588)
			(stroke
				(width 0.1)
				(type default)
			)
			(layer "B.SilkS")
		)
		(fp_rect
			(start 1.143 -0.5588)
			(end -1.143 0.5588)
			(stroke
				(width 0)
				(type default)
			)
			(fill no)
			(layer "B.CrtYd")
		)
		(fp_line
			(start 0.508 0.3048)
			(end -0.508 0.3048)
			(stroke
				(width 0.1)
				(type default)
			)
			(layer "B.Fab")
		)
		(fp_line
			(start 0.508 -0.3048)
			(end 0.508 0.3048)
			(stroke
				(width 0.1)
				(type default)
			)
			(layer "B.Fab")
		)
		(fp_line
			(start -0.508 0.3048)
			(end -0.508 -0.3048)
			(stroke
				(width 0.1)
				(type default)
			)
			(layer "B.Fab")
		)
		(fp_line
			(start -0.508 -0.3048)
			(end 0.508 -0.3048)
			(stroke
				(width 0.1)
				(type default)
			)
			(layer "B.Fab")
		)
		(pad "1" smd rect
			(at 0.5334 0)
			(size 0.7112 0.6096)
			(layers "B.Cu" "B.Mask" "B.Paste")
			(net "XP3R3V_FT4232")
		)
		(pad "2" smd rect
			(at -0.5334 0)
			(size 0.7112 0.6096)
			(layers "B.Cu" "B.Mask" "B.Paste")
			(net "SG")
		)
		(zone
			(layer "B.Cu")
			(hatch none 0.5)
			(connect_pads
				(clearance 0)
			)
			(min_thickness 0.25)
			(keepout
				(tracks allowed)
				(vias not_allowed)
				(pads allowed)
				(copperpour not_allowed)
				(footprints allowed)
			)
			(placement
				(enabled no)
				(sheetname "")
			)
			(fill
				(thermal_gap 0.5)
				(thermal_bridge_width 0.5)
				(island_removal_mode 0)
			)
			(polygon
				(pts
					(xy 29.7688 -87.9602) (xy 29.9212 -87.9602) (xy 29.9212 -88.5698) (xy 29.7688 -88.5698)
				)
			)
		)
	)
	(footprint ""
		(layer "B.Cu")
		(at 104.847136 -42.323004 90)
		(property "Reference" "C222"
			(at -1.141984 -41.510966 270)
			(unlocked yes)
			(layer "B.SilkS")
			(effects
				(font
					(size 0.635 0.4064)
					(thickness 0.1524)
				)
				(justify mirror)
			)
		)
		(property "Value" "VAL*"
			(at 0 3.718306 90)
			(unlocked yes)
			(layer "B.Fab")
			(hide yes)
			(effects
				(font
					(size 0.7874 0.5842)
					(thickness 0.127)
				)
				(justify mirror)
			)
		)
		(property "Tolerance" "TOL*"
			(at 0 4.861306 90)
			(unlocked yes)
			(layer "Cmts.User")
			(hide yes)
			(effects
				(font
					(size 0.7874 0.5842)
					(thickness 0.127)
				)
				(justify mirror)
			)
		)
		(property "User Part Number" "PARTNUM*"
			(at 0 2.575306 90)
			(unlocked yes)
			(layer "Cmts.User")
			(hide yes)
			(effects
				(font
					(size 0.7874 0.5842)
					(thickness 0.127)
				)
				(justify mirror)
			)
		)
		(property "Device Type" "CAPACITOR-G105-0B104-CK,0.1UF,A"
			(at 0 1.432306 90)
			(unlocked yes)
			(layer "B.Fab")
			(hide yes)
			(effects
				(font
					(size 0.7874 0.5842)
					(thickness 0.127)
				)
				(justify mirror)
			)
		)
		(duplicate_pad_numbers_are_jumpers no)
		(fp_line
			(start 0.970026 -0.4699)
			(end -0.970026 -0.4699)
			(stroke
				(width 0.1)
				(type default)
			)
			(layer "B.SilkS")
		)
		(fp_line
			(start -0.970026 -0.4699)
			(end -0.970026 0.4699)
			(stroke
				(width 0.1)
				(type default)
			)
			(layer "B.SilkS")
		)
		(fp_line
			(start 0.970026 0.4699)
			(end 0.970026 -0.4699)
			(stroke
				(width 0.1)
				(type default)
			)
			(layer "B.SilkS")
		)
		(fp_line
			(start -0.970026 0.4699)
			(end 0.970026 0.4699)
			(stroke
				(width 0.1)
				(type default)
			)
			(layer "B.SilkS")
		)
		(fp_poly
			(pts
				(xy 0.970026 0.4699) (xy -0.970026 0.4699) (xy -0.970026 -0.4699) (xy 0.970026 -0.4699)
			)
			(stroke
				(width 0)
				(type default)
			)
			(fill no)
			(layer "B.CrtYd")
		)
		(fp_line
			(start 0.508 -0.3048)
			(end -0.508 -0.3048)
			(stroke
				(width 0.1)
				(type default)
			)
			(layer "B.Fab")
		)
		(fp_line
			(start -0.508 -0.3048)
			(end -0.508 0.3048)
			(stroke
				(width 0.1)
				(type default)
			)
			(layer "B.Fab")
		)
		(fp_line
			(start 0.508 0.3048)
			(end 0.508 -0.3048)
			(stroke
				(width 0.1)
				(type default)
			)
			(layer "B.Fab")
		)
		(fp_line
			(start -0.508 0.3048)
			(end 0.508 0.3048)
			(stroke
				(width 0.1)
				(type default)
			)
			(layer "B.Fab")
		)
		(pad "1" smd circle
			(at 0.500126 0 270)
			(size 0.635 0.635)
			(layers "B.Cu" "B.Mask" "B.Paste")
			(net "XP1R0V_FPGA_VCCINT")
		)
		(pad "2" smd circle
			(at -0.500126 0 270)
			(size 0.635 0.635)
			(layers "B.Cu" "B.Mask" "B.Paste")
			(net "SG")
		)
	)
	(footprint ""
		(layer "B.Cu")
		(at 39.6494 -95.9104)
		(property "Reference" "R49"
			(at 0.4826 1.20777 0)
			(unlocked yes)
			(layer "B.SilkS")
			(effects
				(font
					(size 0.7874 0.5842)
					(thickness 0.1524)
				)
				(justify mirror)
			)
		)
		(property "Value" "VAL*"
			(at -0.02032 2.13233 0)
			(unlocked yes)
			(layer "B.Fab")
			(hide yes)
			(effects
				(font
					(size 0.7874 0.5842)
					(thickness 0.1524)
				)
				(justify mirror)
			)
		)
		(property "Tolerance" "TOL*"
			(at -0.044704 3.05435 0)
			(unlocked yes)
			(layer "Cmts.User")
			(hide yes)
			(effects
				(font
					(size 0.7874 0.5842)
					(thickness 0.1524)
				)
				(justify mirror)
			)
		)
		(property "User Part Number" "PARTNUM*"
			(at -0.02032 4.024884 0)
			(unlocked yes)
			(layer "Cmts.User")
			(hide yes)
			(effects
				(font
					(size 0.7874 0.5842)
					(thickness 0.1524)
				)
				(justify mirror)
			)
		)
		(property "Device Type" "RESISTOR-G155-11002-01,10KOHM,A"
			(at -0.008382 1.210564 0)
			(unlocked yes)
			(layer "B.Fab")
			(hide yes)
			(effects
				(font
					(size 0.7874 0.5842)
					(thickness 0.1524)
				)
				(justify mirror)
			)
		)
		(duplicate_pad_numbers_are_jumpers no)
		(fp_line
			(start -1.143 -0.5588)
			(end 1.143 -0.5588)
			(stroke
				(width 0.1)
				(type default)
			)
			(layer "B.SilkS")
		)
		(fp_line
			(start -1.143 0.5588)
			(end -1.143 -0.5588)
			(stroke
				(width 0.1)
				(type default)
			)
			(layer "B.SilkS")
		)
		(fp_line
			(start 1.143 -0.5588)
			(end 1.143 0.5588)
			(stroke
				(width 0.1)
				(type default)
			)
			(layer "B.SilkS")
		)
		(fp_line
			(start 1.143 0.5588)
			(end -1.143 0.5588)
			(stroke
				(width 0.1)
				(type default)
			)
			(layer "B.SilkS")
		)
		(fp_poly
			(pts
				(xy 1.143 0.5588) (xy -1.143 0.5588) (xy -1.143 -0.5588) (xy 1.143 -0.5588)
			)
			(stroke
				(width 0)
				(type default)
			)
			(fill no)
			(layer "B.CrtYd")
		)
		(fp_line
			(start -0.508 -0.3048)
			(end 0.508 -0.3048)
			(stroke
				(width 0.1)
				(type default)
			)
			(layer "B.Fab")
		)
		(fp_line
			(start -0.508 0.3048)
			(end -0.508 -0.3048)
			(stroke
				(width 0.1)
				(type default)
			)
			(layer "B.Fab")
		)
		(fp_line
			(start 0.508 -0.3048)
			(end 0.508 0.3048)
			(stroke
				(width 0.1)
				(type default)
			)
			(layer "B.Fab")
		)
		(fp_line
			(start 0.508 0.3048)
			(end -0.508 0.3048)
			(stroke
				(width 0.1)
				(type default)
			)
			(layer "B.Fab")
		)
		(pad "1" smd rect
			(at 0.5334 0 180)
			(size 0.7112 0.6096)
			(layers "B.Cu" "B.Mask" "B.Paste")
			(net "VIN_XP5R0V")
		)
		(pad "2" smd rect
			(at -0.5334 0 180)
			(size 0.7112 0.6096)
			(layers "B.Cu" "B.Mask" "B.Paste")
			(net "R_XP5R0V_EN")
		)
		(zone
			(layer "B.Cu")
			(hatch none 0.5)
			(connect_pads
				(clearance 0)
			)
			(min_thickness 0.25)
			(keepout
				(tracks not_allowed)
				(vias allowed)
				(pads allowed)
				(copperpour not_allowed)
				(footprints allowed)
			)
			(placement
				(enabled no)
				(sheetname "")
			)
			(fill
				(thermal_gap 0.5)
				(thermal_bridge_width 0.5)
				(island_removal_mode 0)
			)
			(polygon
				(pts
					(xy 39.7256 -95.6056) (xy 39.7256 -96.2152) (xy 39.5732 -96.2152) (xy 39.5732 -95.6056)
				)
			)
		)
		(zone
			(layer "B.Cu")
			(hatch none 0.5)
			(connect_pads
				(clearance 0)
			)
			(min_thickness 0.25)
			(keepout
				(tracks allowed)
				(vias not_allowed)
				(pads allowed)
				(copperpour not_allowed)
				(footprints allowed)
			)
			(placement
				(enabled no)
				(sheetname "")
			)
			(fill
				(thermal_gap 0.5)
				(thermal_bridge_width 0.5)
				(island_removal_mode 0)
			)
			(polygon
				(pts
					(xy 39.7256 -95.6056) (xy 39.7256 -96.2152) (xy 39.5732 -96.2152) (xy 39.5732 -95.6056)
				)
			)
		)
	)
	(footprint ""
		(layer "B.Cu")
		(at 116.847112 -39.323264 -90)
		(property "Reference" "C93"
			(at -0.173736 0.927862 270)
			(unlocked yes)
			(layer "B.SilkS")
			(effects
				(font
					(size 0.635 0.4064)
					(thickness 0.1524)
				)
				(justify mirror)
			)
		)
		(property "Value" "VAL*"
			(at 0 3.718306 270)
			(unlocked yes)
			(layer "B.Fab")
			(hide yes)
			(effects
				(font
					(size 0.7874 0.5842)
					(thickness 0.127)
				)
				(justify mirror)
			)
		)
		(property "Tolerance" "TOL*"
			(at 0 4.861306 270)
			(unlocked yes)
			(layer "Cmts.User")
			(hide yes)
			(effects
				(font
					(size 0.7874 0.5842)
					(thickness 0.127)
				)
				(justify mirror)
			)
		)
		(property "User Part Number" "PARTNUM*"
			(at 0 2.575306 270)
			(unlocked yes)
			(layer "Cmts.User")
			(hide yes)
			(effects
				(font
					(size 0.7874 0.5842)
					(thickness 0.127)
				)
				(justify mirror)
			)
		)
		(property "Device Type" "CAPACITOR-G105-0F475-BM,4.7UF,A"
			(at 0 1.432306 270)
			(unlocked yes)
			(layer "B.Fab")
			(hide yes)
			(effects
				(font
					(size 0.7874 0.5842)
					(thickness 0.127)
				)
				(justify mirror)
			)
		)
		(duplicate_pad_numbers_are_jumpers no)
		(fp_line
			(start -0.970026 0.4699)
			(end 0.970026 0.4699)
			(stroke
				(width 0.1)
				(type default)
			)
			(layer "B.SilkS")
		)
		(fp_line
			(start 0.970026 0.4699)
			(end 0.970026 -0.4699)
			(stroke
				(width 0.1)
				(type default)
			)
			(layer "B.SilkS")
		)
		(fp_line
			(start -0.970026 -0.4699)
			(end -0.970026 0.4699)
			(stroke
				(width 0.1)
				(type default)
			)
			(layer "B.SilkS")
		)
		(fp_line
			(start 0.970026 -0.4699)
			(end -0.970026 -0.4699)
			(stroke
				(width 0.1)
				(type default)
			)
			(layer "B.SilkS")
		)
		(fp_poly
			(pts
				(xy 0.970026 0.4699) (xy -0.970026 0.4699) (xy -0.970026 -0.4699) (xy 0.970026 -0.4699)
			)
			(stroke
				(width 0)
				(type default)
			)
			(fill no)
			(layer "B.CrtYd")
		)
		(fp_line
			(start -0.508 0.3048)
			(end 0.508 0.3048)
			(stroke
				(width 0.1)
				(type default)
			)
			(layer "B.Fab")
		)
		(fp_line
			(start 0.508 0.3048)
			(end 0.508 -0.3048)
			(stroke
				(width 0.1)
				(type default)
			)
			(layer "B.Fab")
		)
		(fp_line
			(start -0.508 -0.3048)
			(end -0.508 0.3048)
			(stroke
				(width 0.1)
				(type default)
			)
			(layer "B.Fab")
		)
		(fp_line
			(start 0.508 -0.3048)
			(end -0.508 -0.3048)
			(stroke
				(width 0.1)
				(type default)
			)
			(layer "B.Fab")
		)
		(pad "1" smd circle
			(at 0.500126 0 90)
			(size 0.635 0.635)
			(layers "B.Cu" "B.Mask" "B.Paste")
			(net "XP2R5V_FPGA")
		)
		(pad "2" smd circle
			(at -0.500126 0 90)
			(size 0.635 0.635)
			(layers "B.Cu" "B.Mask" "B.Paste")
			(net "SG")
		)
	)
	(footprint ""
		(layer "B.Cu")
		(at 128.1938 -62.3316 180)
		(property "Reference" "C181"
			(at 0.8128 1.76403 0)
			(unlocked yes)
			(layer "B.SilkS")
			(effects
				(font
					(size 0.7874 0.5842)
					(thickness 0.1524)
				)
				(justify mirror)
			)
		)
		(property "Value" "VAL*"
			(at -0.0762 3.134106 180)
			(unlocked yes)
			(layer "B.Fab")
			(hide yes)
			(effects
				(font
					(size 0.7874 0.5842)
					(thickness 0.1524)
				)
				(justify mirror)
			)
		)
		(property "Tolerance" "TOL*"
			(at -0.0762 4.048506 180)
			(unlocked yes)
			(layer "Cmts.User")
			(hide yes)
			(effects
				(font
					(size 0.7874 0.5842)
					(thickness 0.1524)
				)
				(justify mirror)
			)
		)
		(property "User Part Number" "PARTNUM*"
			(at -0.1016 5.013706 180)
			(unlocked yes)
			(layer "Cmts.User")
			(hide yes)
			(effects
				(font
					(size 0.7874 0.5842)
					(thickness 0.1524)
				)
				(justify mirror)
			)
		)
		(property "Device Type" "CAPACITOR-G107-0F226-CM,22UF,2A"
			(at -0.0508 2.194306 180)
			(unlocked yes)
			(layer "B.Fab")
			(hide yes)
			(effects
				(font
					(size 0.7874 0.5842)
					(thickness 0.1524)
				)
				(justify mirror)
			)
		)
		(duplicate_pad_numbers_are_jumpers no)
		(fp_line
			(start 1.5748 0.9398)
			(end -1.5748 0.9398)
			(stroke
				(width 0.1)
				(type default)
			)
			(layer "B.SilkS")
		)
		(fp_line
			(start 1.5748 -0.9398)
			(end 1.5748 0.9398)
			(stroke
				(width 0.1)
				(type default)
			)
			(layer "B.SilkS")
		)
		(fp_line
			(start -1.5748 0.9398)
			(end -1.5748 -0.9398)
			(stroke
				(width 0.1)
				(type default)
			)
			(layer "B.SilkS")
		)
		(fp_line
			(start -1.5748 -0.9398)
			(end 1.5748 -0.9398)
			(stroke
				(width 0.1)
				(type default)
			)
			(layer "B.SilkS")
		)
		(fp_rect
			(start -1.5748 0.9398)
			(end 1.5748 -0.9398)
			(stroke
				(width 0)
				(type default)
			)
			(fill no)
			(layer "B.CrtYd")
		)
		(fp_line
			(start 1.016 0.635)
			(end -1.016 0.635)
			(stroke
				(width 0.1)
				(type default)
			)
			(layer "B.Fab")
		)
		(fp_line
			(start 1.016 -0.635)
			(end 1.016 0.635)
			(stroke
				(width 0.1)
				(type default)
			)
			(layer "B.Fab")
		)
		(fp_line
			(start -1.016 0.635)
			(end -1.016 -0.635)
			(stroke
				(width 0.1)
				(type default)
			)
			(layer "B.Fab")
		)
		(fp_line
			(start -1.016 -0.635)
			(end 1.016 -0.635)
			(stroke
				(width 0.1)
				(type default)
			)
			(layer "B.Fab")
		)
		(pad "1" smd rect
			(at 0.8382 0)
			(size 0.9652 1.3716)
			(layers "B.Cu" "B.Mask" "B.Paste")
			(net "XP3R3V")
		)
		(pad "2" smd rect
			(at -0.8382 0)
			(size 0.9652 1.3716)
			(layers "B.Cu" "B.Mask" "B.Paste")
			(net "SG")
		)
		(zone
			(layer "B.Cu")
			(hatch none 0.5)
			(connect_pads
				(clearance 0)
			)
			(min_thickness 0.25)
			(keepout
				(tracks allowed)
				(vias not_allowed)
				(pads allowed)
				(copperpour not_allowed)
				(footprints allowed)
			)
			(placement
				(enabled no)
				(sheetname "")
			)
			(fill
				(thermal_gap 0.5)
				(thermal_bridge_width 0.5)
				(island_removal_mode 0)
			)
			(polygon
				(pts
					(xy 128.4224 -62.9666) (xy 127.9652 -62.9666) (xy 127.9652 -61.6966) (xy 128.4224 -61.6966)
				)
			)
		)
	)
	(footprint ""
		(layer "B.Cu")
		(at 112.346994 -48.823118)
		(property "Reference" "C132"
			(at -0.078994 -0.929132 0)
			(unlocked yes)
			(layer "B.SilkS")
			(effects
				(font
					(size 0.635 0.4064)
					(thickness 0.1524)
				)
				(justify mirror)
			)
		)
		(property "Value" "VAL*"
			(at 0 3.718306 0)
			(unlocked yes)
			(layer "B.Fab")
			(hide yes)
			(effects
				(font
					(size 0.7874 0.5842)
					(thickness 0.127)
				)
				(justify mirror)
			)
		)
		(property "Device Type" "CAPACITOR-G105-0B104-CK,0.1UF,A"
			(at 0 1.432306 0)
			(unlocked yes)
			(layer "B.Fab")
			(hide yes)
			(effects
				(font
					(size 0.7874 0.5842)
					(thickness 0.127)
				)
				(justify mirror)
			)
		)
		(property "User Part Number" "PARTNUM*"
			(at 0 2.575306 0)
			(unlocked yes)
			(layer "Cmts.User")
			(hide yes)
			(effects
				(font
					(size 0.7874 0.5842)
					(thickness 0.127)
				)
				(justify mirror)
			)
		)
		(property "Tolerance" "TOL*"
			(at 0 4.861306 0)
			(unlocked yes)
			(layer "Cmts.User")
			(hide yes)
			(effects
				(font
					(size 0.7874 0.5842)
					(thickness 0.127)
				)
				(justify mirror)
			)
		)
		(duplicate_pad_numbers_are_jumpers no)
		(fp_line
			(start -0.970026 -0.4699)
			(end -0.970026 0.4699)
			(stroke
				(width 0.1)
				(type default)
			)
			(layer "B.SilkS")
		)
		(fp_line
			(start -0.970026 0.4699)
			(end 0.970026 0.4699)
			(stroke
				(width 0.1)
				(type default)
			)
			(layer "B.SilkS")
		)
		(fp_line
			(start 0.970026 -0.4699)
			(end -0.970026 -0.4699)
			(stroke
				(width 0.1)
				(type default)
			)
			(layer "B.SilkS")
		)
		(fp_line
			(start 0.970026 0.4699)
			(end 0.970026 -0.4699)
			(stroke
				(width 0.1)
				(type default)
			)
			(layer "B.SilkS")
		)
		(fp_poly
			(pts
				(xy 0.970026 0.4699) (xy -0.970026 0.4699) (xy -0.970026 -0.4699) (xy 0.970026 -0.4699)
			)
			(stroke
				(width 0)
				(type default)
			)
			(fill no)
			(layer "B.CrtYd")
		)
		(fp_line
			(start -0.508 -0.3048)
			(end -0.508 0.3048)
			(stroke
				(width 0.1)
				(type default)
			)
			(layer "B.Fab")
		)
		(fp_line
			(start -0.508 0.3048)
			(end 0.508 0.3048)
			(stroke
				(width 0.1)
				(type default)
			)
			(layer "B.Fab")
		)
		(fp_line
			(start 0.508 -0.3048)
			(end -0.508 -0.3048)
			(stroke
				(width 0.1)
				(type default)
			)
			(layer "B.Fab")
		)
		(fp_line
			(start 0.508 0.3048)
			(end 0.508 -0.3048)
			(stroke
				(width 0.1)
				(type default)
			)
			(layer "B.Fab")
		)
		(pad "1" smd circle
			(at 0.500126 0 180)
			(size 0.635 0.635)
			(layers "B.Cu" "B.Mask" "B.Paste")
			(net "XP3R3V_FPGA")
		)
		(pad "2" smd circle
			(at -0.500126 0 180)
			(size 0.635 0.635)
			(layers "B.Cu" "B.Mask" "B.Paste")
			(net "SG")
		)
	)
	(footprint ""
		(layer "B.Cu")
		(at 115.443 -73.533 180)
		(property "Reference" "C294"
			(at 0.127 2.37363 0)
			(unlocked yes)
			(layer "B.SilkS")
			(effects
				(font
					(size 0.7874 0.5842)
					(thickness 0.1524)
				)
				(justify mirror)
			)
		)
		(property "Value" "VAL*"
			(at -0.0762 2.067306 180)
			(unlocked yes)
			(layer "B.Fab")
			(hide yes)
			(effects
				(font
					(size 0.7874 0.5842)
					(thickness 0.1524)
				)
				(justify mirror)
			)
		)
		(property "Tolerance" "TOL*"
			(at -0.0762 3.032506 180)
			(unlocked yes)
			(layer "Cmts.User")
			(hide yes)
			(effects
				(font
					(size 0.7874 0.5842)
					(thickness 0.1524)
				)
				(justify mirror)
			)
		)
		(property "User Part Number" "PARTNUM*"
			(at -0.1016 4.023106 180)
			(unlocked yes)
			(layer "Cmts.User")
			(hide yes)
			(effects
				(font
					(size 0.7874 0.5842)
					(thickness 0.1524)
				)
				(justify mirror)
			)
		)
		(property "Device Type" "CAPACITOR-G105-0B224-DK,0.22UFA"
			(at -0.0508 1.127506 180)
			(unlocked yes)
			(layer "B.Fab")
			(hide yes)
			(effects
				(font
					(size 0.7874 0.5842)
					(thickness 0.1524)
				)
				(justify mirror)
			)
		)
		(duplicate_pad_numbers_are_jumpers no)
		(fp_line
			(start 1.143 0.5588)
			(end -1.143 0.5588)
			(stroke
				(width 0.1)
				(type default)
			)
			(layer "B.SilkS")
		)
		(fp_line
			(start 1.143 -0.5588)
			(end 1.143 0.5588)
			(stroke
				(width 0.1)
				(type default)
			)
			(layer "B.SilkS")
		)
		(fp_line
			(start -1.143 0.5588)
			(end -1.143 -0.5588)
			(stroke
				(width 0.1)
				(type default)
			)
			(layer "B.SilkS")
		)
		(fp_line
			(start -1.143 -0.5588)
			(end 1.143 -0.5588)
			(stroke
				(width 0.1)
				(type default)
			)
			(layer "B.SilkS")
		)
		(fp_rect
			(start 1.143 -0.5588)
			(end -1.143 0.5588)
			(stroke
				(width 0)
				(type default)
			)
			(fill no)
			(layer "B.CrtYd")
		)
		(fp_line
			(start 0.508 0.3048)
			(end -0.508 0.3048)
			(stroke
				(width 0.1)
				(type default)
			)
			(layer "B.Fab")
		)
		(fp_line
			(start 0.508 -0.3048)
			(end 0.508 0.3048)
			(stroke
				(width 0.1)
				(type default)
			)
			(layer "B.Fab")
		)
		(fp_line
			(start -0.508 0.3048)
			(end -0.508 -0.3048)
			(stroke
				(width 0.1)
				(type default)
			)
			(layer "B.Fab")
		)
		(fp_line
			(start -0.508 -0.3048)
			(end 0.508 -0.3048)
			(stroke
				(width 0.1)
				(type default)
			)
			(layer "B.Fab")
		)
		(pad "1" smd rect
			(at 0.5334 0)
			(size 0.7112 0.6096)
			(layers "B.Cu" "B.Mask" "B.Paste")
			(net "XP3R3V_FPGA_EN_R")
		)
		(pad "2" smd rect
			(at -0.5334 0)
			(size 0.7112 0.6096)
			(layers "B.Cu" "B.Mask" "B.Paste")
			(net "SG")
		)
		(zone
			(layer "B.Cu")
			(hatch none 0.5)
			(connect_pads
				(clearance 0)
			)
			(min_thickness 0.25)
			(keepout
				(tracks allowed)
				(vias not_allowed)
				(pads allowed)
				(copperpour not_allowed)
				(footprints allowed)
			)
			(placement
				(enabled no)
				(sheetname "")
			)
			(fill
				(thermal_gap 0.5)
				(thermal_bridge_width 0.5)
				(island_removal_mode 0)
			)
			(polygon
				(pts
					(xy 115.3668 -73.2282) (xy 115.5192 -73.2282) (xy 115.5192 -73.8378) (xy 115.3668 -73.8378)
				)
			)
		)
		(zone
			(layer "B.Cu")
			(hatch none 0.5)
			(connect_pads
				(clearance 0)
			)
			(min_thickness 0.25)
			(keepout
				(tracks not_allowed)
				(vias allowed)
				(pads allowed)
				(copperpour not_allowed)
				(footprints allowed)
			)
			(placement
				(enabled no)
				(sheetname "")
			)
			(fill
				(thermal_gap 0.5)
				(thermal_bridge_width 0.5)
				(island_removal_mode 0)
			)
			(polygon
				(pts
					(xy 115.3668 -73.2282) (xy 115.5192 -73.2282) (xy 115.5192 -73.8378) (xy 115.3668 -73.8378)
				)
			)
		)
	)
	(footprint ""
		(layer "B.Cu")
		(at 18.288 -74.041)
		(property "Reference" "R340"
			(at 0 3.34137 0)
			(unlocked yes)
			(layer "B.SilkS")
			(effects
				(font
					(size 0.7874 0.5842)
					(thickness 0.1524)
				)
				(justify mirror)
			)
		)
		(property "Value" "VAL*"
			(at -0.02032 2.13233 0)
			(unlocked yes)
			(layer "B.Fab")
			(hide yes)
			(effects
				(font
					(size 0.7874 0.5842)
					(thickness 0.1524)
				)
				(justify mirror)
			)
		)
		(property "Tolerance" "TOL*"
			(at -0.044704 3.05435 0)
			(unlocked yes)
			(layer "Cmts.User")
			(hide yes)
			(effects
				(font
					(size 0.7874 0.5842)
					(thickness 0.1524)
				)
				(justify mirror)
			)
		)
		(property "User Part Number" "PARTNUM*"
			(at -0.02032 4.024884 0)
			(unlocked yes)
			(layer "Cmts.User")
			(hide yes)
			(effects
				(font
					(size 0.7874 0.5842)
					(thickness 0.1524)
				)
				(justify mirror)
			)
		)
		(property "Device Type" "RESISTOR-G155-14701-01,4.7KOHMA"
			(at -0.008382 1.210564 0)
			(unlocked yes)
			(layer "B.Fab")
			(hide yes)
			(effects
				(font
					(size 0.7874 0.5842)
					(thickness 0.1524)
				)
				(justify mirror)
			)
		)
		(duplicate_pad_numbers_are_jumpers no)
		(fp_line
			(start -1.143 -0.5588)
			(end 1.143 -0.5588)
			(stroke
				(width 0.1)
				(type default)
			)
			(layer "B.SilkS")
		)
		(fp_line
			(start -1.143 0.5588)
			(end -1.143 -0.5588)
			(stroke
				(width 0.1)
				(type default)
			)
			(layer "B.SilkS")
		)
		(fp_line
			(start 1.143 -0.5588)
			(end 1.143 0.5588)
			(stroke
				(width 0.1)
				(type default)
			)
			(layer "B.SilkS")
		)
		(fp_line
			(start 1.143 0.5588)
			(end -1.143 0.5588)
			(stroke
				(width 0.1)
				(type default)
			)
			(layer "B.SilkS")
		)
		(fp_rect
			(start 1.143 -0.5588)
			(end -1.143 0.5588)
			(stroke
				(width 0)
				(type default)
			)
			(fill no)
			(layer "B.CrtYd")
		)
		(fp_line
			(start -0.508 -0.3048)
			(end 0.508 -0.3048)
			(stroke
				(width 0.1)
				(type default)
			)
			(layer "B.Fab")
		)
		(fp_line
			(start -0.508 0.3048)
			(end -0.508 -0.3048)
			(stroke
				(width 0.1)
				(type default)
			)
			(layer "B.Fab")
		)
		(fp_line
			(start 0.508 -0.3048)
			(end 0.508 0.3048)
			(stroke
				(width 0.1)
				(type default)
			)
			(layer "B.Fab")
		)
		(fp_line
			(start 0.508 0.3048)
			(end -0.508 0.3048)
			(stroke
				(width 0.1)
				(type default)
			)
			(layer "B.Fab")
		)
		(pad "1" smd rect
			(at 0.5334 0 180)
			(size 0.7112 0.6096)
			(layers "B.Cu" "B.Mask" "B.Paste")
			(net "XP3R3V_FPGA")
		)
		(pad "2" smd rect
			(at -0.5334 0 180)
			(size 0.7112 0.6096)
			(layers "B.Cu" "B.Mask" "B.Paste")
			(net "FPGA_IN_LM75B_INT1_N")
		)
		(zone
			(layer "B.Cu")
			(hatch none 0.5)
			(connect_pads
				(clearance 0)
			)
			(min_thickness 0.25)
			(keepout
				(tracks allowed)
				(vias not_allowed)
				(pads allowed)
				(copperpour not_allowed)
				(footprints allowed)
			)
			(placement
				(enabled no)
				(sheetname "")
			)
			(fill
				(thermal_gap 0.5)
				(thermal_bridge_width 0.5)
				(island_removal_mode 0)
			)
			(polygon
				(pts
					(xy 18.3642 -74.3458) (xy 18.2118 -74.3458) (xy 18.2118 -73.7362) (xy 18.3642 -73.7362)
				)
			)
		)
	)
	(footprint ""
		(layer "B.Cu")
		(at 20.447 -61.5442 90)
		(property "Reference" "R316"
			(at -0.3302 -3.97637 270)
			(unlocked yes)
			(layer "B.SilkS")
			(effects
				(font
					(size 0.7874 0.5842)
					(thickness 0.1524)
				)
				(justify mirror)
			)
		)
		(property "Value" "VAL*"
			(at -0.02032 2.13233 90)
			(unlocked yes)
			(layer "B.Fab")
			(hide yes)
			(effects
				(font
					(size 0.7874 0.5842)
					(thickness 0.1524)
				)
				(justify mirror)
			)
		)
		(property "Tolerance" "TOL*"
			(at -0.044704 3.05435 90)
			(unlocked yes)
			(layer "Cmts.User")
			(hide yes)
			(effects
				(font
					(size 0.7874 0.5842)
					(thickness 0.1524)
				)
				(justify mirror)
			)
		)
		(property "User Part Number" "PARTNUM*"
			(at -0.02032 4.024884 90)
			(unlocked yes)
			(layer "Cmts.User")
			(hide yes)
			(effects
				(font
					(size 0.7874 0.5842)
					(thickness 0.1524)
				)
				(justify mirror)
			)
		)
		(property "Device Type" "RESISTOR-G155-100R0-J0,0OHM,-"
			(at -0.008382 1.210564 90)
			(unlocked yes)
			(layer "B.Fab")
			(hide yes)
			(effects
				(font
					(size 0.7874 0.5842)
					(thickness 0.1524)
				)
				(justify mirror)
			)
		)
		(duplicate_pad_numbers_are_jumpers no)
		(fp_line
			(start 1.143 -0.5588)
			(end 1.143 0.5588)
			(stroke
				(width 0.1)
				(type default)
			)
			(layer "B.SilkS")
		)
		(fp_line
			(start -1.143 -0.5588)
			(end 1.143 -0.5588)
			(stroke
				(width 0.1)
				(type default)
			)
			(layer "B.SilkS")
		)
		(fp_line
			(start 1.143 0.5588)
			(end -1.143 0.5588)
			(stroke
				(width 0.1)
				(type default)
			)
			(layer "B.SilkS")
		)
		(fp_line
			(start -1.143 0.5588)
			(end -1.143 -0.5588)
			(stroke
				(width 0.1)
				(type default)
			)
			(layer "B.SilkS")
		)
		(fp_poly
			(pts
				(xy 1.143 0.5588) (xy -1.143 0.5588) (xy -1.143 -0.5588) (xy 1.143 -0.5588)
			)
			(stroke
				(width 0)
				(type default)
			)
			(fill no)
			(layer "B.CrtYd")
		)
		(fp_line
			(start 0.508 -0.3048)
			(end 0.508 0.3048)
			(stroke
				(width 0.1)
				(type default)
			)
			(layer "B.Fab")
		)
		(fp_line
			(start -0.508 -0.3048)
			(end 0.508 -0.3048)
			(stroke
				(width 0.1)
				(type default)
			)
			(layer "B.Fab")
		)
		(fp_line
			(start 0.508 0.3048)
			(end -0.508 0.3048)
			(stroke
				(width 0.1)
				(type default)
			)
			(layer "B.Fab")
		)
		(fp_line
			(start -0.508 0.3048)
			(end -0.508 -0.3048)
			(stroke
				(width 0.1)
				(type default)
			)
			(layer "B.Fab")
		)
		(pad "1" smd rect
			(at 0.5334 0 270)
			(size 0.7112 0.6096)
			(layers "B.Cu" "B.Mask" "B.Paste")
			(net "ICP10100_I2C_SDA")
		)
		(pad "2" smd rect
			(at -0.5334 0 270)
			(size 0.7112 0.6096)
			(layers "B.Cu" "B.Mask" "B.Paste")
			(net "BF_ICP10100_I2C_SDA")
		)
		(zone
			(layer "B.Cu")
			(hatch none 0.5)
			(connect_pads
				(clearance 0)
			)
			(min_thickness 0.25)
			(keepout
				(tracks not_allowed)
				(vias allowed)
				(pads allowed)
				(copperpour not_allowed)
				(footprints allowed)
			)
			(placement
				(enabled no)
				(sheetname "")
			)
			(fill
				(thermal_gap 0.5)
				(thermal_bridge_width 0.5)
				(island_removal_mode 0)
			)
			(polygon
				(pts
					(xy 20.7518 -61.6204) (xy 20.1422 -61.6204) (xy 20.1422 -61.468) (xy 20.7518 -61.468)
				)
			)
		)
		(zone
			(layer "B.Cu")
			(hatch none 0.5)
			(connect_pads
				(clearance 0)
			)
			(min_thickness 0.25)
			(keepout
				(tracks allowed)
				(vias not_allowed)
				(pads allowed)
				(copperpour not_allowed)
				(footprints allowed)
			)
			(placement
				(enabled no)
				(sheetname "")
			)
			(fill
				(thermal_gap 0.5)
				(thermal_bridge_width 0.5)
				(island_removal_mode 0)
			)
			(polygon
				(pts
					(xy 20.7518 -61.6204) (xy 20.1422 -61.6204) (xy 20.1422 -61.468) (xy 20.7518 -61.468)
				)
			)
		)
	)
	(footprint ""
		(layer "B.Cu")
		(at 21.082 -16.891)
		(property "Reference" "R3"
			(at 0.381 1.69037 0)
			(unlocked yes)
			(layer "B.SilkS")
			(effects
				(font
					(size 0.7874 0.5842)
					(thickness 0.1524)
				)
				(justify mirror)
			)
		)
		(property "Value" "VAL*"
			(at -0.02032 2.13233 0)
			(unlocked yes)
			(layer "B.Fab")
			(hide yes)
			(effects
				(font
					(size 0.7874 0.5842)
					(thickness 0.1524)
				)
				(justify mirror)
			)
		)
		(property "Device Type" "RESISTOR-G155-14701-01,4.7KOHMA"
			(at -0.008382 1.210564 0)
			(unlocked yes)
			(layer "B.Fab")
			(hide yes)
			(effects
				(font
					(size 0.7874 0.5842)
					(thickness 0.1524)
				)
				(justify mirror)
			)
		)
		(property "User Part Number" "PARTNUM*"
			(at -0.02032 4.024884 0)
			(unlocked yes)
			(layer "Cmts.User")
			(hide yes)
			(effects
				(font
					(size 0.7874 0.5842)
					(thickness 0.1524)
				)
				(justify mirror)
			)
		)
		(property "Tolerance" "TOL*"
			(at -0.044704 3.05435 0)
			(unlocked yes)
			(layer "Cmts.User")
			(hide yes)
			(effects
				(font
					(size 0.7874 0.5842)
					(thickness 0.1524)
				)
				(justify mirror)
			)
		)
		(duplicate_pad_numbers_are_jumpers no)
		(fp_line
			(start -1.143 -0.5588)
			(end 1.143 -0.5588)
			(stroke
				(width 0.1)
				(type default)
			)
			(layer "B.SilkS")
		)
		(fp_line
			(start -1.143 0.5588)
			(end -1.143 -0.5588)
			(stroke
				(width 0.1)
				(type default)
			)
			(layer "B.SilkS")
		)
		(fp_line
			(start 1.143 -0.5588)
			(end 1.143 0.5588)
			(stroke
				(width 0.1)
				(type default)
			)
			(layer "B.SilkS")
		)
		(fp_line
			(start 1.143 0.5588)
			(end -1.143 0.5588)
			(stroke
				(width 0.1)
				(type default)
			)
			(layer "B.SilkS")
		)
		(fp_rect
			(start -1.143 -0.5588)
			(end 1.143 0.5588)
			(stroke
				(width 0)
				(type default)
			)
			(fill no)
			(layer "B.CrtYd")
		)
		(fp_line
			(start -0.508 -0.3048)
			(end 0.508 -0.3048)
			(stroke
				(width 0.1)
				(type default)
			)
			(layer "B.Fab")
		)
		(fp_line
			(start -0.508 0.3048)
			(end -0.508 -0.3048)
			(stroke
				(width 0.1)
				(type default)
			)
			(layer "B.Fab")
		)
		(fp_line
			(start 0.508 -0.3048)
			(end 0.508 0.3048)
			(stroke
				(width 0.1)
				(type default)
			)
			(layer "B.Fab")
		)
		(fp_line
			(start 0.508 0.3048)
			(end -0.508 0.3048)
			(stroke
				(width 0.1)
				(type default)
			)
			(layer "B.Fab")
		)
		(pad "1" smd rect
			(at 0.5334 0 180)
			(size 0.7112 0.6096)
			(layers "B.Cu" "B.Mask" "B.Paste")
			(net "XP3R3V_FPGA")
		)
		(pad "2" smd rect
			(at -0.5334 0 180)
			(size 0.7112 0.6096)
			(layers "B.Cu" "B.Mask" "B.Paste")
			(net "SEC_EEPROM_WP")
		)
		(zone
			(layer "B.Cu")
			(hatch none 0.5)
			(connect_pads
				(clearance 0)
			)
			(min_thickness 0.25)
			(keepout
				(tracks allowed)
				(vias not_allowed)
				(pads allowed)
				(copperpour not_allowed)
				(footprints allowed)
			)
			(placement
				(enabled no)
				(sheetname "")
			)
			(fill
				(thermal_gap 0.5)
				(thermal_bridge_width 0.5)
				(island_removal_mode 0)
			)
			(polygon
				(pts
					(xy 21.0058 -17.1958) (xy 21.0058 -16.5862) (xy 21.1582 -16.5862) (xy 21.1582 -17.1958)
				)
			)
		)
	)
	(footprint ""
		(layer "B.Cu")
		(at 111.125 -100.711 180)
		(property "Reference" "C315"
			(at -0.762 -1.30937 0)
			(unlocked yes)
			(layer "B.SilkS")
			(effects
				(font
					(size 0.7874 0.5842)
					(thickness 0.1524)
				)
				(justify mirror)
			)
		)
		(property "Value" "VAL*"
			(at -0.0762 2.067306 180)
			(unlocked yes)
			(layer "B.Fab")
			(hide yes)
			(effects
				(font
					(size 0.7874 0.5842)
					(thickness 0.1524)
				)
				(justify mirror)
			)
		)
		(property "Tolerance" "TOL*"
			(at -0.0762 3.032506 180)
			(unlocked yes)
			(layer "Cmts.User")
			(hide yes)
			(effects
				(font
					(size 0.7874 0.5842)
					(thickness 0.1524)
				)
				(justify mirror)
			)
		)
		(property "User Part Number" "PARTNUM*"
			(at -0.1016 4.023106 180)
			(unlocked yes)
			(layer "Cmts.User")
			(hide yes)
			(effects
				(font
					(size 0.7874 0.5842)
					(thickness 0.1524)
				)
				(justify mirror)
			)
		)
		(property "Device Type" "CAPACITOR-G105-0B104-EK,0.1UF,A"
			(at -0.0508 1.127506 180)
			(unlocked yes)
			(layer "B.Fab")
			(hide yes)
			(effects
				(font
					(size 0.7874 0.5842)
					(thickness 0.1524)
				)
				(justify mirror)
			)
		)
		(duplicate_pad_numbers_are_jumpers no)
		(fp_line
			(start 1.143 0.5588)
			(end -1.143 0.5588)
			(stroke
				(width 0.1)
				(type default)
			)
			(layer "B.SilkS")
		)
		(fp_line
			(start 1.143 -0.5588)
			(end 1.143 0.5588)
			(stroke
				(width 0.1)
				(type default)
			)
			(layer "B.SilkS")
		)
		(fp_line
			(start -1.143 0.5588)
			(end -1.143 -0.5588)
			(stroke
				(width 0.1)
				(type default)
			)
			(layer "B.SilkS")
		)
		(fp_line
			(start -1.143 -0.5588)
			(end 1.143 -0.5588)
			(stroke
				(width 0.1)
				(type default)
			)
			(layer "B.SilkS")
		)
		(fp_poly
			(pts
				(xy 1.143 0.5588) (xy -1.143 0.5588) (xy -1.143 -0.5588) (xy 1.143 -0.5588)
			)
			(stroke
				(width 0)
				(type default)
			)
			(fill no)
			(layer "B.CrtYd")
		)
		(fp_line
			(start 0.508 0.3048)
			(end -0.508 0.3048)
			(stroke
				(width 0.1)
				(type default)
			)
			(layer "B.Fab")
		)
		(fp_line
			(start 0.508 -0.3048)
			(end 0.508 0.3048)
			(stroke
				(width 0.1)
				(type default)
			)
			(layer "B.Fab")
		)
		(fp_line
			(start -0.508 0.3048)
			(end -0.508 -0.3048)
			(stroke
				(width 0.1)
				(type default)
			)
			(layer "B.Fab")
		)
		(fp_line
			(start -0.508 -0.3048)
			(end 0.508 -0.3048)
			(stroke
				(width 0.1)
				(type default)
			)
			(layer "B.Fab")
		)
		(pad "1" smd rect
			(at 0.5334 0)
			(size 0.7112 0.6096)
			(layers "B.Cu" "B.Mask" "B.Paste")
			(net "XP3R3V_FPGA")
		)
		(pad "2" smd rect
			(at -0.5334 0)
			(size 0.7112 0.6096)
			(layers "B.Cu" "B.Mask" "B.Paste")
			(net "SG")
		)
		(zone
			(layer "B.Cu")
			(hatch none 0.5)
			(connect_pads
				(clearance 0)
			)
			(min_thickness 0.25)
			(keepout
				(tracks not_allowed)
				(vias allowed)
				(pads allowed)
				(copperpour not_allowed)
				(footprints allowed)
			)
			(placement
				(enabled no)
				(sheetname "")
			)
			(fill
				(thermal_gap 0.5)
				(thermal_bridge_width 0.5)
				(island_removal_mode 0)
			)
			(polygon
				(pts
					(xy 111.0488 -101.0158) (xy 111.0488 -100.4062) (xy 111.2012 -100.4062) (xy 111.2012 -101.0158)
				)
			)
		)
		(zone
			(layer "B.Cu")
			(hatch none 0.5)
			(connect_pads
				(clearance 0)
			)
			(min_thickness 0.25)
			(keepout
				(tracks allowed)
				(vias not_allowed)
				(pads allowed)
				(copperpour not_allowed)
				(footprints allowed)
			)
			(placement
				(enabled no)
				(sheetname "")
			)
			(fill
				(thermal_gap 0.5)
				(thermal_bridge_width 0.5)
				(island_removal_mode 0)
			)
			(polygon
				(pts
					(xy 111.0488 -101.0158) (xy 111.0488 -100.4062) (xy 111.2012 -100.4062) (xy 111.2012 -101.0158)
				)
			)
		)
	)
	(footprint ""
		(layer "B.Cu")
		(at 22.7584 -61.5442 -90)
		(property "Reference" "R314"
			(at 3.1242 -0.69723 270)
			(unlocked yes)
			(layer "B.SilkS")
			(effects
				(font
					(size 0.7874 0.5842)
					(thickness 0.1524)
				)
				(justify mirror)
			)
		)
		(property "Value" "VAL*"
			(at -0.02032 2.13233 270)
			(unlocked yes)
			(layer "B.Fab")
			(hide yes)
			(effects
				(font
					(size 0.7874 0.5842)
					(thickness 0.1524)
				)
				(justify mirror)
			)
		)
		(property "Tolerance" "TOL*"
			(at -0.044704 3.05435 270)
			(unlocked yes)
			(layer "Cmts.User")
			(hide yes)
			(effects
				(font
					(size 0.7874 0.5842)
					(thickness 0.1524)
				)
				(justify mirror)
			)
		)
		(property "User Part Number" "PARTNUM*"
			(at -0.02032 4.024884 270)
			(unlocked yes)
			(layer "Cmts.User")
			(hide yes)
			(effects
				(font
					(size 0.7874 0.5842)
					(thickness 0.1524)
				)
				(justify mirror)
			)
		)
		(property "Device Type" "RESISTOR-G155-14701-01,4.7KOHMA"
			(at -0.008382 1.210564 270)
			(unlocked yes)
			(layer "B.Fab")
			(hide yes)
			(effects
				(font
					(size 0.7874 0.5842)
					(thickness 0.1524)
				)
				(justify mirror)
			)
		)
		(duplicate_pad_numbers_are_jumpers no)
		(fp_line
			(start -1.143 0.5588)
			(end -1.143 -0.5588)
			(stroke
				(width 0.1)
				(type default)
			)
			(layer "B.SilkS")
		)
		(fp_line
			(start 1.143 0.5588)
			(end -1.143 0.5588)
			(stroke
				(width 0.1)
				(type default)
			)
			(layer "B.SilkS")
		)
		(fp_line
			(start -1.143 -0.5588)
			(end 1.143 -0.5588)
			(stroke
				(width 0.1)
				(type default)
			)
			(layer "B.SilkS")
		)
		(fp_line
			(start 1.143 -0.5588)
			(end 1.143 0.5588)
			(stroke
				(width 0.1)
				(type default)
			)
			(layer "B.SilkS")
		)
		(fp_poly
			(pts
				(xy 1.143 0.5588) (xy -1.143 0.5588) (xy -1.143 -0.5588) (xy 1.143 -0.5588)
			)
			(stroke
				(width 0)
				(type default)
			)
			(fill no)
			(layer "B.CrtYd")
		)
		(fp_line
			(start -0.508 0.3048)
			(end -0.508 -0.3048)
			(stroke
				(width 0.1)
				(type default)
			)
			(layer "B.Fab")
		)
		(fp_line
			(start 0.508 0.3048)
			(end -0.508 0.3048)
			(stroke
				(width 0.1)
				(type default)
			)
			(layer "B.Fab")
		)
		(fp_line
			(start -0.508 -0.3048)
			(end 0.508 -0.3048)
			(stroke
				(width 0.1)
				(type default)
			)
			(layer "B.Fab")
		)
		(fp_line
			(start 0.508 -0.3048)
			(end 0.508 0.3048)
			(stroke
				(width 0.1)
				(type default)
			)
			(layer "B.Fab")
		)
		(pad "1" smd rect
			(at 0.5334 0 90)
			(size 0.7112 0.6096)
			(layers "B.Cu" "B.Mask" "B.Paste")
			(net "XP3R3V_FPGA")
		)
		(pad "2" smd rect
			(at -0.5334 0 90)
			(size 0.7112 0.6096)
			(layers "B.Cu" "B.Mask" "B.Paste")
			(net "UNNAMED_8_PCA9508DPTSSOP8_I51_E")
		)
		(zone
			(layer "B.Cu")
			(hatch none 0.5)
			(connect_pads
				(clearance 0)
			)
			(min_thickness 0.25)
			(keepout
				(tracks not_allowed)
				(vias allowed)
				(pads allowed)
				(copperpour not_allowed)
				(footprints allowed)
			)
			(placement
				(enabled no)
				(sheetname "")
			)
			(fill
				(thermal_gap 0.5)
				(thermal_bridge_width 0.5)
				(island_removal_mode 0)
			)
			(polygon
				(pts
					(xy 22.4536 -61.468) (xy 23.0632 -61.468) (xy 23.0632 -61.6204) (xy 22.4536 -61.6204)
				)
			)
		)
		(zone
			(layer "B.Cu")
			(hatch none 0.5)
			(connect_pads
				(clearance 0)
			)
			(min_thickness 0.25)
			(keepout
				(tracks allowed)
				(vias not_allowed)
				(pads allowed)
				(copperpour not_allowed)
				(footprints allowed)
			)
			(placement
				(enabled no)
				(sheetname "")
			)
			(fill
				(thermal_gap 0.5)
				(thermal_bridge_width 0.5)
				(island_removal_mode 0)
			)
			(polygon
				(pts
					(xy 22.4536 -61.468) (xy 23.0632 -61.468) (xy 23.0632 -61.6204) (xy 22.4536 -61.6204)
				)
			)
		)
	)
	(footprint ""
		(layer "B.Cu")
		(at 88.519 -86.741 180)
		(property "Reference" "R203"
			(at -0.254 5.80263 0)
			(unlocked yes)
			(layer "B.SilkS")
			(effects
				(font
					(size 0.7874 0.5842)
					(thickness 0.1524)
				)
				(justify mirror)
			)
		)
		(property "Value" "VAL*"
			(at -0.02032 2.13233 180)
			(unlocked yes)
			(layer "B.Fab")
			(hide yes)
			(effects
				(font
					(size 0.7874 0.5842)
					(thickness 0.1524)
				)
				(justify mirror)
			)
		)
		(property "Tolerance" "TOL*"
			(at -0.044704 3.05435 180)
			(unlocked yes)
			(layer "Cmts.User")
			(hide yes)
			(effects
				(font
					(size 0.7874 0.5842)
					(thickness 0.1524)
				)
				(justify mirror)
			)
		)
		(property "User Part Number" "PARTNUM*"
			(at -0.02032 4.024884 180)
			(unlocked yes)
			(layer "Cmts.User")
			(hide yes)
			(effects
				(font
					(size 0.7874 0.5842)
					(thickness 0.1524)
				)
				(justify mirror)
			)
		)
		(property "Device Type" "RESISTOR-G155-133R0-01,33OHM,1%"
			(at -0.008382 1.210564 180)
			(unlocked yes)
			(layer "B.Fab")
			(hide yes)
			(effects
				(font
					(size 0.7874 0.5842)
					(thickness 0.1524)
				)
				(justify mirror)
			)
		)
		(duplicate_pad_numbers_are_jumpers no)
		(fp_line
			(start 1.143 0.5588)
			(end -1.143 0.5588)
			(stroke
				(width 0.1)
				(type default)
			)
			(layer "B.SilkS")
		)
		(fp_line
			(start 1.143 -0.5588)
			(end 1.143 0.5588)
			(stroke
				(width 0.1)
				(type default)
			)
			(layer "B.SilkS")
		)
		(fp_line
			(start -1.143 0.5588)
			(end -1.143 -0.5588)
			(stroke
				(width 0.1)
				(type default)
			)
			(layer "B.SilkS")
		)
		(fp_line
			(start -1.143 -0.5588)
			(end 1.143 -0.5588)
			(stroke
				(width 0.1)
				(type default)
			)
			(layer "B.SilkS")
		)
		(fp_rect
			(start 1.143 -0.5588)
			(end -1.143 0.5588)
			(stroke
				(width 0)
				(type default)
			)
			(fill no)
			(layer "B.CrtYd")
		)
		(fp_line
			(start 0.508 0.3048)
			(end -0.508 0.3048)
			(stroke
				(width 0.1)
				(type default)
			)
			(layer "B.Fab")
		)
		(fp_line
			(start 0.508 -0.3048)
			(end 0.508 0.3048)
			(stroke
				(width 0.1)
				(type default)
			)
			(layer "B.Fab")
		)
		(fp_line
			(start -0.508 0.3048)
			(end -0.508 -0.3048)
			(stroke
				(width 0.1)
				(type default)
			)
			(layer "B.Fab")
		)
		(fp_line
			(start -0.508 -0.3048)
			(end 0.508 -0.3048)
			(stroke
				(width 0.1)
				(type default)
			)
			(layer "B.Fab")
		)
		(pad "1" smd rect
			(at 0.5334 0)
			(size 0.7112 0.6096)
			(layers "B.Cu" "B.Mask" "B.Paste")
			(net "UNNAMED_127_MT25QL128ABA1ESESOP")
		)
		(pad "2" smd rect
			(at -0.5334 0)
			(size 0.7112 0.6096)
			(layers "B.Cu" "B.Mask" "B.Paste")
			(net "FLASH_DQ0_MOSI")
		)
		(zone
			(layer "B.Cu")
			(hatch none 0.5)
			(connect_pads
				(clearance 0)
			)
			(min_thickness 0.25)
			(keepout
				(tracks allowed)
				(vias not_allowed)
				(pads allowed)
				(copperpour not_allowed)
				(footprints allowed)
			)
			(placement
				(enabled no)
				(sheetname "")
			)
			(fill
				(thermal_gap 0.5)
				(thermal_bridge_width 0.5)
				(island_removal_mode 0)
			)
			(polygon
				(pts
					(xy 88.4428 -86.4362) (xy 88.5952 -86.4362) (xy 88.5952 -87.0458) (xy 88.4428 -87.0458)
				)
			)
		)
	)
	(footprint ""
		(layer "B.Cu")
		(at 147.955 -19.685 -90)
		(property "Reference" "C293"
			(at -2.794 0.03937 270)
			(unlocked yes)
			(layer "B.SilkS")
			(effects
				(font
					(size 0.7874 0.5842)
					(thickness 0.1524)
				)
				(justify mirror)
			)
		)
		(property "Value" "VAL*"
			(at -0.0762 2.067306 270)
			(unlocked yes)
			(layer "B.Fab")
			(hide yes)
			(effects
				(font
					(size 0.7874 0.5842)
					(thickness 0.1524)
				)
				(justify mirror)
			)
		)
		(property "Tolerance" "TOL*"
			(at -0.0762 3.032506 270)
			(unlocked yes)
			(layer "Cmts.User")
			(hide yes)
			(effects
				(font
					(size 0.7874 0.5842)
					(thickness 0.1524)
				)
				(justify mirror)
			)
		)
		(property "User Part Number" "PARTNUM*"
			(at -0.1016 4.023106 270)
			(unlocked yes)
			(layer "Cmts.User")
			(hide yes)
			(effects
				(font
					(size 0.7874 0.5842)
					(thickness 0.1524)
				)
				(justify mirror)
			)
		)
		(property "Device Type" "CAPACITOR-G105-0B224-DK,0.22UFA"
			(at -0.0508 1.127506 270)
			(unlocked yes)
			(layer "B.Fab")
			(hide yes)
			(effects
				(font
					(size 0.7874 0.5842)
					(thickness 0.1524)
				)
				(justify mirror)
			)
		)
		(duplicate_pad_numbers_are_jumpers no)
		(fp_line
			(start -1.143 0.5588)
			(end -1.143 -0.5588)
			(stroke
				(width 0.1)
				(type default)
			)
			(layer "B.SilkS")
		)
		(fp_line
			(start 1.143 0.5588)
			(end -1.143 0.5588)
			(stroke
				(width 0.1)
				(type default)
			)
			(layer "B.SilkS")
		)
		(fp_line
			(start -1.143 -0.5588)
			(end 1.143 -0.5588)
			(stroke
				(width 0.1)
				(type default)
			)
			(layer "B.SilkS")
		)
		(fp_line
			(start 1.143 -0.5588)
			(end 1.143 0.5588)
			(stroke
				(width 0.1)
				(type default)
			)
			(layer "B.SilkS")
		)
		(fp_rect
			(start -1.143 0.5588)
			(end 1.143 -0.5588)
			(stroke
				(width 0)
				(type default)
			)
			(fill no)
			(layer "B.CrtYd")
		)
		(fp_line
			(start -0.508 0.3048)
			(end -0.508 -0.3048)
			(stroke
				(width 0.1)
				(type default)
			)
			(layer "B.Fab")
		)
		(fp_line
			(start 0.508 0.3048)
			(end -0.508 0.3048)
			(stroke
				(width 0.1)
				(type default)
			)
			(layer "B.Fab")
		)
		(fp_line
			(start -0.508 -0.3048)
			(end 0.508 -0.3048)
			(stroke
				(width 0.1)
				(type default)
			)
			(layer "B.Fab")
		)
		(fp_line
			(start 0.508 -0.3048)
			(end 0.508 0.3048)
			(stroke
				(width 0.1)
				(type default)
			)
			(layer "B.Fab")
		)
		(pad "1" smd rect
			(at 0.5334 0 90)
			(size 0.7112 0.6096)
			(layers "B.Cu" "B.Mask" "B.Paste")
			(net "UNNAMED_515_CAPACITOR_I128_1")
		)
		(pad "2" smd rect
			(at -0.5334 0 90)
			(size 0.7112 0.6096)
			(layers "B.Cu" "B.Mask" "B.Paste")
			(net "SG")
		)
		(zone
			(layer "B.Cu")
			(hatch none 0.5)
			(connect_pads
				(clearance 0)
			)
			(min_thickness 0.25)
			(keepout
				(tracks allowed)
				(vias not_allowed)
				(pads allowed)
				(copperpour not_allowed)
				(footprints allowed)
			)
			(placement
				(enabled no)
				(sheetname "")
			)
			(fill
				(thermal_gap 0.5)
				(thermal_bridge_width 0.5)
				(island_removal_mode 0)
			)
			(polygon
				(pts
					(xy 147.6502 -19.7612) (xy 147.6502 -19.6088) (xy 148.2598 -19.6088) (xy 148.2598 -19.7612)
				)
			)
		)
		(zone
			(layer "B.Cu")
			(hatch none 0.5)
			(connect_pads
				(clearance 0)
			)
			(min_thickness 0.25)
			(keepout
				(tracks not_allowed)
				(vias allowed)
				(pads allowed)
				(copperpour not_allowed)
				(footprints allowed)
			)
			(placement
				(enabled no)
				(sheetname "")
			)
			(fill
				(thermal_gap 0.5)
				(thermal_bridge_width 0.5)
				(island_removal_mode 0)
			)
			(polygon
				(pts
					(xy 147.6502 -19.7612) (xy 147.6502 -19.6088) (xy 148.2598 -19.6088) (xy 148.2598 -19.7612)
				)
			)
		)
	)
	(footprint ""
		(layer "B.Cu")
		(at 156.718 -42.037 -90)
		(property "Reference" "R429"
			(at 8.29437 0.635 0)
			(unlocked yes)
			(layer "B.SilkS")
			(effects
				(font
					(size 0.7874 0.5842)
					(thickness 0.1524)
				)
				(justify mirror)
			)
		)
		(property "Value" "VAL*"
			(at -0.02032 2.13233 270)
			(unlocked yes)
			(layer "B.Fab")
			(hide yes)
			(effects
				(font
					(size 0.7874 0.5842)
					(thickness 0.1524)
				)
				(justify mirror)
			)
		)
		(property "Tolerance" "TOL*"
			(at -0.044704 3.05435 270)
			(unlocked yes)
			(layer "Cmts.User")
			(hide yes)
			(effects
				(font
					(size 0.7874 0.5842)
					(thickness 0.1524)
				)
				(justify mirror)
			)
		)
		(property "User Part Number" "PARTNUM*"
			(at -0.02032 4.024884 270)
			(unlocked yes)
			(layer "Cmts.User")
			(hide yes)
			(effects
				(font
					(size 0.7874 0.5842)
					(thickness 0.1524)
				)
				(justify mirror)
			)
		)
		(property "Device Type" "RESISTOR-G155-133R0-01,33OHM,1%"
			(at -0.008382 1.210564 270)
			(unlocked yes)
			(layer "B.Fab")
			(hide yes)
			(effects
				(font
					(size 0.7874 0.5842)
					(thickness 0.1524)
				)
				(justify mirror)
			)
		)
		(duplicate_pad_numbers_are_jumpers no)
		(fp_line
			(start -1.143 0.5588)
			(end -1.143 -0.5588)
			(stroke
				(width 0.1)
				(type default)
			)
			(layer "B.SilkS")
		)
		(fp_line
			(start 1.143 0.5588)
			(end -1.143 0.5588)
			(stroke
				(width 0.1)
				(type default)
			)
			(layer "B.SilkS")
		)
		(fp_line
			(start -1.143 -0.5588)
			(end 1.143 -0.5588)
			(stroke
				(width 0.1)
				(type default)
			)
			(layer "B.SilkS")
		)
		(fp_line
			(start 1.143 -0.5588)
			(end 1.143 0.5588)
			(stroke
				(width 0.1)
				(type default)
			)
			(layer "B.SilkS")
		)
		(fp_poly
			(pts
				(xy 1.143 0.5588) (xy -1.143 0.5588) (xy -1.143 -0.5588) (xy 1.143 -0.5588)
			)
			(stroke
				(width 0)
				(type default)
			)
			(fill no)
			(layer "B.CrtYd")
		)
		(fp_line
			(start -0.508 0.3048)
			(end -0.508 -0.3048)
			(stroke
				(width 0.1)
				(type default)
			)
			(layer "B.Fab")
		)
		(fp_line
			(start 0.508 0.3048)
			(end -0.508 0.3048)
			(stroke
				(width 0.1)
				(type default)
			)
			(layer "B.Fab")
		)
		(fp_line
			(start -0.508 -0.3048)
			(end 0.508 -0.3048)
			(stroke
				(width 0.1)
				(type default)
			)
			(layer "B.Fab")
		)
		(fp_line
			(start 0.508 -0.3048)
			(end 0.508 0.3048)
			(stroke
				(width 0.1)
				(type default)
			)
			(layer "B.Fab")
		)
		(pad "1" smd rect
			(at 0.5334 0 90)
			(size 0.7112 0.6096)
			(layers "B.Cu" "B.Mask" "B.Paste")
			(net "FPGA_IO_5")
		)
		(pad "2" smd rect
			(at -0.5334 0 90)
			(size 0.7112 0.6096)
			(layers "B.Cu" "B.Mask" "B.Paste")
			(net "UNNAMED_16_CONNHDR2X6FSSMT_I1_2")
		)
		(zone
			(layer "B.Cu")
			(hatch none 0.5)
			(connect_pads
				(clearance 0)
			)
			(min_thickness 0.25)
			(keepout
				(tracks allowed)
				(vias not_allowed)
				(pads allowed)
				(copperpour not_allowed)
				(footprints allowed)
			)
			(placement
				(enabled no)
				(sheetname "")
			)
			(fill
				(thermal_gap 0.5)
				(thermal_bridge_width 0.5)
				(island_removal_mode 0)
			)
			(polygon
				(pts
					(xy 156.4132 -41.9608) (xy 157.0228 -41.9608) (xy 157.0228 -42.1132) (xy 156.4132 -42.1132)
				)
			)
		)
		(zone
			(layer "B.Cu")
			(hatch none 0.5)
			(connect_pads
				(clearance 0)
			)
			(min_thickness 0.25)
			(keepout
				(tracks not_allowed)
				(vias allowed)
				(pads allowed)
				(copperpour not_allowed)
				(footprints allowed)
			)
			(placement
				(enabled no)
				(sheetname "")
			)
			(fill
				(thermal_gap 0.5)
				(thermal_bridge_width 0.5)
				(island_removal_mode 0)
			)
			(polygon
				(pts
					(xy 156.4132 -41.9608) (xy 157.0228 -41.9608) (xy 157.0228 -42.1132) (xy 156.4132 -42.1132)
				)
			)
		)
	)
	(footprint ""
		(layer "B.Cu")
		(at 83.2358 -88.265 180)
		(property "Reference" "R60"
			(at 0.3048 5.29463 0)
			(unlocked yes)
			(layer "B.SilkS")
			(effects
				(font
					(size 0.7874 0.5842)
					(thickness 0.1524)
				)
				(justify mirror)
			)
		)
		(property "Value" "VAL*"
			(at -0.02032 2.13233 180)
			(unlocked yes)
			(layer "B.Fab")
			(hide yes)
			(effects
				(font
					(size 0.7874 0.5842)
					(thickness 0.1524)
				)
				(justify mirror)
			)
		)
		(property "Tolerance" "TOL*"
			(at -0.044704 3.05435 180)
			(unlocked yes)
			(layer "Cmts.User")
			(hide yes)
			(effects
				(font
					(size 0.7874 0.5842)
					(thickness 0.1524)
				)
				(justify mirror)
			)
		)
		(property "User Part Number" "PARTNUM*"
			(at -0.02032 4.024884 180)
			(unlocked yes)
			(layer "Cmts.User")
			(hide yes)
			(effects
				(font
					(size 0.7874 0.5842)
					(thickness 0.1524)
				)
				(justify mirror)
			)
		)
		(property "Device Type" "RESISTOR-G155-133R0-01,33OHM,1%"
			(at -0.008382 1.210564 180)
			(unlocked yes)
			(layer "B.Fab")
			(hide yes)
			(effects
				(font
					(size 0.7874 0.5842)
					(thickness 0.1524)
				)
				(justify mirror)
			)
		)
		(duplicate_pad_numbers_are_jumpers no)
		(fp_line
			(start 1.143 0.5588)
			(end -1.143 0.5588)
			(stroke
				(width 0.1)
				(type default)
			)
			(layer "B.SilkS")
		)
		(fp_line
			(start 1.143 -0.5588)
			(end 1.143 0.5588)
			(stroke
				(width 0.1)
				(type default)
			)
			(layer "B.SilkS")
		)
		(fp_line
			(start -1.143 0.5588)
			(end -1.143 -0.5588)
			(stroke
				(width 0.1)
				(type default)
			)
			(layer "B.SilkS")
		)
		(fp_line
			(start -1.143 -0.5588)
			(end 1.143 -0.5588)
			(stroke
				(width 0.1)
				(type default)
			)
			(layer "B.SilkS")
		)
		(fp_rect
			(start 1.143 -0.5588)
			(end -1.143 0.5588)
			(stroke
				(width 0)
				(type default)
			)
			(fill no)
			(layer "B.CrtYd")
		)
		(fp_line
			(start 0.508 0.3048)
			(end -0.508 0.3048)
			(stroke
				(width 0.1)
				(type default)
			)
			(layer "B.Fab")
		)
		(fp_line
			(start 0.508 -0.3048)
			(end 0.508 0.3048)
			(stroke
				(width 0.1)
				(type default)
			)
			(layer "B.Fab")
		)
		(fp_line
			(start -0.508 0.3048)
			(end -0.508 -0.3048)
			(stroke
				(width 0.1)
				(type default)
			)
			(layer "B.Fab")
		)
		(fp_line
			(start -0.508 -0.3048)
			(end 0.508 -0.3048)
			(stroke
				(width 0.1)
				(type default)
			)
			(layer "B.Fab")
		)
		(pad "1" smd rect
			(at 0.5334 0)
			(size 0.7112 0.6096)
			(layers "B.Cu" "B.Mask" "B.Paste")
			(net "FPGA_OUT_PCA9546_RST_N")
		)
		(pad "2" smd rect
			(at -0.5334 0)
			(size 0.7112 0.6096)
			(layers "B.Cu" "B.Mask" "B.Paste")
			(net "PCA9546_RST_N")
		)
		(zone
			(layer "B.Cu")
			(hatch none 0.5)
			(connect_pads
				(clearance 0)
			)
			(min_thickness 0.25)
			(keepout
				(tracks allowed)
				(vias not_allowed)
				(pads allowed)
				(copperpour not_allowed)
				(footprints allowed)
			)
			(placement
				(enabled no)
				(sheetname "")
			)
			(fill
				(thermal_gap 0.5)
				(thermal_bridge_width 0.5)
				(island_removal_mode 0)
			)
			(polygon
				(pts
					(xy 83.1596 -87.9602) (xy 83.312 -87.9602) (xy 83.312 -88.5698) (xy 83.1596 -88.5698)
				)
			)
		)
	)
	(footprint ""
		(layer "B.Cu")
		(at 109.347 -39.878 -90)
		(property "Reference" "C133"
			(at 1.651 41.63695 270)
			(unlocked yes)
			(layer "B.SilkS")
			(effects
				(font
					(size 0.635 0.4064)
					(thickness 0.1524)
				)
				(justify mirror)
			)
		)
		(property "Value" "VAL*"
			(at -0.0762 2.067306 270)
			(unlocked yes)
			(layer "B.Fab")
			(hide yes)
			(effects
				(font
					(size 0.7874 0.5842)
					(thickness 0.1524)
				)
				(justify mirror)
			)
		)
		(property "Device Type" "CAPACITOR-G105-0B104-CK,0.1UF,A"
			(at -0.0508 1.127506 270)
			(unlocked yes)
			(layer "B.Fab")
			(hide yes)
			(effects
				(font
					(size 0.7874 0.5842)
					(thickness 0.1524)
				)
				(justify mirror)
			)
		)
		(property "User Part Number" "PARTNUM*"
			(at -0.1016 4.023106 270)
			(unlocked yes)
			(layer "Cmts.User")
			(hide yes)
			(effects
				(font
					(size 0.7874 0.5842)
					(thickness 0.1524)
				)
				(justify mirror)
			)
		)
		(property "Tolerance" "TOL*"
			(at -0.0762 3.032506 270)
			(unlocked yes)
			(layer "Cmts.User")
			(hide yes)
			(effects
				(font
					(size 0.7874 0.5842)
					(thickness 0.1524)
				)
				(justify mirror)
			)
		)
		(duplicate_pad_numbers_are_jumpers no)
		(fp_line
			(start -1.143 0.5588)
			(end -1.143 -0.5588)
			(stroke
				(width 0.1)
				(type default)
			)
			(layer "B.SilkS")
		)
		(fp_line
			(start 1.143 0.5588)
			(end -1.143 0.5588)
			(stroke
				(width 0.1)
				(type default)
			)
			(layer "B.SilkS")
		)
		(fp_line
			(start -1.143 -0.5588)
			(end 1.143 -0.5588)
			(stroke
				(width 0.1)
				(type default)
			)
			(layer "B.SilkS")
		)
		(fp_line
			(start 1.143 -0.5588)
			(end 1.143 0.5588)
			(stroke
				(width 0.1)
				(type default)
			)
			(layer "B.SilkS")
		)
		(fp_rect
			(start 1.143 0.5588)
			(end -1.143 -0.5588)
			(stroke
				(width 0)
				(type default)
			)
			(fill no)
			(layer "B.CrtYd")
		)
		(fp_line
			(start -0.508 0.3048)
			(end -0.508 -0.3048)
			(stroke
				(width 0.1)
				(type default)
			)
			(layer "B.Fab")
		)
		(fp_line
			(start 0.508 0.3048)
			(end -0.508 0.3048)
			(stroke
				(width 0.1)
				(type default)
			)
			(layer "B.Fab")
		)
		(fp_line
			(start -0.508 -0.3048)
			(end 0.508 -0.3048)
			(stroke
				(width 0.1)
				(type default)
			)
			(layer "B.Fab")
		)
		(fp_line
			(start 0.508 -0.3048)
			(end 0.508 0.3048)
			(stroke
				(width 0.1)
				(type default)
			)
			(layer "B.Fab")
		)
		(pad "1" smd rect
			(at 0.5334 0 90)
			(size 0.7112 0.6096)
			(layers "B.Cu" "B.Mask" "B.Paste")
			(net "XP1R0V_FPGA_VCCINT")
		)
		(pad "2" smd rect
			(at -0.5334 0 90)
			(size 0.7112 0.6096)
			(layers "B.Cu" "B.Mask" "B.Paste")
			(net "SG")
		)
		(zone
			(layer "B.Cu")
			(hatch none 0.5)
			(connect_pads
				(clearance 0)
			)
			(min_thickness 0.25)
			(keepout
				(tracks allowed)
				(vias not_allowed)
				(pads allowed)
				(copperpour not_allowed)
				(footprints allowed)
			)
			(placement
				(enabled no)
				(sheetname "")
			)
			(fill
				(thermal_gap 0.5)
				(thermal_bridge_width 0.5)
				(island_removal_mode 0)
			)
			(polygon
				(pts
					(xy 109.0422 -39.8018) (xy 109.6518 -39.8018) (xy 109.6518 -39.9542) (xy 109.0422 -39.9542)
				)
			)
		)
	)
	(footprint ""
		(layer "B.Cu")
		(at 127.254 -87.757 180)
		(property "Reference" "R269"
			(at -2.794 -0.16637 0)
			(unlocked yes)
			(layer "B.SilkS")
			(effects
				(font
					(size 0.7874 0.5842)
					(thickness 0.1524)
				)
				(justify mirror)
			)
		)
		(property "Value" "VAL*"
			(at -0.02032 2.13233 180)
			(unlocked yes)
			(layer "B.Fab")
			(hide yes)
			(effects
				(font
					(size 0.7874 0.5842)
					(thickness 0.1524)
				)
				(justify mirror)
			)
		)
		(property "Tolerance" "TOL*"
			(at -0.044704 3.05435 180)
			(unlocked yes)
			(layer "Cmts.User")
			(hide yes)
			(effects
				(font
					(size 0.7874 0.5842)
					(thickness 0.1524)
				)
				(justify mirror)
			)
		)
		(property "User Part Number" "PARTNUM*"
			(at -0.02032 4.024884 180)
			(unlocked yes)
			(layer "Cmts.User")
			(hide yes)
			(effects
				(font
					(size 0.7874 0.5842)
					(thickness 0.1524)
				)
				(justify mirror)
			)
		)
		(property "Device Type" "RESISTOR-G155-11003-01,100KOHMA"
			(at -0.008382 1.210564 180)
			(unlocked yes)
			(layer "B.Fab")
			(hide yes)
			(effects
				(font
					(size 0.7874 0.5842)
					(thickness 0.1524)
				)
				(justify mirror)
			)
		)
		(duplicate_pad_numbers_are_jumpers no)
		(fp_line
			(start 1.143 0.5588)
			(end -1.143 0.5588)
			(stroke
				(width 0.1)
				(type default)
			)
			(layer "B.SilkS")
		)
		(fp_line
			(start 1.143 -0.5588)
			(end 1.143 0.5588)
			(stroke
				(width 0.1)
				(type default)
			)
			(layer "B.SilkS")
		)
		(fp_line
			(start -1.143 0.5588)
			(end -1.143 -0.5588)
			(stroke
				(width 0.1)
				(type default)
			)
			(layer "B.SilkS")
		)
		(fp_line
			(start -1.143 -0.5588)
			(end 1.143 -0.5588)
			(stroke
				(width 0.1)
				(type default)
			)
			(layer "B.SilkS")
		)
		(fp_rect
			(start -1.143 -0.5588)
			(end 1.143 0.5588)
			(stroke
				(width 0)
				(type default)
			)
			(fill no)
			(layer "B.CrtYd")
		)
		(fp_line
			(start 0.508 0.3048)
			(end -0.508 0.3048)
			(stroke
				(width 0.1)
				(type default)
			)
			(layer "B.Fab")
		)
		(fp_line
			(start 0.508 -0.3048)
			(end 0.508 0.3048)
			(stroke
				(width 0.1)
				(type default)
			)
			(layer "B.Fab")
		)
		(fp_line
			(start -0.508 0.3048)
			(end -0.508 -0.3048)
			(stroke
				(width 0.1)
				(type default)
			)
			(layer "B.Fab")
		)
		(fp_line
			(start -0.508 -0.3048)
			(end 0.508 -0.3048)
			(stroke
				(width 0.1)
				(type default)
			)
			(layer "B.Fab")
		)
		(pad "1" smd rect
			(at 0.5334 0)
			(size 0.7112 0.6096)
			(layers "B.Cu" "B.Mask" "B.Paste")
			(net "XP3R3V_FPGA")
		)
		(pad "2" smd rect
			(at -0.5334 0)
			(size 0.7112 0.6096)
			(layers "B.Cu" "B.Mask" "B.Paste")
			(net "UART_GPS_TX_FPGA_RX")
		)
		(zone
			(layer "B.Cu")
			(hatch none 0.5)
			(connect_pads
				(clearance 0)
			)
			(min_thickness 0.25)
			(keepout
				(tracks not_allowed)
				(vias allowed)
				(pads allowed)
				(copperpour not_allowed)
				(footprints allowed)
			)
			(placement
				(enabled no)
				(sheetname "")
			)
			(fill
				(thermal_gap 0.5)
				(thermal_bridge_width 0.5)
				(island_removal_mode 0)
			)
			(polygon
				(pts
					(xy 127.3302 -87.4522) (xy 127.3302 -88.0618) (xy 127.1778 -88.0618) (xy 127.1778 -87.4522)
				)
			)
		)
		(zone
			(layer "B.Cu")
			(hatch none 0.5)
			(connect_pads
				(clearance 0)
			)
			(min_thickness 0.25)
			(keepout
				(tracks allowed)
				(vias not_allowed)
				(pads allowed)
				(copperpour not_allowed)
				(footprints allowed)
			)
			(placement
				(enabled no)
				(sheetname "")
			)
			(fill
				(thermal_gap 0.5)
				(thermal_bridge_width 0.5)
				(island_removal_mode 0)
			)
			(polygon
				(pts
					(xy 127.3302 -87.4522) (xy 127.3302 -88.0618) (xy 127.1778 -88.0618) (xy 127.1778 -87.4522)
				)
			)
		)
	)
	(footprint ""
		(layer "B.Cu")
		(at 101.847142 -39.323264 -90)
		(property "Reference" "C218"
			(at 1.268984 42.018712 270)
			(unlocked yes)
			(layer "B.SilkS")
			(effects
				(font
					(size 0.635 0.4064)
					(thickness 0.1524)
				)
				(justify mirror)
			)
		)
		(property "Value" "VAL*"
			(at 0 3.718306 270)
			(unlocked yes)
			(layer "B.Fab")
			(hide yes)
			(effects
				(font
					(size 0.7874 0.5842)
					(thickness 0.127)
				)
				(justify mirror)
			)
		)
		(property "Tolerance" "TOL*"
			(at 0 4.861306 270)
			(unlocked yes)
			(layer "Cmts.User")
			(hide yes)
			(effects
				(font
					(size 0.7874 0.5842)
					(thickness 0.127)
				)
				(justify mirror)
			)
		)
		(property "User Part Number" "PARTNUM*"
			(at 0 2.575306 270)
			(unlocked yes)
			(layer "Cmts.User")
			(hide yes)
			(effects
				(font
					(size 0.7874 0.5842)
					(thickness 0.127)
				)
				(justify mirror)
			)
		)
		(property "Device Type" "CAPACITOR-G105-0B104-CK,0.1UF,A"
			(at 0 1.432306 270)
			(unlocked yes)
			(layer "B.Fab")
			(hide yes)
			(effects
				(font
					(size 0.7874 0.5842)
					(thickness 0.127)
				)
				(justify mirror)
			)
		)
		(duplicate_pad_numbers_are_jumpers no)
		(fp_line
			(start -0.970026 0.4699)
			(end 0.970026 0.4699)
			(stroke
				(width 0.1)
				(type default)
			)
			(layer "B.SilkS")
		)
		(fp_line
			(start 0.970026 0.4699)
			(end 0.970026 -0.4699)
			(stroke
				(width 0.1)
				(type default)
			)
			(layer "B.SilkS")
		)
		(fp_line
			(start -0.970026 -0.4699)
			(end -0.970026 0.4699)
			(stroke
				(width 0.1)
				(type default)
			)
			(layer "B.SilkS")
		)
		(fp_line
			(start 0.970026 -0.4699)
			(end -0.970026 -0.4699)
			(stroke
				(width 0.1)
				(type default)
			)
			(layer "B.SilkS")
		)
		(fp_poly
			(pts
				(xy 0.970026 0.4699) (xy -0.970026 0.4699) (xy -0.970026 -0.4699) (xy 0.970026 -0.4699)
			)
			(stroke
				(width 0)
				(type default)
			)
			(fill no)
			(layer "B.CrtYd")
		)
		(fp_line
			(start -0.508 0.3048)
			(end 0.508 0.3048)
			(stroke
				(width 0.1)
				(type default)
			)
			(layer "B.Fab")
		)
		(fp_line
			(start 0.508 0.3048)
			(end 0.508 -0.3048)
			(stroke
				(width 0.1)
				(type default)
			)
			(layer "B.Fab")
		)
		(fp_line
			(start -0.508 -0.3048)
			(end -0.508 0.3048)
			(stroke
				(width 0.1)
				(type default)
			)
			(layer "B.Fab")
		)
		(fp_line
			(start 0.508 -0.3048)
			(end -0.508 -0.3048)
			(stroke
				(width 0.1)
				(type default)
			)
			(layer "B.Fab")
		)
		(pad "1" smd circle
			(at 0.500126 0 90)
			(size 0.635 0.635)
			(layers "B.Cu" "B.Mask" "B.Paste")
			(net "XP1R0V_FPGA_MGTAVCC")
		)
		(pad "2" smd circle
			(at -0.500126 0 90)
			(size 0.635 0.635)
			(layers "B.Cu" "B.Mask" "B.Paste")
			(net "SG")
		)
	)
	(footprint ""
		(layer "B.Cu")
		(at 18.415 -81.28 180)
		(property "Reference" "R479"
			(at -3.81 -0.42037 0)
			(unlocked yes)
			(layer "B.SilkS")
			(effects
				(font
					(size 0.7874 0.5842)
					(thickness 0.1524)
				)
				(justify mirror)
			)
		)
		(property "Value" "VAL*"
			(at -0.02032 2.13233 180)
			(unlocked yes)
			(layer "B.Fab")
			(hide yes)
			(effects
				(font
					(size 0.7874 0.5842)
					(thickness 0.1524)
				)
				(justify mirror)
			)
		)
		(property "Tolerance" "TOL*"
			(at -0.044704 3.05435 180)
			(unlocked yes)
			(layer "Cmts.User")
			(hide yes)
			(effects
				(font
					(size 0.7874 0.5842)
					(thickness 0.1524)
				)
				(justify mirror)
			)
		)
		(property "User Part Number" "PARTNUM*"
			(at -0.02032 4.024884 180)
			(unlocked yes)
			(layer "Cmts.User")
			(hide yes)
			(effects
				(font
					(size 0.7874 0.5842)
					(thickness 0.1524)
				)
				(justify mirror)
			)
		)
		(property "Device Type" "RESISTOR-G155-11003-01,100KOHMA"
			(at -0.008382 1.210564 180)
			(unlocked yes)
			(layer "B.Fab")
			(hide yes)
			(effects
				(font
					(size 0.7874 0.5842)
					(thickness 0.1524)
				)
				(justify mirror)
			)
		)
		(duplicate_pad_numbers_are_jumpers no)
		(fp_line
			(start 1.143 0.5588)
			(end -1.143 0.5588)
			(stroke
				(width 0.1)
				(type default)
			)
			(layer "B.SilkS")
		)
		(fp_line
			(start 1.143 -0.5588)
			(end 1.143 0.5588)
			(stroke
				(width 0.1)
				(type default)
			)
			(layer "B.SilkS")
		)
		(fp_line
			(start -1.143 0.5588)
			(end -1.143 -0.5588)
			(stroke
				(width 0.1)
				(type default)
			)
			(layer "B.SilkS")
		)
		(fp_line
			(start -1.143 -0.5588)
			(end 1.143 -0.5588)
			(stroke
				(width 0.1)
				(type default)
			)
			(layer "B.SilkS")
		)
		(fp_poly
			(pts
				(xy 1.143 0.5588) (xy -1.143 0.5588) (xy -1.143 -0.5588) (xy 1.143 -0.5588)
			)
			(stroke
				(width 0)
				(type default)
			)
			(fill no)
			(layer "B.CrtYd")
		)
		(fp_line
			(start 0.508 0.3048)
			(end -0.508 0.3048)
			(stroke
				(width 0.1)
				(type default)
			)
			(layer "B.Fab")
		)
		(fp_line
			(start 0.508 -0.3048)
			(end 0.508 0.3048)
			(stroke
				(width 0.1)
				(type default)
			)
			(layer "B.Fab")
		)
		(fp_line
			(start -0.508 0.3048)
			(end -0.508 -0.3048)
			(stroke
				(width 0.1)
				(type default)
			)
			(layer "B.Fab")
		)
		(fp_line
			(start -0.508 -0.3048)
			(end 0.508 -0.3048)
			(stroke
				(width 0.1)
				(type default)
			)
			(layer "B.Fab")
		)
		(pad "1" smd rect
			(at 0.5334 0)
			(size 0.7112 0.6096)
			(layers "B.Cu" "B.Mask" "B.Paste")
			(net "FT4232_I2C_SDA")
		)
		(pad "2" smd rect
			(at -0.5334 0)
			(size 0.7112 0.6096)
			(layers "B.Cu" "B.Mask" "B.Paste")
			(net "XP3R3V_FT4232")
		)
		(zone
			(layer "B.Cu")
			(hatch none 0.5)
			(connect_pads
				(clearance 0)
			)
			(min_thickness 0.25)
			(keepout
				(tracks not_allowed)
				(vias allowed)
				(pads allowed)
				(copperpour not_allowed)
				(footprints allowed)
			)
			(placement
				(enabled no)
				(sheetname "")
			)
			(fill
				(thermal_gap 0.5)
				(thermal_bridge_width 0.5)
				(island_removal_mode 0)
			)
			(polygon
				(pts
					(xy 18.3388 -81.5848) (xy 18.3388 -80.9752) (xy 18.4912 -80.9752) (xy 18.4912 -81.5848)
				)
			)
		)
		(zone
			(layer "B.Cu")
			(hatch none 0.5)
			(connect_pads
				(clearance 0)
			)
			(min_thickness 0.25)
			(keepout
				(tracks allowed)
				(vias not_allowed)
				(pads allowed)
				(copperpour not_allowed)
				(footprints allowed)
			)
			(placement
				(enabled no)
				(sheetname "")
			)
			(fill
				(thermal_gap 0.5)
				(thermal_bridge_width 0.5)
				(island_removal_mode 0)
			)
			(polygon
				(pts
					(xy 18.3388 -81.5848) (xy 18.3388 -80.9752) (xy 18.4912 -80.9752) (xy 18.4912 -81.5848)
				)
			)
		)
	)
	(footprint ""
		(layer "B.Cu")
		(at 64.516 -55.753 90)
		(property "Reference" "R99"
			(at -6.35 0.34163 270)
			(unlocked yes)
			(layer "B.SilkS")
			(effects
				(font
					(size 0.7874 0.5842)
					(thickness 0.1524)
				)
				(justify mirror)
			)
		)
		(property "Value" "VAL*"
			(at -0.02032 2.13233 90)
			(unlocked yes)
			(layer "B.Fab")
			(hide yes)
			(effects
				(font
					(size 0.7874 0.5842)
					(thickness 0.1524)
				)
				(justify mirror)
			)
		)
		(property "Tolerance" "TOL*"
			(at -0.044704 3.05435 90)
			(unlocked yes)
			(layer "Cmts.User")
			(hide yes)
			(effects
				(font
					(size 0.7874 0.5842)
					(thickness 0.1524)
				)
				(justify mirror)
			)
		)
		(property "User Part Number" "PARTNUM*"
			(at -0.02032 4.024884 90)
			(unlocked yes)
			(layer "Cmts.User")
			(hide yes)
			(effects
				(font
					(size 0.7874 0.5842)
					(thickness 0.1524)
				)
				(justify mirror)
			)
		)
		(property "Device Type" "RESISTOR-G155-14701-01,4.7KOHMA"
			(at -0.008382 1.210564 90)
			(unlocked yes)
			(layer "B.Fab")
			(hide yes)
			(effects
				(font
					(size 0.7874 0.5842)
					(thickness 0.1524)
				)
				(justify mirror)
			)
		)
		(duplicate_pad_numbers_are_jumpers no)
		(fp_line
			(start 1.143 -0.5588)
			(end 1.143 0.5588)
			(stroke
				(width 0.1)
				(type default)
			)
			(layer "B.SilkS")
		)
		(fp_line
			(start -1.143 -0.5588)
			(end 1.143 -0.5588)
			(stroke
				(width 0.1)
				(type default)
			)
			(layer "B.SilkS")
		)
		(fp_line
			(start 1.143 0.5588)
			(end -1.143 0.5588)
			(stroke
				(width 0.1)
				(type default)
			)
			(layer "B.SilkS")
		)
		(fp_line
			(start -1.143 0.5588)
			(end -1.143 -0.5588)
			(stroke
				(width 0.1)
				(type default)
			)
			(layer "B.SilkS")
		)
		(fp_rect
			(start -1.143 -0.5588)
			(end 1.143 0.5588)
			(stroke
				(width 0)
				(type default)
			)
			(fill no)
			(layer "B.CrtYd")
		)
		(fp_line
			(start 0.508 -0.3048)
			(end 0.508 0.3048)
			(stroke
				(width 0.1)
				(type default)
			)
			(layer "B.Fab")
		)
		(fp_line
			(start -0.508 -0.3048)
			(end 0.508 -0.3048)
			(stroke
				(width 0.1)
				(type default)
			)
			(layer "B.Fab")
		)
		(fp_line
			(start 0.508 0.3048)
			(end -0.508 0.3048)
			(stroke
				(width 0.1)
				(type default)
			)
			(layer "B.Fab")
		)
		(fp_line
			(start -0.508 0.3048)
			(end -0.508 -0.3048)
			(stroke
				(width 0.1)
				(type default)
			)
			(layer "B.Fab")
		)
		(pad "1" smd rect
			(at 0.5334 0 270)
			(size 0.7112 0.6096)
			(layers "B.Cu" "B.Mask" "B.Paste")
			(net "FPGA_OUT_MACUSBPOWER_EN")
		)
		(pad "2" smd rect
			(at -0.5334 0 270)
			(size 0.7112 0.6096)
			(layers "B.Cu" "B.Mask" "B.Paste")
			(net "SG")
		)
		(zone
			(layer "B.Cu")
			(hatch none 0.5)
			(connect_pads
				(clearance 0)
			)
			(min_thickness 0.25)
			(keepout
				(tracks allowed)
				(vias not_allowed)
				(pads allowed)
				(copperpour not_allowed)
				(footprints allowed)
			)
			(placement
				(enabled no)
				(sheetname "")
			)
			(fill
				(thermal_gap 0.5)
				(thermal_bridge_width 0.5)
				(island_removal_mode 0)
			)
			(polygon
				(pts
					(xy 64.2112 -55.6768) (xy 64.8208 -55.6768) (xy 64.8208 -55.8292) (xy 64.2112 -55.8292)
				)
			)
		)
	)
	(footprint ""
		(layer "B.Cu")
		(at 65.786 -58.039 90)
		(property "Reference" "C69"
			(at -2.794 -0.03937 270)
			(unlocked yes)
			(layer "B.SilkS")
			(effects
				(font
					(size 0.7874 0.5842)
					(thickness 0.1524)
				)
				(justify mirror)
			)
		)
		(property "Value" "VAL*"
			(at -0.0762 2.067306 90)
			(unlocked yes)
			(layer "B.Fab")
			(hide yes)
			(effects
				(font
					(size 0.7874 0.5842)
					(thickness 0.1524)
				)
				(justify mirror)
			)
		)
		(property "Device Type" "CAPACITOR-G105-0B104-EK,0.1UF,A"
			(at -0.0508 1.127506 90)
			(unlocked yes)
			(layer "B.Fab")
			(hide yes)
			(effects
				(font
					(size 0.7874 0.5842)
					(thickness 0.1524)
				)
				(justify mirror)
			)
		)
		(property "User Part Number" "PARTNUM*"
			(at -0.1016 4.023106 90)
			(unlocked yes)
			(layer "Cmts.User")
			(hide yes)
			(effects
				(font
					(size 0.7874 0.5842)
					(thickness 0.1524)
				)
				(justify mirror)
			)
		)
		(property "Tolerance" "TOL*"
			(at -0.0762 3.032506 90)
			(unlocked yes)
			(layer "Cmts.User")
			(hide yes)
			(effects
				(font
					(size 0.7874 0.5842)
					(thickness 0.1524)
				)
				(justify mirror)
			)
		)
		(duplicate_pad_numbers_are_jumpers no)
		(fp_line
			(start 1.143 -0.5588)
			(end 1.143 0.5588)
			(stroke
				(width 0.1)
				(type default)
			)
			(layer "B.SilkS")
		)
		(fp_line
			(start -1.143 -0.5588)
			(end 1.143 -0.5588)
			(stroke
				(width 0.1)
				(type default)
			)
			(layer "B.SilkS")
		)
		(fp_line
			(start 1.143 0.5588)
			(end -1.143 0.5588)
			(stroke
				(width 0.1)
				(type default)
			)
			(layer "B.SilkS")
		)
		(fp_line
			(start -1.143 0.5588)
			(end -1.143 -0.5588)
			(stroke
				(width 0.1)
				(type default)
			)
			(layer "B.SilkS")
		)
		(fp_rect
			(start -1.143 -0.5588)
			(end 1.143 0.5588)
			(stroke
				(width 0)
				(type default)
			)
			(fill no)
			(layer "B.CrtYd")
		)
		(fp_line
			(start 0.508 -0.3048)
			(end 0.508 0.3048)
			(stroke
				(width 0.1)
				(type default)
			)
			(layer "B.Fab")
		)
		(fp_line
			(start -0.508 -0.3048)
			(end 0.508 -0.3048)
			(stroke
				(width 0.1)
				(type default)
			)
			(layer "B.Fab")
		)
		(fp_line
			(start 0.508 0.3048)
			(end -0.508 0.3048)
			(stroke
				(width 0.1)
				(type default)
			)
			(layer "B.Fab")
		)
		(fp_line
			(start -0.508 0.3048)
			(end -0.508 -0.3048)
			(stroke
				(width 0.1)
				(type default)
			)
			(layer "B.Fab")
		)
		(pad "1" smd rect
			(at 0.5334 0 270)
			(size 0.7112 0.6096)
			(layers "B.Cu" "B.Mask" "B.Paste")
			(net "USB_PWR_EN")
		)
		(pad "2" smd rect
			(at -0.5334 0 270)
			(size 0.7112 0.6096)
			(layers "B.Cu" "B.Mask" "B.Paste")
			(net "SG")
		)
		(zone
			(layer "B.Cu")
			(hatch none 0.5)
			(connect_pads
				(clearance 0)
			)
			(min_thickness 0.25)
			(keepout
				(tracks allowed)
				(vias not_allowed)
				(pads allowed)
				(copperpour not_allowed)
				(footprints allowed)
			)
			(placement
				(enabled no)
				(sheetname "")
			)
			(fill
				(thermal_gap 0.5)
				(thermal_bridge_width 0.5)
				(island_removal_mode 0)
			)
			(polygon
				(pts
					(xy 65.4812 -57.9628) (xy 66.0908 -57.9628) (xy 66.0908 -58.1152) (xy 65.4812 -58.1152)
				)
			)
		)
	)
	(footprint ""
		(layer "B.Cu")
		(at 71.5645 -49.403 180)
		(property "Reference" "R89"
			(at 2.3495 -0.03937 0)
			(unlocked yes)
			(layer "B.SilkS")
			(effects
				(font
					(size 0.7874 0.5842)
					(thickness 0.1524)
				)
				(justify mirror)
			)
		)
		(property "Value" "VAL*"
			(at -0.02032 2.13233 180)
			(unlocked yes)
			(layer "B.Fab")
			(hide yes)
			(effects
				(font
					(size 0.7874 0.5842)
					(thickness 0.1524)
				)
				(justify mirror)
			)
		)
		(property "Tolerance" "TOL*"
			(at -0.044704 3.05435 180)
			(unlocked yes)
			(layer "Cmts.User")
			(hide yes)
			(effects
				(font
					(size 0.7874 0.5842)
					(thickness 0.1524)
				)
				(justify mirror)
			)
		)
		(property "User Part Number" "PARTNUM*"
			(at -0.02032 4.024884 180)
			(unlocked yes)
			(layer "Cmts.User")
			(hide yes)
			(effects
				(font
					(size 0.7874 0.5842)
					(thickness 0.1524)
				)
				(justify mirror)
			)
		)
		(property "Device Type" "RESISTOR-G155-11000-01,100OHM,A"
			(at -0.008382 1.210564 180)
			(unlocked yes)
			(layer "B.Fab")
			(hide yes)
			(effects
				(font
					(size 0.7874 0.5842)
					(thickness 0.1524)
				)
				(justify mirror)
			)
		)
		(duplicate_pad_numbers_are_jumpers no)
		(fp_line
			(start 1.143 0.5588)
			(end -1.143 0.5588)
			(stroke
				(width 0.1)
				(type default)
			)
			(layer "B.SilkS")
		)
		(fp_line
			(start 1.143 -0.5588)
			(end 1.143 0.5588)
			(stroke
				(width 0.1)
				(type default)
			)
			(layer "B.SilkS")
		)
		(fp_line
			(start -1.143 0.5588)
			(end -1.143 -0.5588)
			(stroke
				(width 0.1)
				(type default)
			)
			(layer "B.SilkS")
		)
		(fp_line
			(start -1.143 -0.5588)
			(end 1.143 -0.5588)
			(stroke
				(width 0.1)
				(type default)
			)
			(layer "B.SilkS")
		)
		(fp_rect
			(start -1.143 0.5588)
			(end 1.143 -0.5588)
			(stroke
				(width 0)
				(type default)
			)
			(fill no)
			(layer "B.CrtYd")
		)
		(fp_line
			(start 0.508 0.3048)
			(end -0.508 0.3048)
			(stroke
				(width 0.1)
				(type default)
			)
			(layer "B.Fab")
		)
		(fp_line
			(start 0.508 -0.3048)
			(end 0.508 0.3048)
			(stroke
				(width 0.1)
				(type default)
			)
			(layer "B.Fab")
		)
		(fp_line
			(start -0.508 0.3048)
			(end -0.508 -0.3048)
			(stroke
				(width 0.1)
				(type default)
			)
			(layer "B.Fab")
		)
		(fp_line
			(start -0.508 -0.3048)
			(end 0.508 -0.3048)
			(stroke
				(width 0.1)
				(type default)
			)
			(layer "B.Fab")
		)
		(pad "1" smd rect
			(at 0.5334 0)
			(size 0.7112 0.6096)
			(layers "B.Cu" "B.Mask" "B.Paste")
			(net "R_MAC_PPS_IN1P")
		)
		(pad "2" smd rect
			(at -0.5334 0)
			(size 0.7112 0.6096)
			(layers "B.Cu" "B.Mask" "B.Paste")
			(net "R_MAC_PPS_IN1N")
		)
		(zone
			(layer "B.Cu")
			(hatch none 0.5)
			(connect_pads
				(clearance 0)
			)
			(min_thickness 0.25)
			(keepout
				(tracks allowed)
				(vias not_allowed)
				(pads allowed)
				(copperpour not_allowed)
				(footprints allowed)
			)
			(placement
				(enabled no)
				(sheetname "")
			)
			(fill
				(thermal_gap 0.5)
				(thermal_bridge_width 0.5)
				(island_removal_mode 0)
			)
			(polygon
				(pts
					(xy 71.6407 -49.7078) (xy 71.4883 -49.7078) (xy 71.4883 -49.0982) (xy 71.6407 -49.0982)
				)
			)
		)
	)
	(footprint ""
		(layer "B.Cu")
		(at 13.589 -22.987 90)
		(property "Reference" "R493"
			(at 0 0.98425 270)
			(unlocked yes)
			(layer "B.SilkS")
			(effects
				(font
					(size 0.635 0.4064)
					(thickness 0.1524)
				)
				(justify mirror)
			)
		)
		(property "Value" "VAL*"
			(at -0.02032 2.13233 90)
			(unlocked yes)
			(layer "B.Fab")
			(hide yes)
			(effects
				(font
					(size 0.7874 0.5842)
					(thickness 0.1524)
				)
				(justify mirror)
			)
		)
		(property "Tolerance" "TOL*"
			(at -0.044704 3.05435 90)
			(unlocked yes)
			(layer "Cmts.User")
			(hide yes)
			(effects
				(font
					(size 0.7874 0.5842)
					(thickness 0.1524)
				)
				(justify mirror)
			)
		)
		(property "User Part Number" "PARTNUM*"
			(at -0.02032 4.024884 90)
			(unlocked yes)
			(layer "Cmts.User")
			(hide yes)
			(effects
				(font
					(size 0.7874 0.5842)
					(thickness 0.1524)
				)
				(justify mirror)
			)
		)
		(property "Device Type" "RESISTOR-G155-100R0-J0,0OHM,-"
			(at -0.008382 1.210564 90)
			(unlocked yes)
			(layer "B.Fab")
			(hide yes)
			(effects
				(font
					(size 0.7874 0.5842)
					(thickness 0.1524)
				)
				(justify mirror)
			)
		)
		(duplicate_pad_numbers_are_jumpers no)
		(fp_line
			(start 1.143 -0.5588)
			(end 1.143 0.5588)
			(stroke
				(width 0.1)
				(type default)
			)
			(layer "B.SilkS")
		)
		(fp_line
			(start -1.143 -0.5588)
			(end 1.143 -0.5588)
			(stroke
				(width 0.1)
				(type default)
			)
			(layer "B.SilkS")
		)
		(fp_line
			(start 1.143 0.5588)
			(end -1.143 0.5588)
			(stroke
				(width 0.1)
				(type default)
			)
			(layer "B.SilkS")
		)
		(fp_line
			(start -1.143 0.5588)
			(end -1.143 -0.5588)
			(stroke
				(width 0.1)
				(type default)
			)
			(layer "B.SilkS")
		)
		(fp_poly
			(pts
				(xy 1.143 0.5588) (xy -1.143 0.5588) (xy -1.143 -0.5588) (xy 1.143 -0.5588)
			)
			(stroke
				(width 0)
				(type default)
			)
			(fill no)
			(layer "B.CrtYd")
		)
		(fp_line
			(start 0.508 -0.3048)
			(end 0.508 0.3048)
			(stroke
				(width 0.1)
				(type default)
			)
			(layer "B.Fab")
		)
		(fp_line
			(start -0.508 -0.3048)
			(end 0.508 -0.3048)
			(stroke
				(width 0.1)
				(type default)
			)
			(layer "B.Fab")
		)
		(fp_line
			(start 0.508 0.3048)
			(end -0.508 0.3048)
			(stroke
				(width 0.1)
				(type default)
			)
			(layer "B.Fab")
		)
		(fp_line
			(start -0.508 0.3048)
			(end -0.508 -0.3048)
			(stroke
				(width 0.1)
				(type default)
			)
			(layer "B.Fab")
		)
		(pad "1" smd rect
			(at 0.5334 0 270)
			(size 0.7112 0.6096)
			(layers "B.Cu" "B.Mask" "B.Paste")
			(net "UNNAMED_12_CAPACITOR_I321_2")
		)
		(pad "2" smd rect
			(at -0.5334 0 270)
			(size 0.7112 0.6096)
			(layers "B.Cu" "B.Mask" "B.Paste")
			(net "UNNAMED_12_74HCT2G125DPTSSOP8_3")
		)
		(zone
			(layer "B.Cu")
			(hatch none 0.5)
			(connect_pads
				(clearance 0)
			)
			(min_thickness 0.25)
			(keepout
				(tracks allowed)
				(vias not_allowed)
				(pads allowed)
				(copperpour not_allowed)
				(footprints allowed)
			)
			(placement
				(enabled no)
				(sheetname "")
			)
			(fill
				(thermal_gap 0.5)
				(thermal_bridge_width 0.5)
				(island_removal_mode 0)
			)
			(polygon
				(pts
					(xy 13.8938 -23.0632) (xy 13.2842 -23.0632) (xy 13.2842 -22.9108) (xy 13.8938 -22.9108)
				)
			)
		)
		(zone
			(layer "B.Cu")
			(hatch none 0.5)
			(connect_pads
				(clearance 0)
			)
			(min_thickness 0.25)
			(keepout
				(tracks not_allowed)
				(vias allowed)
				(pads allowed)
				(copperpour not_allowed)
				(footprints allowed)
			)
			(placement
				(enabled no)
				(sheetname "")
			)
			(fill
				(thermal_gap 0.5)
				(thermal_bridge_width 0.5)
				(island_removal_mode 0)
			)
			(polygon
				(pts
					(xy 13.8938 -23.0632) (xy 13.2842 -23.0632) (xy 13.2842 -22.9108) (xy 13.8938 -22.9108)
				)
			)
		)
	)
	(footprint ""
		(layer "B.Cu")
		(at 30.988 -91.059 -90)
		(property "Reference" "C99"
			(at -2.794 -0.21463 270)
			(unlocked yes)
			(layer "B.SilkS")
			(effects
				(font
					(size 0.7874 0.5842)
					(thickness 0.1524)
				)
				(justify mirror)
			)
		)
		(property "Value" "VAL*"
			(at -0.02032 2.13233 270)
			(unlocked yes)
			(layer "B.Fab")
			(hide yes)
			(effects
				(font
					(size 0.7874 0.5842)
					(thickness 0.1524)
				)
				(justify mirror)
			)
		)
		(property "Tolerance" "TOL*"
			(at -0.044704 3.05435 270)
			(unlocked yes)
			(layer "Cmts.User")
			(hide yes)
			(effects
				(font
					(size 0.7874 0.5842)
					(thickness 0.1524)
				)
				(justify mirror)
			)
		)
		(property "User Part Number" "PARTNUM*"
			(at -0.02032 4.024884 270)
			(unlocked yes)
			(layer "Cmts.User")
			(hide yes)
			(effects
				(font
					(size 0.7874 0.5842)
					(thickness 0.1524)
				)
				(justify mirror)
			)
		)
		(property "Device Type" "CAPACITOR-G105-0F475-BM,4.7UF,A"
			(at -0.008382 1.210564 270)
			(unlocked yes)
			(layer "B.Fab")
			(hide yes)
			(effects
				(font
					(size 0.7874 0.5842)
					(thickness 0.1524)
				)
				(justify mirror)
			)
		)
		(duplicate_pad_numbers_are_jumpers no)
		(fp_line
			(start -1.143 0.5588)
			(end -1.143 -0.5588)
			(stroke
				(width 0.1)
				(type default)
			)
			(layer "B.SilkS")
		)
		(fp_line
			(start 1.143 0.5588)
			(end -1.143 0.5588)
			(stroke
				(width 0.1)
				(type default)
			)
			(layer "B.SilkS")
		)
		(fp_line
			(start -1.143 -0.5588)
			(end 1.143 -0.5588)
			(stroke
				(width 0.1)
				(type default)
			)
			(layer "B.SilkS")
		)
		(fp_line
			(start 1.143 -0.5588)
			(end 1.143 0.5588)
			(stroke
				(width 0.1)
				(type default)
			)
			(layer "B.SilkS")
		)
		(fp_poly
			(pts
				(xy 1.143 0.5588) (xy -1.143 0.5588) (xy -1.143 -0.5588) (xy 1.143 -0.5588)
			)
			(stroke
				(width 0)
				(type default)
			)
			(fill no)
			(layer "B.CrtYd")
		)
		(fp_line
			(start -0.508 0.3048)
			(end -0.508 -0.3048)
			(stroke
				(width 0.1)
				(type default)
			)
			(layer "B.Fab")
		)
		(fp_line
			(start 0.508 0.3048)
			(end -0.508 0.3048)
			(stroke
				(width 0.1)
				(type default)
			)
			(layer "B.Fab")
		)
		(fp_line
			(start -0.508 -0.3048)
			(end 0.508 -0.3048)
			(stroke
				(width 0.1)
				(type default)
			)
			(layer "B.Fab")
		)
		(fp_line
			(start 0.508 -0.3048)
			(end 0.508 0.3048)
			(stroke
				(width 0.1)
				(type default)
			)
			(layer "B.Fab")
		)
		(pad "1" smd rect
			(at 0.5334 0 90)
			(size 0.7112 0.6096)
			(layers "B.Cu" "B.Mask" "B.Paste")
			(net "XP3R3V_VPHY")
		)
		(pad "2" smd rect
			(at -0.5334 0 90)
			(size 0.7112 0.6096)
			(layers "B.Cu" "B.Mask" "B.Paste")
			(net "SG")
		)
		(zone
			(layer "B.Cu")
			(hatch none 0.5)
			(connect_pads
				(clearance 0)
			)
			(min_thickness 0.25)
			(keepout
				(tracks allowed)
				(vias not_allowed)
				(pads allowed)
				(copperpour not_allowed)
				(footprints allowed)
			)
			(placement
				(enabled no)
				(sheetname "")
			)
			(fill
				(thermal_gap 0.5)
				(thermal_bridge_width 0.5)
				(island_removal_mode 0)
			)
			(polygon
				(pts
					(xy 30.6832 -90.9828) (xy 31.2928 -90.9828) (xy 31.2928 -91.1352) (xy 30.6832 -91.1352)
				)
			)
		)
		(zone
			(layer "B.Cu")
			(hatch none 0.5)
			(connect_pads
				(clearance 0)
			)
			(min_thickness 0.25)
			(keepout
				(tracks not_allowed)
				(vias allowed)
				(pads allowed)
				(copperpour not_allowed)
				(footprints allowed)
			)
			(placement
				(enabled no)
				(sheetname "")
			)
			(fill
				(thermal_gap 0.5)
				(thermal_bridge_width 0.5)
				(island_removal_mode 0)
			)
			(polygon
				(pts
					(xy 30.6832 -90.9828) (xy 31.2928 -90.9828) (xy 31.2928 -91.1352) (xy 30.6832 -91.1352)
				)
			)
		)
	)
	(footprint ""
		(layer "B.Cu")
		(at 95.631 -86.741)
		(property "Reference" "R205"
			(at -0.254 -5.54863 0)
			(unlocked yes)
			(layer "B.SilkS")
			(effects
				(font
					(size 0.7874 0.5842)
					(thickness 0.1524)
				)
				(justify mirror)
			)
		)
		(property "Value" "VAL*"
			(at -0.02032 2.13233 0)
			(unlocked yes)
			(layer "B.Fab")
			(hide yes)
			(effects
				(font
					(size 0.7874 0.5842)
					(thickness 0.1524)
				)
				(justify mirror)
			)
		)
		(property "Tolerance" "TOL*"
			(at -0.044704 3.05435 0)
			(unlocked yes)
			(layer "Cmts.User")
			(hide yes)
			(effects
				(font
					(size 0.7874 0.5842)
					(thickness 0.1524)
				)
				(justify mirror)
			)
		)
		(property "User Part Number" "PARTNUM*"
			(at -0.02032 4.024884 0)
			(unlocked yes)
			(layer "Cmts.User")
			(hide yes)
			(effects
				(font
					(size 0.7874 0.5842)
					(thickness 0.1524)
				)
				(justify mirror)
			)
		)
		(property "Device Type" "RESISTOR-G155-133R0-01,33OHM,1%"
			(at -0.008382 1.210564 0)
			(unlocked yes)
			(layer "B.Fab")
			(hide yes)
			(effects
				(font
					(size 0.7874 0.5842)
					(thickness 0.1524)
				)
				(justify mirror)
			)
		)
		(duplicate_pad_numbers_are_jumpers no)
		(fp_line
			(start -1.143 -0.5588)
			(end 1.143 -0.5588)
			(stroke
				(width 0.1)
				(type default)
			)
			(layer "B.SilkS")
		)
		(fp_line
			(start -1.143 0.5588)
			(end -1.143 -0.5588)
			(stroke
				(width 0.1)
				(type default)
			)
			(layer "B.SilkS")
		)
		(fp_line
			(start 1.143 -0.5588)
			(end 1.143 0.5588)
			(stroke
				(width 0.1)
				(type default)
			)
			(layer "B.SilkS")
		)
		(fp_line
			(start 1.143 0.5588)
			(end -1.143 0.5588)
			(stroke
				(width 0.1)
				(type default)
			)
			(layer "B.SilkS")
		)
		(fp_rect
			(start -1.143 0.5588)
			(end 1.143 -0.5588)
			(stroke
				(width 0)
				(type default)
			)
			(fill no)
			(layer "B.CrtYd")
		)
		(fp_line
			(start -0.508 -0.3048)
			(end 0.508 -0.3048)
			(stroke
				(width 0.1)
				(type default)
			)
			(layer "B.Fab")
		)
		(fp_line
			(start -0.508 0.3048)
			(end -0.508 -0.3048)
			(stroke
				(width 0.1)
				(type default)
			)
			(layer "B.Fab")
		)
		(fp_line
			(start 0.508 -0.3048)
			(end 0.508 0.3048)
			(stroke
				(width 0.1)
				(type default)
			)
			(layer "B.Fab")
		)
		(fp_line
			(start 0.508 0.3048)
			(end -0.508 0.3048)
			(stroke
				(width 0.1)
				(type default)
			)
			(layer "B.Fab")
		)
		(pad "1" smd rect
			(at 0.5334 0 180)
			(size 0.7112 0.6096)
			(layers "B.Cu" "B.Mask" "B.Paste")
			(net "UNNAMED_127_MT25QL128ABA1ESES_3")
		)
		(pad "2" smd rect
			(at -0.5334 0 180)
			(size 0.7112 0.6096)
			(layers "B.Cu" "B.Mask" "B.Paste")
			(net "FLASH_DQ2")
		)
		(zone
			(layer "B.Cu")
			(hatch none 0.5)
			(connect_pads
				(clearance 0)
			)
			(min_thickness 0.25)
			(keepout
				(tracks allowed)
				(vias not_allowed)
				(pads allowed)
				(copperpour not_allowed)
				(footprints allowed)
			)
			(placement
				(enabled no)
				(sheetname "")
			)
			(fill
				(thermal_gap 0.5)
				(thermal_bridge_width 0.5)
				(island_removal_mode 0)
			)
			(polygon
				(pts
					(xy 95.5548 -86.4362) (xy 95.7072 -86.4362) (xy 95.7072 -87.0458) (xy 95.5548 -87.0458)
				)
			)
		)
	)
	(footprint ""
		(layer "B.Cu")
		(at 119.761 -23.241 180)
		(property "Reference" "R483"
			(at 0 -1.18237 0)
			(unlocked yes)
			(layer "B.SilkS")
			(effects
				(font
					(size 0.7874 0.5842)
					(thickness 0.1524)
				)
				(justify mirror)
			)
		)
		(property "Value" "VAL*"
			(at -0.02032 2.13233 180)
			(unlocked yes)
			(layer "B.Fab")
			(hide yes)
			(effects
				(font
					(size 0.7874 0.5842)
					(thickness 0.1524)
				)
				(justify mirror)
			)
		)
		(property "Tolerance" "TOL*"
			(at -0.044704 3.05435 180)
			(unlocked yes)
			(layer "Cmts.User")
			(hide yes)
			(effects
				(font
					(size 0.7874 0.5842)
					(thickness 0.1524)
				)
				(justify mirror)
			)
		)
		(property "User Part Number" "PARTNUM*"
			(at -0.02032 4.024884 180)
			(unlocked yes)
			(layer "Cmts.User")
			(hide yes)
			(effects
				(font
					(size 0.7874 0.5842)
					(thickness 0.1524)
				)
				(justify mirror)
			)
		)
		(property "Device Type" "RESISTOR-G155-11001-01,1KOHM,1%"
			(at -0.008382 1.210564 180)
			(unlocked yes)
			(layer "B.Fab")
			(hide yes)
			(effects
				(font
					(size 0.7874 0.5842)
					(thickness 0.1524)
				)
				(justify mirror)
			)
		)
		(duplicate_pad_numbers_are_jumpers no)
		(fp_line
			(start 1.143 0.5588)
			(end -1.143 0.5588)
			(stroke
				(width 0.1)
				(type default)
			)
			(layer "B.SilkS")
		)
		(fp_line
			(start 1.143 -0.5588)
			(end 1.143 0.5588)
			(stroke
				(width 0.1)
				(type default)
			)
			(layer "B.SilkS")
		)
		(fp_line
			(start -1.143 0.5588)
			(end -1.143 -0.5588)
			(stroke
				(width 0.1)
				(type default)
			)
			(layer "B.SilkS")
		)
		(fp_line
			(start -1.143 -0.5588)
			(end 1.143 -0.5588)
			(stroke
				(width 0.1)
				(type default)
			)
			(layer "B.SilkS")
		)
		(fp_poly
			(pts
				(xy 1.143 0.5588) (xy -1.143 0.5588) (xy -1.143 -0.5588) (xy 1.143 -0.5588)
			)
			(stroke
				(width 0)
				(type default)
			)
			(fill no)
			(layer "B.CrtYd")
		)
		(fp_line
			(start 0.508 0.3048)
			(end -0.508 0.3048)
			(stroke
				(width 0.1)
				(type default)
			)
			(layer "B.Fab")
		)
		(fp_line
			(start 0.508 -0.3048)
			(end 0.508 0.3048)
			(stroke
				(width 0.1)
				(type default)
			)
			(layer "B.Fab")
		)
		(fp_line
			(start -0.508 0.3048)
			(end -0.508 -0.3048)
			(stroke
				(width 0.1)
				(type default)
			)
			(layer "B.Fab")
		)
		(fp_line
			(start -0.508 -0.3048)
			(end 0.508 -0.3048)
			(stroke
				(width 0.1)
				(type default)
			)
			(layer "B.Fab")
		)
		(pad "1" smd rect
			(at 0.5334 0)
			(size 0.7112 0.6096)
			(layers "B.Cu" "B.Mask" "B.Paste")
			(net "SG")
		)
		(pad "2" smd rect
			(at -0.5334 0)
			(size 0.7112 0.6096)
			(layers "B.Cu" "B.Mask" "B.Paste")
			(net "MUX3_SEL")
		)
		(zone
			(layer "B.Cu")
			(hatch none 0.5)
			(connect_pads
				(clearance 0)
			)
			(min_thickness 0.25)
			(keepout
				(tracks allowed)
				(vias not_allowed)
				(pads allowed)
				(copperpour not_allowed)
				(footprints allowed)
			)
			(placement
				(enabled no)
				(sheetname "")
			)
			(fill
				(thermal_gap 0.5)
				(thermal_bridge_width 0.5)
				(island_removal_mode 0)
			)
			(polygon
				(pts
					(xy 119.6848 -23.5458) (xy 119.6848 -22.9362) (xy 119.8372 -22.9362) (xy 119.8372 -23.5458)
				)
			)
		)
		(zone
			(layer "B.Cu")
			(hatch none 0.5)
			(connect_pads
				(clearance 0)
			)
			(min_thickness 0.25)
			(keepout
				(tracks not_allowed)
				(vias allowed)
				(pads allowed)
				(copperpour not_allowed)
				(footprints allowed)
			)
			(placement
				(enabled no)
				(sheetname "")
			)
			(fill
				(thermal_gap 0.5)
				(thermal_bridge_width 0.5)
				(island_removal_mode 0)
			)
			(polygon
				(pts
					(xy 119.6848 -23.5458) (xy 119.6848 -22.9362) (xy 119.8372 -22.9362) (xy 119.8372 -23.5458)
				)
			)
		)
	)
	(footprint ""
		(layer "B.Cu")
		(at 116.205 -61.976 -90)
		(property "Reference" "R223"
			(at -3.429 -0.08763 270)
			(unlocked yes)
			(layer "B.SilkS")
			(effects
				(font
					(size 0.7874 0.5842)
					(thickness 0.1524)
				)
				(justify mirror)
			)
		)
		(property "Value" "VAL*"
			(at -0.02032 2.13233 270)
			(unlocked yes)
			(layer "B.Fab")
			(hide yes)
			(effects
				(font
					(size 0.7874 0.5842)
					(thickness 0.1524)
				)
				(justify mirror)
			)
		)
		(property "Device Type" "RESISTOR-G155-11001-01,1KOHM,1%"
			(at -0.008382 1.210564 270)
			(unlocked yes)
			(layer "B.Fab")
			(hide yes)
			(effects
				(font
					(size 0.7874 0.5842)
					(thickness 0.1524)
				)
				(justify mirror)
			)
		)
		(property "User Part Number" "PARTNUM*"
			(at -0.02032 4.024884 270)
			(unlocked yes)
			(layer "Cmts.User")
			(hide yes)
			(effects
				(font
					(size 0.7874 0.5842)
					(thickness 0.1524)
				)
				(justify mirror)
			)
		)
		(property "Tolerance" "TOL*"
			(at -0.044704 3.05435 270)
			(unlocked yes)
			(layer "Cmts.User")
			(hide yes)
			(effects
				(font
					(size 0.7874 0.5842)
					(thickness 0.1524)
				)
				(justify mirror)
			)
		)
		(duplicate_pad_numbers_are_jumpers no)
		(fp_line
			(start -1.143 0.5588)
			(end -1.143 -0.5588)
			(stroke
				(width 0.1)
				(type default)
			)
			(layer "B.SilkS")
		)
		(fp_line
			(start 1.143 0.5588)
			(end -1.143 0.5588)
			(stroke
				(width 0.1)
				(type default)
			)
			(layer "B.SilkS")
		)
		(fp_line
			(start -1.143 -0.5588)
			(end 1.143 -0.5588)
			(stroke
				(width 0.1)
				(type default)
			)
			(layer "B.SilkS")
		)
		(fp_line
			(start 1.143 -0.5588)
			(end 1.143 0.5588)
			(stroke
				(width 0.1)
				(type default)
			)
			(layer "B.SilkS")
		)
		(fp_rect
			(start 1.143 -0.5588)
			(end -1.143 0.5588)
			(stroke
				(width 0)
				(type default)
			)
			(fill no)
			(layer "B.CrtYd")
		)
		(fp_line
			(start -0.508 0.3048)
			(end -0.508 -0.3048)
			(stroke
				(width 0.1)
				(type default)
			)
			(layer "B.Fab")
		)
		(fp_line
			(start 0.508 0.3048)
			(end -0.508 0.3048)
			(stroke
				(width 0.1)
				(type default)
			)
			(layer "B.Fab")
		)
		(fp_line
			(start -0.508 -0.3048)
			(end 0.508 -0.3048)
			(stroke
				(width 0.1)
				(type default)
			)
			(layer "B.Fab")
		)
		(fp_line
			(start 0.508 -0.3048)
			(end 0.508 0.3048)
			(stroke
				(width 0.1)
				(type default)
			)
			(layer "B.Fab")
		)
		(pad "1" smd rect
			(at 0.5334 0 90)
			(size 0.7112 0.6096)
			(layers "B.Cu" "B.Mask" "B.Paste")
			(net "PUDC")
		)
		(pad "2" smd rect
			(at -0.5334 0 90)
			(size 0.7112 0.6096)
			(layers "B.Cu" "B.Mask" "B.Paste")
			(net "XP3R3V_FPGA")
		)
		(zone
			(layer "B.Cu")
			(hatch none 0.5)
			(connect_pads
				(clearance 0)
			)
			(min_thickness 0.25)
			(keepout
				(tracks allowed)
				(vias not_allowed)
				(pads allowed)
				(copperpour not_allowed)
				(footprints allowed)
			)
			(placement
				(enabled no)
				(sheetname "")
			)
			(fill
				(thermal_gap 0.5)
				(thermal_bridge_width 0.5)
				(island_removal_mode 0)
			)
			(polygon
				(pts
					(xy 116.5098 -61.8998) (xy 116.5098 -62.0522) (xy 115.9002 -62.0522) (xy 115.9002 -61.8998)
				)
			)
		)
	)
	(footprint ""
		(layer "B.Cu")
		(at 18.3134 -21.2852 90)
		(property "Reference" "R45"
			(at -0.0762 -1.08077 270)
			(unlocked yes)
			(layer "B.SilkS")
			(effects
				(font
					(size 0.7874 0.5842)
					(thickness 0.1524)
				)
				(justify mirror)
			)
		)
		(property "Value" "VAL*"
			(at -0.02032 2.13233 90)
			(unlocked yes)
			(layer "B.Fab")
			(hide yes)
			(effects
				(font
					(size 0.7874 0.5842)
					(thickness 0.1524)
				)
				(justify mirror)
			)
		)
		(property "Tolerance" "TOL*"
			(at -0.044704 3.05435 90)
			(unlocked yes)
			(layer "Cmts.User")
			(hide yes)
			(effects
				(font
					(size 0.7874 0.5842)
					(thickness 0.1524)
				)
				(justify mirror)
			)
		)
		(property "User Part Number" "PARTNUM*"
			(at -0.02032 4.024884 90)
			(unlocked yes)
			(layer "Cmts.User")
			(hide yes)
			(effects
				(font
					(size 0.7874 0.5842)
					(thickness 0.1524)
				)
				(justify mirror)
			)
		)
		(property "Device Type" "RESISTOR-G155-133R0-01,33OHM,1%"
			(at -0.008382 1.210564 90)
			(unlocked yes)
			(layer "B.Fab")
			(hide yes)
			(effects
				(font
					(size 0.7874 0.5842)
					(thickness 0.1524)
				)
				(justify mirror)
			)
		)
		(duplicate_pad_numbers_are_jumpers no)
		(fp_line
			(start 1.143 -0.5588)
			(end 1.143 0.5588)
			(stroke
				(width 0.1)
				(type default)
			)
			(layer "B.SilkS")
		)
		(fp_line
			(start -1.143 -0.5588)
			(end 1.143 -0.5588)
			(stroke
				(width 0.1)
				(type default)
			)
			(layer "B.SilkS")
		)
		(fp_line
			(start 1.143 0.5588)
			(end -1.143 0.5588)
			(stroke
				(width 0.1)
				(type default)
			)
			(layer "B.SilkS")
		)
		(fp_line
			(start -1.143 0.5588)
			(end -1.143 -0.5588)
			(stroke
				(width 0.1)
				(type default)
			)
			(layer "B.SilkS")
		)
		(fp_rect
			(start 1.143 0.5588)
			(end -1.143 -0.5588)
			(stroke
				(width 0)
				(type default)
			)
			(fill no)
			(layer "B.CrtYd")
		)
		(fp_line
			(start 0.508 -0.3048)
			(end 0.508 0.3048)
			(stroke
				(width 0.1)
				(type default)
			)
			(layer "B.Fab")
		)
		(fp_line
			(start -0.508 -0.3048)
			(end 0.508 -0.3048)
			(stroke
				(width 0.1)
				(type default)
			)
			(layer "B.Fab")
		)
		(fp_line
			(start 0.508 0.3048)
			(end -0.508 0.3048)
			(stroke
				(width 0.1)
				(type default)
			)
			(layer "B.Fab")
		)
		(fp_line
			(start -0.508 0.3048)
			(end -0.508 -0.3048)
			(stroke
				(width 0.1)
				(type default)
			)
			(layer "B.Fab")
		)
		(pad "1" smd rect
			(at 0.5334 0 270)
			(size 0.7112 0.6096)
			(layers "B.Cu" "B.Mask" "B.Paste")
			(net "EEPROM_SDA")
		)
		(pad "2" smd rect
			(at -0.5334 0 270)
			(size 0.7112 0.6096)
			(layers "B.Cu" "B.Mask" "B.Paste")
			(net "SEC_EEPROM_SDA")
		)
		(zone
			(layer "B.Cu")
			(hatch none 0.5)
			(connect_pads
				(clearance 0)
			)
			(min_thickness 0.25)
			(keepout
				(tracks allowed)
				(vias not_allowed)
				(pads allowed)
				(copperpour not_allowed)
				(footprints allowed)
			)
			(placement
				(enabled no)
				(sheetname "")
			)
			(fill
				(thermal_gap 0.5)
				(thermal_bridge_width 0.5)
				(island_removal_mode 0)
			)
			(polygon
				(pts
					(xy 18.6182 -21.3614) (xy 18.0086 -21.3614) (xy 18.0086 -21.209) (xy 18.6182 -21.209)
				)
			)
		)
	)
	(footprint ""
		(layer "B.Cu")
		(at 103.347012 -42.82313)
		(property "Reference" "R198"
			(at -41.625012 0.94488 0)
			(unlocked yes)
			(layer "B.SilkS")
			(effects
				(font
					(size 0.635 0.4064)
					(thickness 0.1524)
				)
				(justify mirror)
			)
		)
		(property "Value" "VAL*"
			(at 0 3.718306 0)
			(unlocked yes)
			(layer "B.Fab")
			(hide yes)
			(effects
				(font
					(size 0.7874 0.5842)
					(thickness 0.127)
				)
				(justify mirror)
			)
		)
		(property "Device Type" "RESISTOR-G155-11000-01,100OHM,A"
			(at 0 1.432306 0)
			(unlocked yes)
			(layer "B.Fab")
			(hide yes)
			(effects
				(font
					(size 0.7874 0.5842)
					(thickness 0.127)
				)
				(justify mirror)
			)
		)
		(property "User Part Number" "PARTNUM*"
			(at 0 2.575306 0)
			(unlocked yes)
			(layer "Cmts.User")
			(hide yes)
			(effects
				(font
					(size 0.7874 0.5842)
					(thickness 0.127)
				)
				(justify mirror)
			)
		)
		(property "Tolerance" "TOL*"
			(at 0 4.861306 0)
			(unlocked yes)
			(layer "Cmts.User")
			(hide yes)
			(effects
				(font
					(size 0.7874 0.5842)
					(thickness 0.127)
				)
				(justify mirror)
			)
		)
		(duplicate_pad_numbers_are_jumpers no)
		(fp_line
			(start -0.970026 -0.4699)
			(end -0.970026 0.4699)
			(stroke
				(width 0.1)
				(type default)
			)
			(layer "B.SilkS")
		)
		(fp_line
			(start -0.970026 0.4699)
			(end 0.970026 0.4699)
			(stroke
				(width 0.1)
				(type default)
			)
			(layer "B.SilkS")
		)
		(fp_line
			(start 0.970026 -0.4699)
			(end -0.970026 -0.4699)
			(stroke
				(width 0.1)
				(type default)
			)
			(layer "B.SilkS")
		)
		(fp_line
			(start 0.970026 0.4699)
			(end 0.970026 -0.4699)
			(stroke
				(width 0.1)
				(type default)
			)
			(layer "B.SilkS")
		)
		(fp_poly
			(pts
				(xy 0.970026 0.4699) (xy -0.970026 0.4699) (xy -0.970026 -0.4699) (xy 0.970026 -0.4699)
			)
			(stroke
				(width 0)
				(type default)
			)
			(fill no)
			(layer "B.CrtYd")
		)
		(fp_line
			(start -0.508 -0.3048)
			(end -0.508 0.3048)
			(stroke
				(width 0.1)
				(type default)
			)
			(layer "B.Fab")
		)
		(fp_line
			(start -0.508 0.3048)
			(end 0.508 0.3048)
			(stroke
				(width 0.1)
				(type default)
			)
			(layer "B.Fab")
		)
		(fp_line
			(start 0.508 -0.3048)
			(end -0.508 -0.3048)
			(stroke
				(width 0.1)
				(type default)
			)
			(layer "B.Fab")
		)
		(fp_line
			(start 0.508 0.3048)
			(end 0.508 -0.3048)
			(stroke
				(width 0.1)
				(type default)
			)
			(layer "B.Fab")
		)
		(pad "1" smd circle
			(at 0.500126 0 180)
			(size 0.635 0.635)
			(layers "B.Cu" "B.Mask" "B.Paste")
			(net "PCIE_REFCLKP")
		)
		(pad "2" smd circle
			(at -0.500126 0 180)
			(size 0.635 0.635)
			(layers "B.Cu" "B.Mask" "B.Paste")
			(net "PCIE_REFCLKN")
		)
	)
	(footprint ""
		(layer "B.Cu")
		(at 101.4476 -82.2706 180)
		(property "Reference" "R458"
			(at -0.0254 -1.66497 0)
			(unlocked yes)
			(layer "B.SilkS")
			(effects
				(font
					(size 0.7874 0.5842)
					(thickness 0.1524)
				)
				(justify mirror)
			)
		)
		(property "Value" "VAL*"
			(at -0.02032 2.13233 180)
			(unlocked yes)
			(layer "B.Fab")
			(hide yes)
			(effects
				(font
					(size 0.7874 0.5842)
					(thickness 0.1524)
				)
				(justify mirror)
			)
		)
		(property "Tolerance" "TOL*"
			(at -0.044704 3.05435 180)
			(unlocked yes)
			(layer "Cmts.User")
			(hide yes)
			(effects
				(font
					(size 0.7874 0.5842)
					(thickness 0.1524)
				)
				(justify mirror)
			)
		)
		(property "User Part Number" "PARTNUM*"
			(at -0.02032 4.024884 180)
			(unlocked yes)
			(layer "Cmts.User")
			(hide yes)
			(effects
				(font
					(size 0.7874 0.5842)
					(thickness 0.1524)
				)
				(justify mirror)
			)
		)
		(property "Device Type" "RESISTOR-G155-11001-01,1KOHM,1%"
			(at -0.008382 1.210564 180)
			(unlocked yes)
			(layer "B.Fab")
			(hide yes)
			(effects
				(font
					(size 0.7874 0.5842)
					(thickness 0.1524)
				)
				(justify mirror)
			)
		)
		(duplicate_pad_numbers_are_jumpers no)
		(fp_line
			(start 1.143 0.5588)
			(end -1.143 0.5588)
			(stroke
				(width 0.1)
				(type default)
			)
			(layer "B.SilkS")
		)
		(fp_line
			(start 1.143 -0.5588)
			(end 1.143 0.5588)
			(stroke
				(width 0.1)
				(type default)
			)
			(layer "B.SilkS")
		)
		(fp_line
			(start -1.143 0.5588)
			(end -1.143 -0.5588)
			(stroke
				(width 0.1)
				(type default)
			)
			(layer "B.SilkS")
		)
		(fp_line
			(start -1.143 -0.5588)
			(end 1.143 -0.5588)
			(stroke
				(width 0.1)
				(type default)
			)
			(layer "B.SilkS")
		)
		(fp_poly
			(pts
				(xy 1.143 0.5588) (xy -1.143 0.5588) (xy -1.143 -0.5588) (xy 1.143 -0.5588)
			)
			(stroke
				(width 0)
				(type default)
			)
			(fill no)
			(layer "B.CrtYd")
		)
		(fp_line
			(start 0.508 0.3048)
			(end -0.508 0.3048)
			(stroke
				(width 0.1)
				(type default)
			)
			(layer "B.Fab")
		)
		(fp_line
			(start 0.508 -0.3048)
			(end 0.508 0.3048)
			(stroke
				(width 0.1)
				(type default)
			)
			(layer "B.Fab")
		)
		(fp_line
			(start -0.508 0.3048)
			(end -0.508 -0.3048)
			(stroke
				(width 0.1)
				(type default)
			)
			(layer "B.Fab")
		)
		(fp_line
			(start -0.508 -0.3048)
			(end 0.508 -0.3048)
			(stroke
				(width 0.1)
				(type default)
			)
			(layer "B.Fab")
		)
		(pad "1" smd rect
			(at 0.5334 0)
			(size 0.7112 0.6096)
			(layers "B.Cu" "B.Mask" "B.Paste")
			(net "SG")
		)
		(pad "2" smd rect
			(at -0.5334 0)
			(size 0.7112 0.6096)
			(layers "B.Cu" "B.Mask" "B.Paste")
			(net "MUX2_SEL")
		)
		(zone
			(layer "B.Cu")
			(hatch none 0.5)
			(connect_pads
				(clearance 0)
			)
			(min_thickness 0.25)
			(keepout
				(tracks not_allowed)
				(vias allowed)
				(pads allowed)
				(copperpour not_allowed)
				(footprints allowed)
			)
			(placement
				(enabled no)
				(sheetname "")
			)
			(fill
				(thermal_gap 0.5)
				(thermal_bridge_width 0.5)
				(island_removal_mode 0)
			)
			(polygon
				(pts
					(xy 101.3714 -82.5754) (xy 101.3714 -81.9658) (xy 101.5238 -81.9658) (xy 101.5238 -82.5754)
				)
			)
		)
		(zone
			(layer "B.Cu")
			(hatch none 0.5)
			(connect_pads
				(clearance 0)
			)
			(min_thickness 0.25)
			(keepout
				(tracks allowed)
				(vias not_allowed)
				(pads allowed)
				(copperpour not_allowed)
				(footprints allowed)
			)
			(placement
				(enabled no)
				(sheetname "")
			)
			(fill
				(thermal_gap 0.5)
				(thermal_bridge_width 0.5)
				(island_removal_mode 0)
			)
			(polygon
				(pts
					(xy 101.3714 -82.5754) (xy 101.3714 -81.9658) (xy 101.5238 -81.9658) (xy 101.5238 -82.5754)
				)
			)
		)
	)
	(footprint ""
		(layer "B.Cu")
		(at 102.347014 -45.823124)
		(property "Reference" "C106"
			(at 0.014986 1.150874 0)
			(unlocked yes)
			(layer "B.SilkS")
			(effects
				(font
					(size 0.635 0.4064)
					(thickness 0.1524)
				)
				(justify mirror)
			)
		)
		(property "Value" "VAL*"
			(at 0 3.718306 0)
			(unlocked yes)
			(layer "B.Fab")
			(hide yes)
			(effects
				(font
					(size 0.7874 0.5842)
					(thickness 0.127)
				)
				(justify mirror)
			)
		)
		(property "Tolerance" "TOL*"
			(at 0 4.861306 0)
			(unlocked yes)
			(layer "Cmts.User")
			(hide yes)
			(effects
				(font
					(size 0.7874 0.5842)
					(thickness 0.127)
				)
				(justify mirror)
			)
		)
		(property "User Part Number" "PARTNUM*"
			(at 0 2.575306 0)
			(unlocked yes)
			(layer "Cmts.User")
			(hide yes)
			(effects
				(font
					(size 0.7874 0.5842)
					(thickness 0.127)
				)
				(justify mirror)
			)
		)
		(property "Device Type" "CAPACITOR-G105-0B104-CK,0.1UF,A"
			(at 0 1.432306 0)
			(unlocked yes)
			(layer "B.Fab")
			(hide yes)
			(effects
				(font
					(size 0.7874 0.5842)
					(thickness 0.127)
				)
				(justify mirror)
			)
		)
		(duplicate_pad_numbers_are_jumpers no)
		(fp_line
			(start -0.970026 -0.4699)
			(end -0.970026 0.4699)
			(stroke
				(width 0.1)
				(type default)
			)
			(layer "B.SilkS")
		)
		(fp_line
			(start -0.970026 0.4699)
			(end 0.970026 0.4699)
			(stroke
				(width 0.1)
				(type default)
			)
			(layer "B.SilkS")
		)
		(fp_line
			(start 0.970026 -0.4699)
			(end -0.970026 -0.4699)
			(stroke
				(width 0.1)
				(type default)
			)
			(layer "B.SilkS")
		)
		(fp_line
			(start 0.970026 0.4699)
			(end 0.970026 -0.4699)
			(stroke
				(width 0.1)
				(type default)
			)
			(layer "B.SilkS")
		)
		(fp_poly
			(pts
				(xy 0.970026 0.4699) (xy -0.970026 0.4699) (xy -0.970026 -0.4699) (xy 0.970026 -0.4699)
			)
			(stroke
				(width 0)
				(type default)
			)
			(fill no)
			(layer "B.CrtYd")
		)
		(fp_line
			(start -0.508 -0.3048)
			(end -0.508 0.3048)
			(stroke
				(width 0.1)
				(type default)
			)
			(layer "B.Fab")
		)
		(fp_line
			(start -0.508 0.3048)
			(end 0.508 0.3048)
			(stroke
				(width 0.1)
				(type default)
			)
			(layer "B.Fab")
		)
		(fp_line
			(start 0.508 -0.3048)
			(end -0.508 -0.3048)
			(stroke
				(width 0.1)
				(type default)
			)
			(layer "B.Fab")
		)
		(fp_line
			(start 0.508 0.3048)
			(end 0.508 -0.3048)
			(stroke
				(width 0.1)
				(type default)
			)
			(layer "B.Fab")
		)
		(pad "1" smd circle
			(at 0.500126 0 180)
			(size 0.635 0.635)
			(layers "B.Cu" "B.Mask" "B.Paste")
			(net "XP1R8V_FPGA_VCCAUX")
		)
		(pad "2" smd circle
			(at -0.500126 0 180)
			(size 0.635 0.635)
			(layers "B.Cu" "B.Mask" "B.Paste")
			(net "SG")
		)
	)
	(footprint ""
		(layer "B.Cu")
		(at 61.976 -56.896 -90)
		(property "Reference" "U10"
			(at 0.381 2.19837 270)
			(unlocked yes)
			(layer "B.SilkS")
			(effects
				(font
					(size 0.7874 0.5842)
					(thickness 0.1524)
				)
				(justify mirror)
			)
		)
		(property "Value" ""
			(at 0 0 90)
			(layer "B.Fab")
			(effects
				(font
					(size 1.27 1.27)
				)
				(justify mirror)
			)
		)
		(property "User Part Number" "PARTNUM*"
			(at -0.381 2.97307 270)
			(unlocked yes)
			(layer "Cmts.User")
			(hide yes)
			(effects
				(font
					(size 0.7874 0.5842)
					(thickness 0.1524)
				)
				(justify mirror)
			)
		)
		(property "Device Type" "CL5003148A-G220-10019-01"
			(at -0.4064 2.05867 270)
			(unlocked yes)
			(layer "B.Fab")
			(hide yes)
			(effects
				(font
					(size 0.7874 0.5842)
					(thickness 0.1524)
				)
				(justify mirror)
			)
		)
		(duplicate_pad_numbers_are_jumpers no)
		(fp_line
			(start -0.952754 1.32842)
			(end -0.952754 1.069086)
			(stroke
				(width 0.1)
				(type default)
			)
			(layer "B.SilkS")
		)
		(fp_line
			(start 0.952754 1.32842)
			(end -0.952754 1.32842)
			(stroke
				(width 0.1)
				(type default)
			)
			(layer "B.SilkS")
		)
		(fp_line
			(start -1.9304 1.069086)
			(end -1.9304 -1.069086)
			(stroke
				(width 0.1)
				(type default)
			)
			(layer "B.SilkS")
		)
		(fp_line
			(start -0.952754 1.069086)
			(end -1.9304 1.069086)
			(stroke
				(width 0.1)
				(type default)
			)
			(layer "B.SilkS")
		)
		(fp_line
			(start 0.952754 1.069086)
			(end 0.952754 1.32842)
			(stroke
				(width 0.1)
				(type default)
			)
			(layer "B.SilkS")
		)
		(fp_line
			(start 1.9304 1.069086)
			(end 0.952754 1.069086)
			(stroke
				(width 0.1)
				(type default)
			)
			(layer "B.SilkS")
		)
		(fp_line
			(start -1.9304 -1.069086)
			(end -0.952754 -1.069086)
			(stroke
				(width 0.1)
				(type default)
			)
			(layer "B.SilkS")
		)
		(fp_line
			(start -0.952754 -1.069086)
			(end -0.952754 -1.32842)
			(stroke
				(width 0.1)
				(type default)
			)
			(layer "B.SilkS")
		)
		(fp_line
			(start 0.952754 -1.069086)
			(end 1.9304 -1.069086)
			(stroke
				(width 0.1)
				(type default)
			)
			(layer "B.SilkS")
		)
		(fp_line
			(start 1.9304 -1.069086)
			(end 1.9304 1.069086)
			(stroke
				(width 0.1)
				(type default)
			)
			(layer "B.SilkS")
		)
		(fp_line
			(start -0.952754 -1.32842)
			(end 0.952754 -1.32842)
			(stroke
				(width 0.1)
				(type default)
			)
			(layer "B.SilkS")
		)
		(fp_line
			(start 0.952754 -1.32842)
			(end 0.952754 -1.069086)
			(stroke
				(width 0.1)
				(type default)
			)
			(layer "B.SilkS")
		)
		(fp_poly
			(pts
				(arc
					(start 2.577592 -1.13538)
					(mid 2.577592 -0.37338)
					(end 2.577592 -1.13538)
				)
			)
			(stroke
				(width 0)
				(type default)
			)
			(fill yes)
			(layer "B.SilkS")
		)
		(fp_rect
			(start -2.1844 1.58242)
			(end 2.1844 -1.58242)
			(stroke
				(width 0)
				(type default)
			)
			(fill no)
			(layer "B.CrtYd")
		)
		(fp_line
			(start -0.698754 1.07442)
			(end -0.698754 0.774954)
			(stroke
				(width 0.1)
				(type default)
			)
			(layer "B.Fab")
		)
		(fp_line
			(start 0.450088 1.07442)
			(end 0.450088 -1.07442)
			(stroke
				(width 0.1)
				(type default)
			)
			(layer "B.Fab")
		)
		(fp_line
			(start 0.698754 1.07442)
			(end -0.698754 1.07442)
			(stroke
				(width 0.1)
				(type default)
			)
			(layer "B.Fab")
		)
		(fp_line
			(start 0.698754 0.774954)
			(end 0.698754 1.07442)
			(stroke
				(width 0.1)
				(type default)
			)
			(layer "B.Fab")
		)
		(fp_line
			(start 0.698754 0.124968)
			(end 0.698754 0.525018)
			(stroke
				(width 0.1)
				(type default)
			)
			(layer "B.Fab")
		)
		(fp_line
			(start -0.698754 -0.525018)
			(end -0.698754 0.525018)
			(stroke
				(width 0.1)
				(type default)
			)
			(layer "B.Fab")
		)
		(fp_line
			(start 0.698754 -0.525018)
			(end 0.698754 -0.124968)
			(stroke
				(width 0.1)
				(type default)
			)
			(layer "B.Fab")
		)
		(fp_line
			(start 0.698754 -0.774954)
			(end 0.698754 -1.07442)
			(stroke
				(width 0.1)
				(type default)
			)
			(layer "B.Fab")
		)
		(fp_line
			(start -0.698754 -1.07442)
			(end -0.698754 -0.774954)
			(stroke
				(width 0.1)
				(type default)
			)
			(layer "B.Fab")
		)
		(fp_line
			(start -0.450088 -1.07442)
			(end -0.450088 1.07442)
			(stroke
				(width 0.1)
				(type default)
			)
			(layer "B.Fab")
		)
		(fp_line
			(start 0.698754 -1.07442)
			(end -0.698754 -1.07442)
			(stroke
				(width 0.1)
				(type default)
			)
			(layer "B.Fab")
		)
		(fp_rect
			(start -1.198626 0.774954)
			(end -0.6985 0.525018)
			(stroke
				(width 0)
				(type default)
			)
			(fill no)
			(layer "B.Fab")
		)
		(fp_rect
			(start 0.6985 0.774954)
			(end 1.198626 0.525018)
			(stroke
				(width 0)
				(type default)
			)
			(fill no)
			(layer "B.Fab")
		)
		(fp_rect
			(start 0.6985 0.124968)
			(end 1.198626 -0.124968)
			(stroke
				(width 0)
				(type default)
			)
			(fill no)
			(layer "B.Fab")
		)
		(fp_rect
			(start -1.198626 -0.525018)
			(end -0.6985 -0.774954)
			(stroke
				(width 0)
				(type default)
			)
			(fill no)
			(layer "B.Fab")
		)
		(fp_rect
			(start 0.6985 -0.525018)
			(end 1.198626 -0.774954)
			(stroke
				(width 0)
				(type default)
			)
			(fill no)
			(layer "B.Fab")
		)
		(fp_poly
			(pts
				(arc
					(start 2.577592 -1.13538)
					(mid 2.577592 -0.37338)
					(end 2.577592 -1.13538)
				)
			)
			(stroke
				(width 0)
				(type default)
			)
			(fill yes)
			(layer "B.Fab")
		)
		(fp_text user "4"
			(at -1.41605 1.778 0)
			(unlocked yes)
			(layer "B.SilkS")
			(effects
				(font
					(size 0.635 0.4064)
					(thickness 0.1524)
				)
				(justify mirror)
			)
		)
		(fp_text user "3"
			(at 2.64795 1.524 0)
			(unlocked yes)
			(layer "B.SilkS")
			(effects
				(font
					(size 0.635 0.4064)
					(thickness 0.1524)
				)
				(justify mirror)
			)
		)
		(fp_text user "5"
			(at -1.54305 -1.524 0)
			(unlocked yes)
			(layer "B.SilkS")
			(effects
				(font
					(size 0.635 0.4064)
					(thickness 0.1524)
				)
				(justify mirror)
			)
		)
		(fp_text user "3"
			(at 2.05867 0.889 0)
			(unlocked yes)
			(layer "B.Fab")
			(effects
				(font
					(size 0.7874 0.5842)
					(thickness 0.1524)
				)
				(justify mirror)
			)
		)
		(fp_text user "4"
			(at -1.781302 0.36703 0)
			(unlocked yes)
			(layer "B.Fab")
			(effects
				(font
					(size 0.7874 0.5842)
					(thickness 0.1524)
				)
				(justify mirror)
			)
		)
		(fp_text user "5"
			(at -1.75133 -1.007618 0)
			(unlocked yes)
			(layer "B.Fab")
			(effects
				(font
					(size 0.7874 0.5842)
					(thickness 0.1524)
				)
				(justify mirror)
			)
		)
		(pad "1" smd rect
			(at 1.1938 -0.649986)
			(size 0.3302 0.9652)
			(layers "B.Cu" "B.Mask" "B.Paste")
			(net "FPGA_OUT_MACUSBPOWER_EN")
		)
		(pad "2" smd rect
			(at 1.1938 0)
			(size 0.3302 0.9652)
			(layers "B.Cu" "B.Mask" "B.Paste")
			(net "XP5R0V_USB_CONN_DET")
		)
		(pad "3" smd rect
			(at 1.1938 0.649986)
			(size 0.3302 0.9652)
			(layers "B.Cu" "B.Mask" "B.Paste")
			(net "SG")
		)
		(pad "4" smd rect
			(at -1.1938 0.649986)
			(size 0.3302 0.9652)
			(layers "B.Cu" "B.Mask" "B.Paste")
			(net "USB_PWR_EN")
		)
		(pad "5" smd rect
			(at -1.1938 -0.649986)
			(size 0.3302 0.9652)
			(layers "B.Cu" "B.Mask" "B.Paste")
			(net "XP3R3V_FPGA")
		)
		(zone
			(layer "B.Cu")
			(hatch none 0.5)
			(connect_pads
				(clearance 0)
			)
			(min_thickness 0.25)
			(keepout
				(tracks allowed)
				(vias not_allowed)
				(pads allowed)
				(copperpour not_allowed)
				(footprints allowed)
			)
			(placement
				(enabled no)
				(sheetname "")
			)
			(fill
				(thermal_gap 0.5)
				(thermal_bridge_width 0.5)
				(island_removal_mode 0)
			)
			(polygon
				(pts
					(xy 60.9727 -57.531) (xy 60.9727 -56.261) (xy 62.9793 -56.261) (xy 62.9793 -57.531)
				)
			)
		)
	)
	(footprint ""
		(layer "B.Cu")
		(at 25.273 -91.059 90)
		(property "Reference" "R130"
			(at 2.286 -5.11937 270)
			(unlocked yes)
			(layer "B.SilkS")
			(effects
				(font
					(size 0.7874 0.5842)
					(thickness 0.1524)
				)
				(justify mirror)
			)
		)
		(property "Value" "VAL*"
			(at -0.02032 2.13233 90)
			(unlocked yes)
			(layer "B.Fab")
			(hide yes)
			(effects
				(font
					(size 0.7874 0.5842)
					(thickness 0.1524)
				)
				(justify mirror)
			)
		)
		(property "Tolerance" "TOL*"
			(at -0.044704 3.05435 90)
			(unlocked yes)
			(layer "Cmts.User")
			(hide yes)
			(effects
				(font
					(size 0.7874 0.5842)
					(thickness 0.1524)
				)
				(justify mirror)
			)
		)
		(property "User Part Number" "PARTNUM*"
			(at -0.02032 4.024884 90)
			(unlocked yes)
			(layer "Cmts.User")
			(hide yes)
			(effects
				(font
					(size 0.7874 0.5842)
					(thickness 0.1524)
				)
				(justify mirror)
			)
		)
		(property "Device Type" "RESISTOR-G155-11002-01,10KOHM,A"
			(at -0.008382 1.210564 90)
			(unlocked yes)
			(layer "B.Fab")
			(hide yes)
			(effects
				(font
					(size 0.7874 0.5842)
					(thickness 0.1524)
				)
				(justify mirror)
			)
		)
		(duplicate_pad_numbers_are_jumpers no)
		(fp_line
			(start 1.143 -0.5588)
			(end 1.143 0.5588)
			(stroke
				(width 0.1)
				(type default)
			)
			(layer "B.SilkS")
		)
		(fp_line
			(start -1.143 -0.5588)
			(end 1.143 -0.5588)
			(stroke
				(width 0.1)
				(type default)
			)
			(layer "B.SilkS")
		)
		(fp_line
			(start 1.143 0.5588)
			(end -1.143 0.5588)
			(stroke
				(width 0.1)
				(type default)
			)
			(layer "B.SilkS")
		)
		(fp_line
			(start -1.143 0.5588)
			(end -1.143 -0.5588)
			(stroke
				(width 0.1)
				(type default)
			)
			(layer "B.SilkS")
		)
		(fp_poly
			(pts
				(xy 1.143 0.5588) (xy -1.143 0.5588) (xy -1.143 -0.5588) (xy 1.143 -0.5588)
			)
			(stroke
				(width 0)
				(type default)
			)
			(fill no)
			(layer "B.CrtYd")
		)
		(fp_line
			(start 0.508 -0.3048)
			(end 0.508 0.3048)
			(stroke
				(width 0.1)
				(type default)
			)
			(layer "B.Fab")
		)
		(fp_line
			(start -0.508 -0.3048)
			(end 0.508 -0.3048)
			(stroke
				(width 0.1)
				(type default)
			)
			(layer "B.Fab")
		)
		(fp_line
			(start 0.508 0.3048)
			(end -0.508 0.3048)
			(stroke
				(width 0.1)
				(type default)
			)
			(layer "B.Fab")
		)
		(fp_line
			(start -0.508 0.3048)
			(end -0.508 -0.3048)
			(stroke
				(width 0.1)
				(type default)
			)
			(layer "B.Fab")
		)
		(pad "1" smd rect
			(at 0.5334 0 270)
			(size 0.7112 0.6096)
			(layers "B.Cu" "B.Mask" "B.Paste")
			(net "FT_USB_DETECT")
		)
		(pad "2" smd rect
			(at -0.5334 0 270)
			(size 0.7112 0.6096)
			(layers "B.Cu" "B.Mask" "B.Paste")
			(net "SG")
		)
		(zone
			(layer "B.Cu")
			(hatch none 0.5)
			(connect_pads
				(clearance 0)
			)
			(min_thickness 0.25)
			(keepout
				(tracks not_allowed)
				(vias allowed)
				(pads allowed)
				(copperpour not_allowed)
				(footprints allowed)
			)
			(placement
				(enabled no)
				(sheetname "")
			)
			(fill
				(thermal_gap 0.5)
				(thermal_bridge_width 0.5)
				(island_removal_mode 0)
			)
			(polygon
				(pts
					(xy 25.5778 -91.1352) (xy 24.9682 -91.1352) (xy 24.9682 -90.9828) (xy 25.5778 -90.9828)
				)
			)
		)
		(zone
			(layer "B.Cu")
			(hatch none 0.5)
			(connect_pads
				(clearance 0)
			)
			(min_thickness 0.25)
			(keepout
				(tracks allowed)
				(vias not_allowed)
				(pads allowed)
				(copperpour not_allowed)
				(footprints allowed)
			)
			(placement
				(enabled no)
				(sheetname "")
			)
			(fill
				(thermal_gap 0.5)
				(thermal_bridge_width 0.5)
				(island_removal_mode 0)
			)
			(polygon
				(pts
					(xy 25.5778 -91.1352) (xy 24.9682 -91.1352) (xy 24.9682 -90.9828) (xy 25.5778 -90.9828)
				)
			)
		)
	)
	(footprint ""
		(layer "B.Cu")
		(at 60.784994 -15.367 -90)
		(property "Reference" "C23"
			(at 2.3368 -0.059436 270)
			(unlocked yes)
			(layer "B.SilkS")
			(effects
				(font
					(size 0.7874 0.5842)
					(thickness 0.1524)
				)
				(justify mirror)
			)
		)
		(property "Value" "VAL*"
			(at -0.0762 2.067306 270)
			(unlocked yes)
			(layer "B.Fab")
			(hide yes)
			(effects
				(font
					(size 0.7874 0.5842)
					(thickness 0.1524)
				)
				(justify mirror)
			)
		)
		(property "Tolerance" "TOL*"
			(at -0.0762 3.032506 270)
			(unlocked yes)
			(layer "Cmts.User")
			(hide yes)
			(effects
				(font
					(size 0.7874 0.5842)
					(thickness 0.1524)
				)
				(justify mirror)
			)
		)
		(property "User Part Number" "PARTNUM*"
			(at -0.1016 4.023106 270)
			(unlocked yes)
			(layer "Cmts.User")
			(hide yes)
			(effects
				(font
					(size 0.7874 0.5842)
					(thickness 0.1524)
				)
				(justify mirror)
			)
		)
		(property "Device Type" "CAPACITOR-G105-0B104-CK,0.1UF,A"
			(at -0.0508 1.127506 270)
			(unlocked yes)
			(layer "B.Fab")
			(hide yes)
			(effects
				(font
					(size 0.7874 0.5842)
					(thickness 0.1524)
				)
				(justify mirror)
			)
		)
		(duplicate_pad_numbers_are_jumpers no)
		(fp_line
			(start -1.143 0.5588)
			(end -1.143 -0.5588)
			(stroke
				(width 0.1)
				(type default)
			)
			(layer "B.SilkS")
		)
		(fp_line
			(start 1.143 0.5588)
			(end -1.143 0.5588)
			(stroke
				(width 0.1)
				(type default)
			)
			(layer "B.SilkS")
		)
		(fp_line
			(start -1.143 -0.5588)
			(end 1.143 -0.5588)
			(stroke
				(width 0.1)
				(type default)
			)
			(layer "B.SilkS")
		)
		(fp_line
			(start 1.143 -0.5588)
			(end 1.143 0.5588)
			(stroke
				(width 0.1)
				(type default)
			)
			(layer "B.SilkS")
		)
		(fp_rect
			(start 1.143 0.5588)
			(end -1.143 -0.5588)
			(stroke
				(width 0)
				(type default)
			)
			(fill no)
			(layer "B.CrtYd")
		)
		(fp_line
			(start -0.508 0.3048)
			(end -0.508 -0.3048)
			(stroke
				(width 0.1)
				(type default)
			)
			(layer "B.Fab")
		)
		(fp_line
			(start 0.508 0.3048)
			(end -0.508 0.3048)
			(stroke
				(width 0.1)
				(type default)
			)
			(layer "B.Fab")
		)
		(fp_line
			(start -0.508 -0.3048)
			(end 0.508 -0.3048)
			(stroke
				(width 0.1)
				(type default)
			)
			(layer "B.Fab")
		)
		(fp_line
			(start 0.508 -0.3048)
			(end 0.508 0.3048)
			(stroke
				(width 0.1)
				(type default)
			)
			(layer "B.Fab")
		)
		(pad "1" smd rect
			(at 0.5334 0 90)
			(size 0.7112 0.6096)
			(layers "B.Cu" "B.Mask" "B.Paste")
			(net "C_PCIEREFCLKN")
		)
		(pad "2" smd rect
			(at -0.5334 0 90)
			(size 0.7112 0.6096)
			(layers "B.Cu" "B.Mask" "B.Paste")
			(net "PCIE_REFCLKN")
		)
		(zone
			(layer "B.Cu")
			(hatch none 0.5)
			(connect_pads
				(clearance 0)
			)
			(min_thickness 0.25)
			(keepout
				(tracks allowed)
				(vias not_allowed)
				(pads allowed)
				(copperpour not_allowed)
				(footprints allowed)
			)
			(placement
				(enabled no)
				(sheetname "")
			)
			(fill
				(thermal_gap 0.5)
				(thermal_bridge_width 0.5)
				(island_removal_mode 0)
			)
			(polygon
				(pts
					(xy 60.480194 -15.2908) (xy 61.089794 -15.2908) (xy 61.089794 -15.4432) (xy 60.480194 -15.4432)
				)
			)
		)
	)
	(footprint ""
		(layer "B.Cu")
		(at 72.263 -55.753 90)
		(property "Reference" "FU3"
			(at -2.413 0.08763 270)
			(unlocked yes)
			(layer "B.SilkS")
			(effects
				(font
					(size 0.7874 0.5842)
					(thickness 0.1524)
				)
				(justify mirror)
			)
		)
		(property "Value" "VAL*"
			(at 0.0254 2.524506 90)
			(unlocked yes)
			(layer "B.Fab")
			(hide yes)
			(effects
				(font
					(size 0.7874 0.5842)
					(thickness 0.1524)
				)
				(justify mirror)
			)
		)
		(property "Tolerance" "TOL*"
			(at 0.0254 3.464306 90)
			(unlocked yes)
			(layer "Cmts.User")
			(hide yes)
			(effects
				(font
					(size 0.7874 0.5842)
					(thickness 0.1524)
				)
				(justify mirror)
			)
		)
		(property "User Part Number" "PARTNUM*"
			(at 0.0254 4.505706 90)
			(unlocked yes)
			(layer "Cmts.User")
			(hide yes)
			(effects
				(font
					(size 0.7874 0.5842)
					(thickness 0.1524)
				)
				(justify mirror)
			)
		)
		(property "Device Type" "FUSE-G280-10049-01,1A"
			(at 0 1.610106 90)
			(unlocked yes)
			(layer "B.Fab")
			(hide yes)
			(effects
				(font
					(size 0.7874 0.5842)
					(thickness 0.1524)
				)
				(justify mirror)
			)
		)
		(duplicate_pad_numbers_are_jumpers no)
		(fp_line
			(start 1.3208 -0.7112)
			(end -1.3208 -0.7112)
			(stroke
				(width 0.1)
				(type default)
			)
			(layer "B.SilkS")
		)
		(fp_line
			(start -1.3208 -0.7112)
			(end -1.3208 0.7112)
			(stroke
				(width 0.1)
				(type default)
			)
			(layer "B.SilkS")
		)
		(fp_line
			(start 1.3208 0.7112)
			(end 1.3208 -0.7112)
			(stroke
				(width 0.1)
				(type default)
			)
			(layer "B.SilkS")
		)
		(fp_line
			(start -1.3208 0.7112)
			(end 1.3208 0.7112)
			(stroke
				(width 0.1)
				(type default)
			)
			(layer "B.SilkS")
		)
		(fp_rect
			(start 1.3208 0.7112)
			(end -1.3208 -0.7112)
			(stroke
				(width 0)
				(type default)
			)
			(fill no)
			(layer "B.CrtYd")
		)
		(fp_line
			(start 0.8128 -0.4572)
			(end -0.8128 -0.4572)
			(stroke
				(width 0.1)
				(type default)
			)
			(layer "B.Fab")
		)
		(fp_line
			(start -0.8128 -0.4572)
			(end -0.8128 0.4572)
			(stroke
				(width 0.1)
				(type default)
			)
			(layer "B.Fab")
		)
		(fp_line
			(start 0.8128 0.4572)
			(end 0.8128 -0.4572)
			(stroke
				(width 0.1)
				(type default)
			)
			(layer "B.Fab")
		)
		(fp_line
			(start -0.8128 0.4572)
			(end 0.8128 0.4572)
			(stroke
				(width 0.1)
				(type default)
			)
			(layer "B.Fab")
		)
		(pad "1" smd rect
			(at 0.6858 0 270)
			(size 0.762 0.8636)
			(layers "B.Cu" "B.Mask" "B.Paste")
			(net "UNNAMED_527_FUSE_I244_1")
		)
		(pad "2" smd rect
			(at -0.6858 0 270)
			(size 0.762 0.8636)
			(layers "B.Cu" "B.Mask" "B.Paste")
			(net "XP5R0V_MAC_USB")
		)
		(zone
			(layer "B.Cu")
			(hatch none 0.5)
			(connect_pads
				(clearance 0)
			)
			(min_thickness 0.25)
			(keepout
				(tracks not_allowed)
				(vias allowed)
				(pads allowed)
				(copperpour not_allowed)
				(footprints allowed)
			)
			(placement
				(enabled no)
				(sheetname "")
			)
			(fill
				(thermal_gap 0.5)
				(thermal_bridge_width 0.5)
				(island_removal_mode 0)
			)
			(polygon
				(pts
					(xy 72.7202 -55.9054) (xy 71.8058 -55.9054) (xy 71.8058 -55.6006) (xy 72.7202 -55.6006)
				)
			)
		)
		(zone
			(layer "B.Cu")
			(hatch none 0.5)
			(connect_pads
				(clearance 0)
			)
			(min_thickness 0.25)
			(keepout
				(tracks allowed)
				(vias not_allowed)
				(pads allowed)
				(copperpour not_allowed)
				(footprints allowed)
			)
			(placement
				(enabled no)
				(sheetname "")
			)
			(fill
				(thermal_gap 0.5)
				(thermal_bridge_width 0.5)
				(island_removal_mode 0)
			)
			(polygon
				(pts
					(xy 72.7202 -55.9054) (xy 71.8058 -55.9054) (xy 71.8058 -55.6006) (xy 72.7202 -55.6006)
				)
			)
		)
	)
	(footprint ""
		(layer "B.Cu")
		(at 98.991166 -32.857694)
		(property "Reference" "C116"
			(at 2.989834 0.258064 0)
			(unlocked yes)
			(layer "B.SilkS")
			(effects
				(font
					(size 0.7874 0.5842)
					(thickness 0.1524)
				)
				(justify mirror)
			)
		)
		(property "Value" "VAL*"
			(at -0.0762 2.067306 0)
			(unlocked yes)
			(layer "B.Fab")
			(hide yes)
			(effects
				(font
					(size 0.7874 0.5842)
					(thickness 0.1524)
				)
				(justify mirror)
			)
		)
		(property "Tolerance" "TOL*"
			(at -0.0762 3.032506 0)
			(unlocked yes)
			(layer "Cmts.User")
			(hide yes)
			(effects
				(font
					(size 0.7874 0.5842)
					(thickness 0.1524)
				)
				(justify mirror)
			)
		)
		(property "User Part Number" "PARTNUM*"
			(at -0.1016 4.023106 0)
			(unlocked yes)
			(layer "Cmts.User")
			(hide yes)
			(effects
				(font
					(size 0.7874 0.5842)
					(thickness 0.1524)
				)
				(justify mirror)
			)
		)
		(property "Device Type" "CAPACITOR-G105-0B104-CK,0.1UF,A"
			(at -0.0508 1.127506 0)
			(unlocked yes)
			(layer "B.Fab")
			(hide yes)
			(effects
				(font
					(size 0.7874 0.5842)
					(thickness 0.1524)
				)
				(justify mirror)
			)
		)
		(duplicate_pad_numbers_are_jumpers no)
		(fp_line
			(start -1.143 -0.5588)
			(end 1.143 -0.5588)
			(stroke
				(width 0.1)
				(type default)
			)
			(layer "B.SilkS")
		)
		(fp_line
			(start -1.143 0.5588)
			(end -1.143 -0.5588)
			(stroke
				(width 0.1)
				(type default)
			)
			(layer "B.SilkS")
		)
		(fp_line
			(start 1.143 -0.5588)
			(end 1.143 0.5588)
			(stroke
				(width 0.1)
				(type default)
			)
			(layer "B.SilkS")
		)
		(fp_line
			(start 1.143 0.5588)
			(end -1.143 0.5588)
			(stroke
				(width 0.1)
				(type default)
			)
			(layer "B.SilkS")
		)
		(fp_poly
			(pts
				(xy 1.143 0.5588) (xy -1.143 0.5588) (xy -1.143 -0.5588) (xy 1.143 -0.5588)
			)
			(stroke
				(width 0)
				(type default)
			)
			(fill no)
			(layer "B.CrtYd")
		)
		(fp_line
			(start -0.508 -0.3048)
			(end 0.508 -0.3048)
			(stroke
				(width 0.1)
				(type default)
			)
			(layer "B.Fab")
		)
		(fp_line
			(start -0.508 0.3048)
			(end -0.508 -0.3048)
			(stroke
				(width 0.1)
				(type default)
			)
			(layer "B.Fab")
		)
		(fp_line
			(start 0.508 -0.3048)
			(end 0.508 0.3048)
			(stroke
				(width 0.1)
				(type default)
			)
			(layer "B.Fab")
		)
		(fp_line
			(start 0.508 0.3048)
			(end -0.508 0.3048)
			(stroke
				(width 0.1)
				(type default)
			)
			(layer "B.Fab")
		)
		(pad "1" smd rect
			(at 0.5334 0 180)
			(size 0.7112 0.6096)
			(layers "B.Cu" "B.Mask" "B.Paste")
			(net "XP2R5V_FPGA")
		)
		(pad "2" smd rect
			(at -0.5334 0 180)
			(size 0.7112 0.6096)
			(layers "B.Cu" "B.Mask" "B.Paste")
			(net "SG")
		)
		(zone
			(layer "B.Cu")
			(hatch none 0.5)
			(connect_pads
				(clearance 0)
			)
			(min_thickness 0.25)
			(keepout
				(tracks allowed)
				(vias not_allowed)
				(pads allowed)
				(copperpour not_allowed)
				(footprints allowed)
			)
			(placement
				(enabled no)
				(sheetname "")
			)
			(fill
				(thermal_gap 0.5)
				(thermal_bridge_width 0.5)
				(island_removal_mode 0)
			)
			(polygon
				(pts
					(xy 99.067366 -32.552894) (xy 99.067366 -33.162494) (xy 98.914966 -33.162494) (xy 98.914966 -32.552894)
				)
			)
		)
		(zone
			(layer "B.Cu")
			(hatch none 0.5)
			(connect_pads
				(clearance 0)
			)
			(min_thickness 0.25)
			(keepout
				(tracks not_allowed)
				(vias allowed)
				(pads allowed)
				(copperpour not_allowed)
				(footprints allowed)
			)
			(placement
				(enabled no)
				(sheetname "")
			)
			(fill
				(thermal_gap 0.5)
				(thermal_bridge_width 0.5)
				(island_removal_mode 0)
			)
			(polygon
				(pts
					(xy 99.067366 -32.552894) (xy 99.067366 -33.162494) (xy 98.914966 -33.162494) (xy 98.914966 -32.552894)
				)
			)
		)
	)
	(footprint ""
		(layer "B.Cu")
		(at 114.347244 -36.823142 180)
		(property "Reference" "R278"
			(at -0.079756 0.991108 0)
			(unlocked yes)
			(layer "B.SilkS")
			(effects
				(font
					(size 0.635 0.4064)
					(thickness 0.1524)
				)
				(justify mirror)
			)
		)
		(property "Value" "VAL*"
			(at 0 3.718306 180)
			(unlocked yes)
			(layer "B.Fab")
			(hide yes)
			(effects
				(font
					(size 0.7874 0.5842)
					(thickness 0.127)
				)
				(justify mirror)
			)
		)
		(property "Tolerance" "TOL*"
			(at 0 4.861306 180)
			(unlocked yes)
			(layer "Cmts.User")
			(hide yes)
			(effects
				(font
					(size 0.7874 0.5842)
					(thickness 0.127)
				)
				(justify mirror)
			)
		)
		(property "User Part Number" "PARTNUM*"
			(at 0 2.575306 180)
			(unlocked yes)
			(layer "Cmts.User")
			(hide yes)
			(effects
				(font
					(size 0.7874 0.5842)
					(thickness 0.127)
				)
				(justify mirror)
			)
		)
		(property "Device Type" "RESISTOR-G155-11000-01,100OHM,A"
			(at 0 1.432306 180)
			(unlocked yes)
			(layer "B.Fab")
			(hide yes)
			(effects
				(font
					(size 0.7874 0.5842)
					(thickness 0.127)
				)
				(justify mirror)
			)
		)
		(duplicate_pad_numbers_are_jumpers no)
		(fp_line
			(start 0.970026 0.4699)
			(end 0.970026 -0.4699)
			(stroke
				(width 0.1)
				(type default)
			)
			(layer "B.SilkS")
		)
		(fp_line
			(start 0.970026 -0.4699)
			(end -0.970026 -0.4699)
			(stroke
				(width 0.1)
				(type default)
			)
			(layer "B.SilkS")
		)
		(fp_line
			(start -0.970026 0.4699)
			(end 0.970026 0.4699)
			(stroke
				(width 0.1)
				(type default)
			)
			(layer "B.SilkS")
		)
		(fp_line
			(start -0.970026 -0.4699)
			(end -0.970026 0.4699)
			(stroke
				(width 0.1)
				(type default)
			)
			(layer "B.SilkS")
		)
		(fp_poly
			(pts
				(xy 0.970026 0.4699) (xy -0.970026 0.4699) (xy -0.970026 -0.4699) (xy 0.970026 -0.4699)
			)
			(stroke
				(width 0)
				(type default)
			)
			(fill no)
			(layer "B.CrtYd")
		)
		(fp_line
			(start 0.508 0.3048)
			(end 0.508 -0.3048)
			(stroke
				(width 0.1)
				(type default)
			)
			(layer "B.Fab")
		)
		(fp_line
			(start 0.508 -0.3048)
			(end -0.508 -0.3048)
			(stroke
				(width 0.1)
				(type default)
			)
			(layer "B.Fab")
		)
		(fp_line
			(start -0.508 0.3048)
			(end 0.508 0.3048)
			(stroke
				(width 0.1)
				(type default)
			)
			(layer "B.Fab")
		)
		(fp_line
			(start -0.508 -0.3048)
			(end -0.508 0.3048)
			(stroke
				(width 0.1)
				(type default)
			)
			(layer "B.Fab")
		)
		(pad "1" smd circle
			(at 0.500126 0)
			(size 0.635 0.635)
			(layers "B.Cu" "B.Mask" "B.Paste")
			(net "MHZ200CLKP_CLKIN")
		)
		(pad "2" smd circle
			(at -0.500126 0)
			(size 0.635 0.635)
			(layers "B.Cu" "B.Mask" "B.Paste")
			(net "MHZ200CLKN_CLKIN")
		)
	)
	(footprint ""
		(layer "B.Cu")
		(at 78.994 -73.152 -90)
		(property "Reference" "C283"
			(at -3.683 0.42037 270)
			(unlocked yes)
			(layer "B.SilkS")
			(effects
				(font
					(size 0.7874 0.5842)
					(thickness 0.1524)
				)
				(justify mirror)
			)
		)
		(property "Value" "VAL*"
			(at -0.0762 3.134106 270)
			(unlocked yes)
			(layer "B.Fab")
			(hide yes)
			(effects
				(font
					(size 0.7874 0.5842)
					(thickness 0.1524)
				)
				(justify mirror)
			)
		)
		(property "Device Type" "CAPACITOR-G107-0F106-EM,10UF,2A"
			(at -0.0508 2.194306 270)
			(unlocked yes)
			(layer "B.Fab")
			(hide yes)
			(effects
				(font
					(size 0.7874 0.5842)
					(thickness 0.1524)
				)
				(justify mirror)
			)
		)
		(property "User Part Number" "PARTNUM*"
			(at -0.1016 5.013706 270)
			(unlocked yes)
			(layer "Cmts.User")
			(hide yes)
			(effects
				(font
					(size 0.7874 0.5842)
					(thickness 0.1524)
				)
				(justify mirror)
			)
		)
		(property "Tolerance" "TOL*"
			(at -0.0762 4.048506 270)
			(unlocked yes)
			(layer "Cmts.User")
			(hide yes)
			(effects
				(font
					(size 0.7874 0.5842)
					(thickness 0.1524)
				)
				(justify mirror)
			)
		)
		(duplicate_pad_numbers_are_jumpers no)
		(fp_line
			(start -1.5748 0.9398)
			(end -1.5748 -0.9398)
			(stroke
				(width 0.1)
				(type default)
			)
			(layer "B.SilkS")
		)
		(fp_line
			(start 1.5748 0.9398)
			(end -1.5748 0.9398)
			(stroke
				(width 0.1)
				(type default)
			)
			(layer "B.SilkS")
		)
		(fp_line
			(start -1.5748 -0.9398)
			(end 1.5748 -0.9398)
			(stroke
				(width 0.1)
				(type default)
			)
			(layer "B.SilkS")
		)
		(fp_line
			(start 1.5748 -0.9398)
			(end 1.5748 0.9398)
			(stroke
				(width 0.1)
				(type default)
			)
			(layer "B.SilkS")
		)
		(fp_rect
			(start 1.5748 0.9398)
			(end -1.5748 -0.9398)
			(stroke
				(width 0)
				(type default)
			)
			(fill no)
			(layer "B.CrtYd")
		)
		(fp_line
			(start -1.016 0.635)
			(end -1.016 -0.635)
			(stroke
				(width 0.1)
				(type default)
			)
			(layer "B.Fab")
		)
		(fp_line
			(start 1.016 0.635)
			(end -1.016 0.635)
			(stroke
				(width 0.1)
				(type default)
			)
			(layer "B.Fab")
		)
		(fp_line
			(start -1.016 -0.635)
			(end 1.016 -0.635)
			(stroke
				(width 0.1)
				(type default)
			)
			(layer "B.Fab")
		)
		(fp_line
			(start 1.016 -0.635)
			(end 1.016 0.635)
			(stroke
				(width 0.1)
				(type default)
			)
			(layer "B.Fab")
		)
		(pad "1" smd rect
			(at 0.8382 0 90)
			(size 0.9652 1.3716)
			(layers "B.Cu" "B.Mask" "B.Paste")
			(net "XP5R0V_MAC")
		)
		(pad "2" smd rect
			(at -0.8382 0 90)
			(size 0.9652 1.3716)
			(layers "B.Cu" "B.Mask" "B.Paste")
			(net "SG")
		)
		(zone
			(layer "B.Cu")
			(hatch none 0.5)
			(connect_pads
				(clearance 0)
			)
			(min_thickness 0.25)
			(keepout
				(tracks allowed)
				(vias not_allowed)
				(pads allowed)
				(copperpour not_allowed)
				(footprints allowed)
			)
			(placement
				(enabled no)
				(sheetname "")
			)
			(fill
				(thermal_gap 0.5)
				(thermal_bridge_width 0.5)
				(island_removal_mode 0)
			)
			(polygon
				(pts
					(xy 78.359 -72.9234) (xy 79.629 -72.9234) (xy 79.629 -73.3806) (xy 78.359 -73.3806)
				)
			)
		)
	)
	(footprint ""
		(layer "B.Cu")
		(at 139.954 -51.943 90)
		(property "Reference" "C265"
			(at -2.032 -1.18237 270)
			(unlocked yes)
			(layer "B.SilkS")
			(effects
				(font
					(size 0.7874 0.5842)
					(thickness 0.1524)
				)
				(justify mirror)
			)
		)
		(property "Value" "VAL*"
			(at -0.0762 2.067306 90)
			(unlocked yes)
			(layer "B.Fab")
			(hide yes)
			(effects
				(font
					(size 0.7874 0.5842)
					(thickness 0.1524)
				)
				(justify mirror)
			)
		)
		(property "Tolerance" "TOL*"
			(at -0.0762 3.032506 90)
			(unlocked yes)
			(layer "Cmts.User")
			(hide yes)
			(effects
				(font
					(size 0.7874 0.5842)
					(thickness 0.1524)
				)
				(justify mirror)
			)
		)
		(property "User Part Number" "PARTNUM*"
			(at -0.1016 4.023106 90)
			(unlocked yes)
			(layer "Cmts.User")
			(hide yes)
			(effects
				(font
					(size 0.7874 0.5842)
					(thickness 0.1524)
				)
				(justify mirror)
			)
		)
		(property "Device Type" "CAPACITOR-G105-0B104-EK,0.1UF,A"
			(at -0.0508 1.127506 90)
			(unlocked yes)
			(layer "B.Fab")
			(hide yes)
			(effects
				(font
					(size 0.7874 0.5842)
					(thickness 0.1524)
				)
				(justify mirror)
			)
		)
		(duplicate_pad_numbers_are_jumpers no)
		(fp_line
			(start 1.143 -0.5588)
			(end 1.143 0.5588)
			(stroke
				(width 0.1)
				(type default)
			)
			(layer "B.SilkS")
		)
		(fp_line
			(start -1.143 -0.5588)
			(end 1.143 -0.5588)
			(stroke
				(width 0.1)
				(type default)
			)
			(layer "B.SilkS")
		)
		(fp_line
			(start 1.143 0.5588)
			(end -1.143 0.5588)
			(stroke
				(width 0.1)
				(type default)
			)
			(layer "B.SilkS")
		)
		(fp_line
			(start -1.143 0.5588)
			(end -1.143 -0.5588)
			(stroke
				(width 0.1)
				(type default)
			)
			(layer "B.SilkS")
		)
		(fp_rect
			(start 1.143 -0.5588)
			(end -1.143 0.5588)
			(stroke
				(width 0)
				(type default)
			)
			(fill no)
			(layer "B.CrtYd")
		)
		(fp_line
			(start 0.508 -0.3048)
			(end 0.508 0.3048)
			(stroke
				(width 0.1)
				(type default)
			)
			(layer "B.Fab")
		)
		(fp_line
			(start -0.508 -0.3048)
			(end 0.508 -0.3048)
			(stroke
				(width 0.1)
				(type default)
			)
			(layer "B.Fab")
		)
		(fp_line
			(start 0.508 0.3048)
			(end -0.508 0.3048)
			(stroke
				(width 0.1)
				(type default)
			)
			(layer "B.Fab")
		)
		(fp_line
			(start -0.508 0.3048)
			(end -0.508 -0.3048)
			(stroke
				(width 0.1)
				(type default)
			)
			(layer "B.Fab")
		)
		(pad "1" smd rect
			(at 0.5334 0 270)
			(size 0.7112 0.6096)
			(layers "B.Cu" "B.Mask" "B.Paste")
			(net "UNNAMED_523_CAPACITOR_I24_1")
		)
		(pad "2" smd rect
			(at -0.5334 0 270)
			(size 0.7112 0.6096)
			(layers "B.Cu" "B.Mask" "B.Paste")
			(net "XP1R0V_SW")
		)
		(zone
			(layer "B.Cu")
			(hatch none 0.5)
			(connect_pads
				(clearance 0)
			)
			(min_thickness 0.25)
			(keepout
				(tracks allowed)
				(vias not_allowed)
				(pads allowed)
				(copperpour not_allowed)
				(footprints allowed)
			)
			(placement
				(enabled no)
				(sheetname "")
			)
			(fill
				(thermal_gap 0.5)
				(thermal_bridge_width 0.5)
				(island_removal_mode 0)
			)
			(polygon
				(pts
					(xy 139.6492 -52.0192) (xy 139.6492 -51.8668) (xy 140.2588 -51.8668) (xy 140.2588 -52.0192)
				)
			)
		)
	)
	(footprint ""
		(layer "B.Cu")
		(at 110.847124 -39.32301 90)
		(property "Reference" "C214"
			(at -1.14173 -42.016934 270)
			(unlocked yes)
			(layer "B.SilkS")
			(effects
				(font
					(size 0.635 0.4064)
					(thickness 0.1524)
				)
				(justify mirror)
			)
		)
		(property "Value" "VAL*"
			(at 0 3.718306 90)
			(unlocked yes)
			(layer "B.Fab")
			(hide yes)
			(effects
				(font
					(size 0.7874 0.5842)
					(thickness 0.127)
				)
				(justify mirror)
			)
		)
		(property "Tolerance" "TOL*"
			(at 0 4.861306 90)
			(unlocked yes)
			(layer "Cmts.User")
			(hide yes)
			(effects
				(font
					(size 0.7874 0.5842)
					(thickness 0.127)
				)
				(justify mirror)
			)
		)
		(property "User Part Number" "PARTNUM*"
			(at 0 2.575306 90)
			(unlocked yes)
			(layer "Cmts.User")
			(hide yes)
			(effects
				(font
					(size 0.7874 0.5842)
					(thickness 0.127)
				)
				(justify mirror)
			)
		)
		(property "Device Type" "CAPACITOR-G105-0B104-CK,0.1UF,A"
			(at 0 1.432306 90)
			(unlocked yes)
			(layer "B.Fab")
			(hide yes)
			(effects
				(font
					(size 0.7874 0.5842)
					(thickness 0.127)
				)
				(justify mirror)
			)
		)
		(duplicate_pad_numbers_are_jumpers no)
		(fp_line
			(start 0.970026 -0.4699)
			(end -0.970026 -0.4699)
			(stroke
				(width 0.1)
				(type default)
			)
			(layer "B.SilkS")
		)
		(fp_line
			(start -0.970026 -0.4699)
			(end -0.970026 0.4699)
			(stroke
				(width 0.1)
				(type default)
			)
			(layer "B.SilkS")
		)
		(fp_line
			(start 0.970026 0.4699)
			(end 0.970026 -0.4699)
			(stroke
				(width 0.1)
				(type default)
			)
			(layer "B.SilkS")
		)
		(fp_line
			(start -0.970026 0.4699)
			(end 0.970026 0.4699)
			(stroke
				(width 0.1)
				(type default)
			)
			(layer "B.SilkS")
		)
		(fp_poly
			(pts
				(xy 0.970026 0.4699) (xy -0.970026 0.4699) (xy -0.970026 -0.4699) (xy 0.970026 -0.4699)
			)
			(stroke
				(width 0)
				(type default)
			)
			(fill no)
			(layer "B.CrtYd")
		)
		(fp_line
			(start 0.508 -0.3048)
			(end -0.508 -0.3048)
			(stroke
				(width 0.1)
				(type default)
			)
			(layer "B.Fab")
		)
		(fp_line
			(start -0.508 -0.3048)
			(end -0.508 0.3048)
			(stroke
				(width 0.1)
				(type default)
			)
			(layer "B.Fab")
		)
		(fp_line
			(start 0.508 0.3048)
			(end 0.508 -0.3048)
			(stroke
				(width 0.1)
				(type default)
			)
			(layer "B.Fab")
		)
		(fp_line
			(start -0.508 0.3048)
			(end 0.508 0.3048)
			(stroke
				(width 0.1)
				(type default)
			)
			(layer "B.Fab")
		)
		(pad "1" smd circle
			(at 0.500126 0 270)
			(size 0.635 0.635)
			(layers "B.Cu" "B.Mask" "B.Paste")
			(net "XP1R0V_FPGA_VCCINT")
		)
		(pad "2" smd circle
			(at -0.500126 0 270)
			(size 0.635 0.635)
			(layers "B.Cu" "B.Mask" "B.Paste")
			(net "SG")
		)
	)
	(footprint ""
		(layer "B.Cu")
		(at 98.044 -96.774)
		(property "Reference" "R450"
			(at -0.889 -1.61163 0)
			(unlocked yes)
			(layer "B.SilkS")
			(effects
				(font
					(size 0.7874 0.5842)
					(thickness 0.1524)
				)
				(justify mirror)
			)
		)
		(property "Value" "VAL*"
			(at -0.02032 2.13233 0)
			(unlocked yes)
			(layer "B.Fab")
			(hide yes)
			(effects
				(font
					(size 0.7874 0.5842)
					(thickness 0.1524)
				)
				(justify mirror)
			)
		)
		(property "Tolerance" "TOL*"
			(at -0.044704 3.05435 0)
			(unlocked yes)
			(layer "Cmts.User")
			(hide yes)
			(effects
				(font
					(size 0.7874 0.5842)
					(thickness 0.1524)
				)
				(justify mirror)
			)
		)
		(property "User Part Number" "PARTNUM*"
			(at -0.02032 4.024884 0)
			(unlocked yes)
			(layer "Cmts.User")
			(hide yes)
			(effects
				(font
					(size 0.7874 0.5842)
					(thickness 0.1524)
				)
				(justify mirror)
			)
		)
		(property "Device Type" "RESISTOR-G155-14701-01,4.7KOHMA"
			(at -0.008382 1.210564 0)
			(unlocked yes)
			(layer "B.Fab")
			(hide yes)
			(effects
				(font
					(size 0.7874 0.5842)
					(thickness 0.1524)
				)
				(justify mirror)
			)
		)
		(duplicate_pad_numbers_are_jumpers no)
		(fp_line
			(start -1.143 -0.5588)
			(end 1.143 -0.5588)
			(stroke
				(width 0.1)
				(type default)
			)
			(layer "B.SilkS")
		)
		(fp_line
			(start -1.143 0.5588)
			(end -1.143 -0.5588)
			(stroke
				(width 0.1)
				(type default)
			)
			(layer "B.SilkS")
		)
		(fp_line
			(start 1.143 -0.5588)
			(end 1.143 0.5588)
			(stroke
				(width 0.1)
				(type default)
			)
			(layer "B.SilkS")
		)
		(fp_line
			(start 1.143 0.5588)
			(end -1.143 0.5588)
			(stroke
				(width 0.1)
				(type default)
			)
			(layer "B.SilkS")
		)
		(fp_poly
			(pts
				(xy 1.143 0.5588) (xy -1.143 0.5588) (xy -1.143 -0.5588) (xy 1.143 -0.5588)
			)
			(stroke
				(width 0)
				(type default)
			)
			(fill no)
			(layer "B.CrtYd")
		)
		(fp_line
			(start -0.508 -0.3048)
			(end 0.508 -0.3048)
			(stroke
				(width 0.1)
				(type default)
			)
			(layer "B.Fab")
		)
		(fp_line
			(start -0.508 0.3048)
			(end -0.508 -0.3048)
			(stroke
				(width 0.1)
				(type default)
			)
			(layer "B.Fab")
		)
		(fp_line
			(start 0.508 -0.3048)
			(end 0.508 0.3048)
			(stroke
				(width 0.1)
				(type default)
			)
			(layer "B.Fab")
		)
		(fp_line
			(start 0.508 0.3048)
			(end -0.508 0.3048)
			(stroke
				(width 0.1)
				(type default)
			)
			(layer "B.Fab")
		)
		(pad "1" smd rect
			(at 0.5334 0 180)
			(size 0.7112 0.6096)
			(layers "B.Cu" "B.Mask" "B.Paste")
			(net "MUX1_SEL")
		)
		(pad "2" smd rect
			(at -0.5334 0 180)
			(size 0.7112 0.6096)
			(layers "B.Cu" "B.Mask" "B.Paste")
			(net "XP3R3V_FPGA")
		)
		(zone
			(layer "B.Cu")
			(hatch none 0.5)
			(connect_pads
				(clearance 0)
			)
			(min_thickness 0.25)
			(keepout
				(tracks not_allowed)
				(vias allowed)
				(pads allowed)
				(copperpour not_allowed)
				(footprints allowed)
			)
			(placement
				(enabled no)
				(sheetname "")
			)
			(fill
				(thermal_gap 0.5)
				(thermal_bridge_width 0.5)
				(island_removal_mode 0)
			)
			(polygon
				(pts
					(xy 98.1202 -96.4692) (xy 98.1202 -97.0788) (xy 97.9678 -97.0788) (xy 97.9678 -96.4692)
				)
			)
		)
		(zone
			(layer "B.Cu")
			(hatch none 0.5)
			(connect_pads
				(clearance 0)
			)
			(min_thickness 0.25)
			(keepout
				(tracks allowed)
				(vias not_allowed)
				(pads allowed)
				(copperpour not_allowed)
				(footprints allowed)
			)
			(placement
				(enabled no)
				(sheetname "")
			)
			(fill
				(thermal_gap 0.5)
				(thermal_bridge_width 0.5)
				(island_removal_mode 0)
			)
			(polygon
				(pts
					(xy 98.1202 -96.4692) (xy 98.1202 -97.0788) (xy 97.9678 -97.0788) (xy 97.9678 -96.4692)
				)
			)
		)
	)
	(footprint ""
		(layer "B.Cu")
		(at 121.412 -46.789594 90)
		(property "Reference" "C145"
			(at -1.196594 1.49225 270)
			(unlocked yes)
			(layer "B.SilkS")
			(effects
				(font
					(size 0.635 0.4064)
					(thickness 0.1524)
				)
				(justify mirror)
			)
		)
		(property "Value" "VAL*"
			(at -0.0762 2.067306 90)
			(unlocked yes)
			(layer "B.Fab")
			(hide yes)
			(effects
				(font
					(size 0.7874 0.5842)
					(thickness 0.1524)
				)
				(justify mirror)
			)
		)
		(property "Tolerance" "TOL*"
			(at -0.0762 3.032506 90)
			(unlocked yes)
			(layer "Cmts.User")
			(hide yes)
			(effects
				(font
					(size 0.7874 0.5842)
					(thickness 0.1524)
				)
				(justify mirror)
			)
		)
		(property "User Part Number" "PARTNUM*"
			(at -0.1016 4.023106 90)
			(unlocked yes)
			(layer "Cmts.User")
			(hide yes)
			(effects
				(font
					(size 0.7874 0.5842)
					(thickness 0.1524)
				)
				(justify mirror)
			)
		)
		(property "Device Type" "CAPACITOR-G105-0B104-CK,0.1UF,A"
			(at -0.0508 1.127506 90)
			(unlocked yes)
			(layer "B.Fab")
			(hide yes)
			(effects
				(font
					(size 0.7874 0.5842)
					(thickness 0.1524)
				)
				(justify mirror)
			)
		)
		(duplicate_pad_numbers_are_jumpers no)
		(fp_line
			(start 1.143 -0.5588)
			(end 1.143 0.5588)
			(stroke
				(width 0.1)
				(type default)
			)
			(layer "B.SilkS")
		)
		(fp_line
			(start -1.143 -0.5588)
			(end 1.143 -0.5588)
			(stroke
				(width 0.1)
				(type default)
			)
			(layer "B.SilkS")
		)
		(fp_line
			(start 1.143 0.5588)
			(end -1.143 0.5588)
			(stroke
				(width 0.1)
				(type default)
			)
			(layer "B.SilkS")
		)
		(fp_line
			(start -1.143 0.5588)
			(end -1.143 -0.5588)
			(stroke
				(width 0.1)
				(type default)
			)
			(layer "B.SilkS")
		)
		(fp_rect
			(start -1.143 -0.5588)
			(end 1.143 0.5588)
			(stroke
				(width 0)
				(type default)
			)
			(fill no)
			(layer "B.CrtYd")
		)
		(fp_line
			(start 0.508 -0.3048)
			(end 0.508 0.3048)
			(stroke
				(width 0.1)
				(type default)
			)
			(layer "B.Fab")
		)
		(fp_line
			(start -0.508 -0.3048)
			(end 0.508 -0.3048)
			(stroke
				(width 0.1)
				(type default)
			)
			(layer "B.Fab")
		)
		(fp_line
			(start 0.508 0.3048)
			(end -0.508 0.3048)
			(stroke
				(width 0.1)
				(type default)
			)
			(layer "B.Fab")
		)
		(fp_line
			(start -0.508 0.3048)
			(end -0.508 -0.3048)
			(stroke
				(width 0.1)
				(type default)
			)
			(layer "B.Fab")
		)
		(pad "1" smd rect
			(at 0.5334 0 270)
			(size 0.7112 0.6096)
			(layers "B.Cu" "B.Mask" "B.Paste")
			(net "XP3R3V_FPGA")
		)
		(pad "2" smd rect
			(at -0.5334 0 270)
			(size 0.7112 0.6096)
			(layers "B.Cu" "B.Mask" "B.Paste")
			(net "SG")
		)
		(zone
			(layer "B.Cu")
			(hatch none 0.5)
			(connect_pads
				(clearance 0)
			)
			(min_thickness 0.25)
			(keepout
				(tracks allowed)
				(vias not_allowed)
				(pads allowed)
				(copperpour not_allowed)
				(footprints allowed)
			)
			(placement
				(enabled no)
				(sheetname "")
			)
			(fill
				(thermal_gap 0.5)
				(thermal_bridge_width 0.5)
				(island_removal_mode 0)
			)
			(polygon
				(pts
					(xy 121.1072 -46.713394) (xy 121.7168 -46.713394) (xy 121.7168 -46.865794) (xy 121.1072 -46.865794)
				)
			)
		)
	)
	(footprint ""
		(layer "B.Cu")
		(at 138.811 -59.563 90)
		(property "Reference" "R247"
			(at 3.175 -0.03937 270)
			(unlocked yes)
			(layer "B.SilkS")
			(effects
				(font
					(size 0.7874 0.5842)
					(thickness 0.1524)
				)
				(justify mirror)
			)
		)
		(property "Value" "VAL*"
			(at -0.02032 2.13233 90)
			(unlocked yes)
			(layer "B.Fab")
			(hide yes)
			(effects
				(font
					(size 0.7874 0.5842)
					(thickness 0.1524)
				)
				(justify mirror)
			)
		)
		(property "Tolerance" "TOL*"
			(at -0.044704 3.05435 90)
			(unlocked yes)
			(layer "Cmts.User")
			(hide yes)
			(effects
				(font
					(size 0.7874 0.5842)
					(thickness 0.1524)
				)
				(justify mirror)
			)
		)
		(property "User Part Number" "PARTNUM*"
			(at -0.02032 4.024884 90)
			(unlocked yes)
			(layer "Cmts.User")
			(hide yes)
			(effects
				(font
					(size 0.7874 0.5842)
					(thickness 0.1524)
				)
				(justify mirror)
			)
		)
		(property "Device Type" "RESISTOR-G155-11002-01,10KOHM,A"
			(at -0.008382 1.210564 90)
			(unlocked yes)
			(layer "B.Fab")
			(hide yes)
			(effects
				(font
					(size 0.7874 0.5842)
					(thickness 0.1524)
				)
				(justify mirror)
			)
		)
		(duplicate_pad_numbers_are_jumpers no)
		(fp_line
			(start 1.143 -0.5588)
			(end 1.143 0.5588)
			(stroke
				(width 0.1)
				(type default)
			)
			(layer "B.SilkS")
		)
		(fp_line
			(start -1.143 -0.5588)
			(end 1.143 -0.5588)
			(stroke
				(width 0.1)
				(type default)
			)
			(layer "B.SilkS")
		)
		(fp_line
			(start 1.143 0.5588)
			(end -1.143 0.5588)
			(stroke
				(width 0.1)
				(type default)
			)
			(layer "B.SilkS")
		)
		(fp_line
			(start -1.143 0.5588)
			(end -1.143 -0.5588)
			(stroke
				(width 0.1)
				(type default)
			)
			(layer "B.SilkS")
		)
		(fp_poly
			(pts
				(xy 1.143 0.5588) (xy -1.143 0.5588) (xy -1.143 -0.5588) (xy 1.143 -0.5588)
			)
			(stroke
				(width 0)
				(type default)
			)
			(fill no)
			(layer "B.CrtYd")
		)
		(fp_line
			(start 0.508 -0.3048)
			(end 0.508 0.3048)
			(stroke
				(width 0.1)
				(type default)
			)
			(layer "B.Fab")
		)
		(fp_line
			(start -0.508 -0.3048)
			(end 0.508 -0.3048)
			(stroke
				(width 0.1)
				(type default)
			)
			(layer "B.Fab")
		)
		(fp_line
			(start 0.508 0.3048)
			(end -0.508 0.3048)
			(stroke
				(width 0.1)
				(type default)
			)
			(layer "B.Fab")
		)
		(fp_line
			(start -0.508 0.3048)
			(end -0.508 -0.3048)
			(stroke
				(width 0.1)
				(type default)
			)
			(layer "B.Fab")
		)
		(pad "1" smd rect
			(at 0.5334 0 270)
			(size 0.7112 0.6096)
			(layers "B.Cu" "B.Mask" "B.Paste")
			(net "VIN_XP1R0V")
		)
		(pad "2" smd rect
			(at -0.5334 0 270)
			(size 0.7112 0.6096)
			(layers "B.Cu" "B.Mask" "B.Paste")
			(net "UNNAMED_523_CAPACITOR_I7_1")
		)
		(zone
			(layer "B.Cu")
			(hatch none 0.5)
			(connect_pads
				(clearance 0)
			)
			(min_thickness 0.25)
			(keepout
				(tracks not_allowed)
				(vias allowed)
				(pads allowed)
				(copperpour not_allowed)
				(footprints allowed)
			)
			(placement
				(enabled no)
				(sheetname "")
			)
			(fill
				(thermal_gap 0.5)
				(thermal_bridge_width 0.5)
				(island_removal_mode 0)
			)
			(polygon
				(pts
					(xy 139.1158 -59.6392) (xy 138.5062 -59.6392) (xy 138.5062 -59.4868) (xy 139.1158 -59.4868)
				)
			)
		)
		(zone
			(layer "B.Cu")
			(hatch none 0.5)
			(connect_pads
				(clearance 0)
			)
			(min_thickness 0.25)
			(keepout
				(tracks allowed)
				(vias not_allowed)
				(pads allowed)
				(copperpour not_allowed)
				(footprints allowed)
			)
			(placement
				(enabled no)
				(sheetname "")
			)
			(fill
				(thermal_gap 0.5)
				(thermal_bridge_width 0.5)
				(island_removal_mode 0)
			)
			(polygon
				(pts
					(xy 139.1158 -59.6392) (xy 138.5062 -59.6392) (xy 138.5062 -59.4868) (xy 139.1158 -59.4868)
				)
			)
		)
	)
	(footprint ""
		(layer "B.Cu")
		(at 93.0148 -75.819 90)
		(property "Reference" "C180"
			(at 0.508 1.56083 270)
			(unlocked yes)
			(layer "B.SilkS")
			(effects
				(font
					(size 0.7874 0.5842)
					(thickness 0.1524)
				)
				(justify mirror)
			)
		)
		(property "Value" "VAL*"
			(at -0.0762 3.134106 90)
			(unlocked yes)
			(layer "B.Fab")
			(hide yes)
			(effects
				(font
					(size 0.7874 0.5842)
					(thickness 0.1524)
				)
				(justify mirror)
			)
		)
		(property "Tolerance" "TOL*"
			(at -0.0762 4.048506 90)
			(unlocked yes)
			(layer "Cmts.User")
			(hide yes)
			(effects
				(font
					(size 0.7874 0.5842)
					(thickness 0.1524)
				)
				(justify mirror)
			)
		)
		(property "User Part Number" "PARTNUM*"
			(at -0.1016 5.013706 90)
			(unlocked yes)
			(layer "Cmts.User")
			(hide yes)
			(effects
				(font
					(size 0.7874 0.5842)
					(thickness 0.1524)
				)
				(justify mirror)
			)
		)
		(property "Device Type" "CAPACITOR-G107-0F226-CM,22UF,2A"
			(at -0.0508 2.194306 90)
			(unlocked yes)
			(layer "B.Fab")
			(hide yes)
			(effects
				(font
					(size 0.7874 0.5842)
					(thickness 0.1524)
				)
				(justify mirror)
			)
		)
		(duplicate_pad_numbers_are_jumpers no)
		(fp_line
			(start 1.5748 -0.9398)
			(end 1.5748 0.9398)
			(stroke
				(width 0.1)
				(type default)
			)
			(layer "B.SilkS")
		)
		(fp_line
			(start -1.5748 -0.9398)
			(end 1.5748 -0.9398)
			(stroke
				(width 0.1)
				(type default)
			)
			(layer "B.SilkS")
		)
		(fp_line
			(start 1.5748 0.9398)
			(end -1.5748 0.9398)
			(stroke
				(width 0.1)
				(type default)
			)
			(layer "B.SilkS")
		)
		(fp_line
			(start -1.5748 0.9398)
			(end -1.5748 -0.9398)
			(stroke
				(width 0.1)
				(type default)
			)
			(layer "B.SilkS")
		)
		(fp_rect
			(start 1.5748 -0.9398)
			(end -1.5748 0.9398)
			(stroke
				(width 0)
				(type default)
			)
			(fill no)
			(layer "B.CrtYd")
		)
		(fp_line
			(start 1.016 -0.635)
			(end 1.016 0.635)
			(stroke
				(width 0.1)
				(type default)
			)
			(layer "B.Fab")
		)
		(fp_line
			(start -1.016 -0.635)
			(end 1.016 -0.635)
			(stroke
				(width 0.1)
				(type default)
			)
			(layer "B.Fab")
		)
		(fp_line
			(start 1.016 0.635)
			(end -1.016 0.635)
			(stroke
				(width 0.1)
				(type default)
			)
			(layer "B.Fab")
		)
		(fp_line
			(start -1.016 0.635)
			(end -1.016 -0.635)
			(stroke
				(width 0.1)
				(type default)
			)
			(layer "B.Fab")
		)
		(pad "1" smd rect
			(at 0.8382 0 270)
			(size 0.9652 1.3716)
			(layers "B.Cu" "B.Mask" "B.Paste")
			(net "XP3R3V")
		)
		(pad "2" smd rect
			(at -0.8382 0 270)
			(size 0.9652 1.3716)
			(layers "B.Cu" "B.Mask" "B.Paste")
			(net "SG")
		)
		(zone
			(layer "B.Cu")
			(hatch none 0.5)
			(connect_pads
				(clearance 0)
			)
			(min_thickness 0.25)
			(keepout
				(tracks allowed)
				(vias not_allowed)
				(pads allowed)
				(copperpour not_allowed)
				(footprints allowed)
			)
			(placement
				(enabled no)
				(sheetname "")
			)
			(fill
				(thermal_gap 0.5)
				(thermal_bridge_width 0.5)
				(island_removal_mode 0)
			)
			(polygon
				(pts
					(xy 92.3798 -76.0476) (xy 92.3798 -75.5904) (xy 93.6498 -75.5904) (xy 93.6498 -76.0476)
				)
			)
		)
	)
	(footprint ""
		(layer "B.Cu")
		(at 59.51474 -15.36446 -90)
		(property "Reference" "C19"
			(at -2.41554 0.11811 270)
			(unlocked yes)
			(layer "B.SilkS")
			(effects
				(font
					(size 0.7874 0.5842)
					(thickness 0.1524)
				)
				(justify mirror)
			)
		)
		(property "Value" "VAL*"
			(at -0.0762 2.067306 270)
			(unlocked yes)
			(layer "B.Fab")
			(hide yes)
			(effects
				(font
					(size 0.7874 0.5842)
					(thickness 0.1524)
				)
				(justify mirror)
			)
		)
		(property "Tolerance" "TOL*"
			(at -0.0762 3.032506 270)
			(unlocked yes)
			(layer "Cmts.User")
			(hide yes)
			(effects
				(font
					(size 0.7874 0.5842)
					(thickness 0.1524)
				)
				(justify mirror)
			)
		)
		(property "User Part Number" "PARTNUM*"
			(at -0.1016 4.023106 270)
			(unlocked yes)
			(layer "Cmts.User")
			(hide yes)
			(effects
				(font
					(size 0.7874 0.5842)
					(thickness 0.1524)
				)
				(justify mirror)
			)
		)
		(property "Device Type" "CAPACITOR-G105-0B104-CK,0.1UF,A"
			(at -0.0508 1.127506 270)
			(unlocked yes)
			(layer "B.Fab")
			(hide yes)
			(effects
				(font
					(size 0.7874 0.5842)
					(thickness 0.1524)
				)
				(justify mirror)
			)
		)
		(duplicate_pad_numbers_are_jumpers no)
		(fp_line
			(start -1.143 0.5588)
			(end -1.143 -0.5588)
			(stroke
				(width 0.1)
				(type default)
			)
			(layer "B.SilkS")
		)
		(fp_line
			(start 1.143 0.5588)
			(end -1.143 0.5588)
			(stroke
				(width 0.1)
				(type default)
			)
			(layer "B.SilkS")
		)
		(fp_line
			(start -1.143 -0.5588)
			(end 1.143 -0.5588)
			(stroke
				(width 0.1)
				(type default)
			)
			(layer "B.SilkS")
		)
		(fp_line
			(start 1.143 -0.5588)
			(end 1.143 0.5588)
			(stroke
				(width 0.1)
				(type default)
			)
			(layer "B.SilkS")
		)
		(fp_rect
			(start 1.143 0.5588)
			(end -1.143 -0.5588)
			(stroke
				(width 0)
				(type default)
			)
			(fill no)
			(layer "B.CrtYd")
		)
		(fp_line
			(start -0.508 0.3048)
			(end -0.508 -0.3048)
			(stroke
				(width 0.1)
				(type default)
			)
			(layer "B.Fab")
		)
		(fp_line
			(start 0.508 0.3048)
			(end -0.508 0.3048)
			(stroke
				(width 0.1)
				(type default)
			)
			(layer "B.Fab")
		)
		(fp_line
			(start -0.508 -0.3048)
			(end 0.508 -0.3048)
			(stroke
				(width 0.1)
				(type default)
			)
			(layer "B.Fab")
		)
		(fp_line
			(start 0.508 -0.3048)
			(end 0.508 0.3048)
			(stroke
				(width 0.1)
				(type default)
			)
			(layer "B.Fab")
		)
		(pad "1" smd rect
			(at 0.5334 0 90)
			(size 0.7112 0.6096)
			(layers "B.Cu" "B.Mask" "B.Paste")
			(net "C_PCIEREFCLKP")
		)
		(pad "2" smd rect
			(at -0.5334 0 90)
			(size 0.7112 0.6096)
			(layers "B.Cu" "B.Mask" "B.Paste")
			(net "PCIE_REFCLKP")
		)
		(zone
			(layer "B.Cu")
			(hatch none 0.5)
			(connect_pads
				(clearance 0)
			)
			(min_thickness 0.25)
			(keepout
				(tracks allowed)
				(vias not_allowed)
				(pads allowed)
				(copperpour not_allowed)
				(footprints allowed)
			)
			(placement
				(enabled no)
				(sheetname "")
			)
			(fill
				(thermal_gap 0.5)
				(thermal_bridge_width 0.5)
				(island_removal_mode 0)
			)
			(polygon
				(pts
					(xy 59.20994 -15.28826) (xy 59.81954 -15.28826) (xy 59.81954 -15.44066) (xy 59.20994 -15.44066)
				)
			)
		)
	)
	(footprint ""
		(layer "B.Cu")
		(at 105.347008 -38.823138)
		(property "Reference" "C204"
			(at -41.656508 1.377188 0)
			(unlocked yes)
			(layer "B.SilkS")
			(effects
				(font
					(size 0.635 0.4064)
					(thickness 0.1524)
				)
				(justify mirror)
			)
		)
		(property "Value" "VAL*"
			(at 0 3.718306 0)
			(unlocked yes)
			(layer "B.Fab")
			(hide yes)
			(effects
				(font
					(size 0.7874 0.5842)
					(thickness 0.127)
				)
				(justify mirror)
			)
		)
		(property "Device Type" "CAPACITOR-G105-0B104-CK,0.1UF,A"
			(at 0 1.432306 0)
			(unlocked yes)
			(layer "B.Fab")
			(hide yes)
			(effects
				(font
					(size 0.7874 0.5842)
					(thickness 0.127)
				)
				(justify mirror)
			)
		)
		(property "User Part Number" "PARTNUM*"
			(at 0 2.575306 0)
			(unlocked yes)
			(layer "Cmts.User")
			(hide yes)
			(effects
				(font
					(size 0.7874 0.5842)
					(thickness 0.127)
				)
				(justify mirror)
			)
		)
		(property "Tolerance" "TOL*"
			(at 0 4.861306 0)
			(unlocked yes)
			(layer "Cmts.User")
			(hide yes)
			(effects
				(font
					(size 0.7874 0.5842)
					(thickness 0.127)
				)
				(justify mirror)
			)
		)
		(duplicate_pad_numbers_are_jumpers no)
		(fp_line
			(start -0.970026 -0.4699)
			(end -0.970026 0.4699)
			(stroke
				(width 0.1)
				(type default)
			)
			(layer "B.SilkS")
		)
		(fp_line
			(start -0.970026 0.4699)
			(end 0.970026 0.4699)
			(stroke
				(width 0.1)
				(type default)
			)
			(layer "B.SilkS")
		)
		(fp_line
			(start 0.970026 -0.4699)
			(end -0.970026 -0.4699)
			(stroke
				(width 0.1)
				(type default)
			)
			(layer "B.SilkS")
		)
		(fp_line
			(start 0.970026 0.4699)
			(end 0.970026 -0.4699)
			(stroke
				(width 0.1)
				(type default)
			)
			(layer "B.SilkS")
		)
		(fp_poly
			(pts
				(xy 0.970026 0.4699) (xy -0.970026 0.4699) (xy -0.970026 -0.4699) (xy 0.970026 -0.4699)
			)
			(stroke
				(width 0)
				(type default)
			)
			(fill no)
			(layer "B.CrtYd")
		)
		(fp_line
			(start -0.508 -0.3048)
			(end -0.508 0.3048)
			(stroke
				(width 0.1)
				(type default)
			)
			(layer "B.Fab")
		)
		(fp_line
			(start -0.508 0.3048)
			(end 0.508 0.3048)
			(stroke
				(width 0.1)
				(type default)
			)
			(layer "B.Fab")
		)
		(fp_line
			(start 0.508 -0.3048)
			(end -0.508 -0.3048)
			(stroke
				(width 0.1)
				(type default)
			)
			(layer "B.Fab")
		)
		(fp_line
			(start 0.508 0.3048)
			(end 0.508 -0.3048)
			(stroke
				(width 0.1)
				(type default)
			)
			(layer "B.Fab")
		)
		(pad "1" smd circle
			(at 0.500126 0 180)
			(size 0.635 0.635)
			(layers "B.Cu" "B.Mask" "B.Paste")
			(net "XP2R5V_FPGA")
		)
		(pad "2" smd circle
			(at -0.500126 0 180)
			(size 0.635 0.635)
			(layers "B.Cu" "B.Mask" "B.Paste")
			(net "SG")
		)
	)
	(footprint ""
		(layer "B.Cu")
		(at 99.346766 -37.82314)
		(property "Reference" "C110"
			(at -42.196766 2.16789 0)
			(unlocked yes)
			(layer "B.SilkS")
			(effects
				(font
					(size 0.635 0.4064)
					(thickness 0.1524)
				)
				(justify mirror)
			)
		)
		(property "Value" "VAL*"
			(at 0 3.718306 0)
			(unlocked yes)
			(layer "B.Fab")
			(hide yes)
			(effects
				(font
					(size 0.7874 0.5842)
					(thickness 0.127)
				)
				(justify mirror)
			)
		)
		(property "Tolerance" "TOL*"
			(at 0 4.861306 0)
			(unlocked yes)
			(layer "Cmts.User")
			(hide yes)
			(effects
				(font
					(size 0.7874 0.5842)
					(thickness 0.127)
				)
				(justify mirror)
			)
		)
		(property "User Part Number" "PARTNUM*"
			(at 0 2.575306 0)
			(unlocked yes)
			(layer "Cmts.User")
			(hide yes)
			(effects
				(font
					(size 0.7874 0.5842)
					(thickness 0.127)
				)
				(justify mirror)
			)
		)
		(property "Device Type" "CAPACITOR-G105-0B104-CK,0.1UF,A"
			(at 0 1.432306 0)
			(unlocked yes)
			(layer "B.Fab")
			(hide yes)
			(effects
				(font
					(size 0.7874 0.5842)
					(thickness 0.127)
				)
				(justify mirror)
			)
		)
		(duplicate_pad_numbers_are_jumpers no)
		(fp_line
			(start -0.970026 -0.4699)
			(end -0.970026 0.4699)
			(stroke
				(width 0.1)
				(type default)
			)
			(layer "B.SilkS")
		)
		(fp_line
			(start -0.970026 0.4699)
			(end 0.970026 0.4699)
			(stroke
				(width 0.1)
				(type default)
			)
			(layer "B.SilkS")
		)
		(fp_line
			(start 0.970026 -0.4699)
			(end -0.970026 -0.4699)
			(stroke
				(width 0.1)
				(type default)
			)
			(layer "B.SilkS")
		)
		(fp_line
			(start 0.970026 0.4699)
			(end 0.970026 -0.4699)
			(stroke
				(width 0.1)
				(type default)
			)
			(layer "B.SilkS")
		)
		(fp_poly
			(pts
				(xy 0.970026 0.4699) (xy -0.970026 0.4699) (xy -0.970026 -0.4699) (xy 0.970026 -0.4699)
			)
			(stroke
				(width 0)
				(type default)
			)
			(fill no)
			(layer "B.CrtYd")
		)
		(fp_line
			(start -0.508 -0.3048)
			(end -0.508 0.3048)
			(stroke
				(width 0.1)
				(type default)
			)
			(layer "B.Fab")
		)
		(fp_line
			(start -0.508 0.3048)
			(end 0.508 0.3048)
			(stroke
				(width 0.1)
				(type default)
			)
			(layer "B.Fab")
		)
		(fp_line
			(start 0.508 -0.3048)
			(end -0.508 -0.3048)
			(stroke
				(width 0.1)
				(type default)
			)
			(layer "B.Fab")
		)
		(fp_line
			(start 0.508 0.3048)
			(end 0.508 -0.3048)
			(stroke
				(width 0.1)
				(type default)
			)
			(layer "B.Fab")
		)
		(pad "1" smd circle
			(at 0.500126 0 180)
			(size 0.635 0.635)
			(layers "B.Cu" "B.Mask" "B.Paste")
			(net "FPGA_MGTAVTT")
		)
		(pad "2" smd circle
			(at -0.500126 0 180)
			(size 0.635 0.635)
			(layers "B.Cu" "B.Mask" "B.Paste")
			(net "SG")
		)
	)
	(footprint ""
		(layer "B.Cu")
		(at 21.7932 -71.374 -90)
		(property "Reference" "R343"
			(at -0.254 1.13157 270)
			(unlocked yes)
			(layer "B.SilkS")
			(effects
				(font
					(size 0.7874 0.5842)
					(thickness 0.1524)
				)
				(justify mirror)
			)
		)
		(property "Value" "VAL*"
			(at -0.02032 2.13233 270)
			(unlocked yes)
			(layer "B.Fab")
			(hide yes)
			(effects
				(font
					(size 0.7874 0.5842)
					(thickness 0.1524)
				)
				(justify mirror)
			)
		)
		(property "Tolerance" "TOL*"
			(at -0.044704 3.05435 270)
			(unlocked yes)
			(layer "Cmts.User")
			(hide yes)
			(effects
				(font
					(size 0.7874 0.5842)
					(thickness 0.1524)
				)
				(justify mirror)
			)
		)
		(property "User Part Number" "PARTNUM*"
			(at -0.02032 4.024884 270)
			(unlocked yes)
			(layer "Cmts.User")
			(hide yes)
			(effects
				(font
					(size 0.7874 0.5842)
					(thickness 0.1524)
				)
				(justify mirror)
			)
		)
		(property "Device Type" "RESISTOR-G155-100R0-J0,0OHM,-"
			(at -0.008382 1.210564 270)
			(unlocked yes)
			(layer "B.Fab")
			(hide yes)
			(effects
				(font
					(size 0.7874 0.5842)
					(thickness 0.1524)
				)
				(justify mirror)
			)
		)
		(duplicate_pad_numbers_are_jumpers no)
		(fp_line
			(start -1.143 0.5588)
			(end -1.143 -0.5588)
			(stroke
				(width 0.1)
				(type default)
			)
			(layer "B.SilkS")
		)
		(fp_line
			(start 1.143 0.5588)
			(end -1.143 0.5588)
			(stroke
				(width 0.1)
				(type default)
			)
			(layer "B.SilkS")
		)
		(fp_line
			(start -1.143 -0.5588)
			(end 1.143 -0.5588)
			(stroke
				(width 0.1)
				(type default)
			)
			(layer "B.SilkS")
		)
		(fp_line
			(start 1.143 -0.5588)
			(end 1.143 0.5588)
			(stroke
				(width 0.1)
				(type default)
			)
			(layer "B.SilkS")
		)
		(fp_poly
			(pts
				(xy 1.143 0.5588) (xy -1.143 0.5588) (xy -1.143 -0.5588) (xy 1.143 -0.5588)
			)
			(stroke
				(width 0)
				(type default)
			)
			(fill no)
			(layer "B.CrtYd")
		)
		(fp_line
			(start -0.508 0.3048)
			(end -0.508 -0.3048)
			(stroke
				(width 0.1)
				(type default)
			)
			(layer "B.Fab")
		)
		(fp_line
			(start 0.508 0.3048)
			(end -0.508 0.3048)
			(stroke
				(width 0.1)
				(type default)
			)
			(layer "B.Fab")
		)
		(fp_line
			(start -0.508 -0.3048)
			(end 0.508 -0.3048)
			(stroke
				(width 0.1)
				(type default)
			)
			(layer "B.Fab")
		)
		(fp_line
			(start 0.508 -0.3048)
			(end 0.508 0.3048)
			(stroke
				(width 0.1)
				(type default)
			)
			(layer "B.Fab")
		)
		(pad "1" smd rect
			(at 0.5334 0 90)
			(size 0.7112 0.6096)
			(layers "B.Cu" "B.Mask" "B.Paste")
			(net "UNNAMED_8_ICP10100LGA10_I24_RES")
		)
		(pad "2" smd rect
			(at -0.5334 0 90)
			(size 0.7112 0.6096)
			(layers "B.Cu" "B.Mask" "B.Paste")
			(net "SG")
		)
		(zone
			(layer "B.Cu")
			(hatch none 0.5)
			(connect_pads
				(clearance 0)
			)
			(min_thickness 0.25)
			(keepout
				(tracks not_allowed)
				(vias allowed)
				(pads allowed)
				(copperpour not_allowed)
				(footprints allowed)
			)
			(placement
				(enabled no)
				(sheetname "")
			)
			(fill
				(thermal_gap 0.5)
				(thermal_bridge_width 0.5)
				(island_removal_mode 0)
			)
			(polygon
				(pts
					(xy 21.4884 -71.2978) (xy 22.098 -71.2978) (xy 22.098 -71.4502) (xy 21.4884 -71.4502)
				)
			)
		)
		(zone
			(layer "B.Cu")
			(hatch none 0.5)
			(connect_pads
				(clearance 0)
			)
			(min_thickness 0.25)
			(keepout
				(tracks allowed)
				(vias not_allowed)
				(pads allowed)
				(copperpour not_allowed)
				(footprints allowed)
			)
			(placement
				(enabled no)
				(sheetname "")
			)
			(fill
				(thermal_gap 0.5)
				(thermal_bridge_width 0.5)
				(island_removal_mode 0)
			)
			(polygon
				(pts
					(xy 21.4884 -71.2978) (xy 22.098 -71.2978) (xy 22.098 -71.4502) (xy 21.4884 -71.4502)
				)
			)
		)
	)
	(footprint ""
		(layer "B.Cu")
		(at 140.97 -104.521 180)
		(property "Reference" "R108"
			(at 0.889 -3.84937 0)
			(unlocked yes)
			(layer "B.SilkS")
			(effects
				(font
					(size 0.7874 0.5842)
					(thickness 0.1524)
				)
				(justify mirror)
			)
		)
		(property "Value" "VAL*"
			(at -0.02032 2.13233 180)
			(unlocked yes)
			(layer "B.Fab")
			(hide yes)
			(effects
				(font
					(size 0.7874 0.5842)
					(thickness 0.1524)
				)
				(justify mirror)
			)
		)
		(property "Tolerance" "TOL*"
			(at -0.044704 3.05435 180)
			(unlocked yes)
			(layer "Cmts.User")
			(hide yes)
			(effects
				(font
					(size 0.7874 0.5842)
					(thickness 0.1524)
				)
				(justify mirror)
			)
		)
		(property "User Part Number" "PARTNUM*"
			(at -0.02032 4.024884 180)
			(unlocked yes)
			(layer "Cmts.User")
			(hide yes)
			(effects
				(font
					(size 0.7874 0.5842)
					(thickness 0.1524)
				)
				(justify mirror)
			)
		)
		(property "Device Type" "RESISTOR-G155-11000-01,100OHM,A"
			(at -0.008382 1.210564 180)
			(unlocked yes)
			(layer "B.Fab")
			(hide yes)
			(effects
				(font
					(size 0.7874 0.5842)
					(thickness 0.1524)
				)
				(justify mirror)
			)
		)
		(duplicate_pad_numbers_are_jumpers no)
		(fp_line
			(start 1.143 0.5588)
			(end -1.143 0.5588)
			(stroke
				(width 0.1)
				(type default)
			)
			(layer "B.SilkS")
		)
		(fp_line
			(start 1.143 -0.5588)
			(end 1.143 0.5588)
			(stroke
				(width 0.1)
				(type default)
			)
			(layer "B.SilkS")
		)
		(fp_line
			(start -1.143 0.5588)
			(end -1.143 -0.5588)
			(stroke
				(width 0.1)
				(type default)
			)
			(layer "B.SilkS")
		)
		(fp_line
			(start -1.143 -0.5588)
			(end 1.143 -0.5588)
			(stroke
				(width 0.1)
				(type default)
			)
			(layer "B.SilkS")
		)
		(fp_rect
			(start 1.143 0.5588)
			(end -1.143 -0.5588)
			(stroke
				(width 0)
				(type default)
			)
			(fill no)
			(layer "B.CrtYd")
		)
		(fp_line
			(start 0.508 0.3048)
			(end -0.508 0.3048)
			(stroke
				(width 0.1)
				(type default)
			)
			(layer "B.Fab")
		)
		(fp_line
			(start 0.508 -0.3048)
			(end 0.508 0.3048)
			(stroke
				(width 0.1)
				(type default)
			)
			(layer "B.Fab")
		)
		(fp_line
			(start -0.508 0.3048)
			(end -0.508 -0.3048)
			(stroke
				(width 0.1)
				(type default)
			)
			(layer "B.Fab")
		)
		(fp_line
			(start -0.508 -0.3048)
			(end 0.508 -0.3048)
			(stroke
				(width 0.1)
				(type default)
			)
			(layer "B.Fab")
		)
		(pad "1" smd rect
			(at 0.5334 0)
			(size 0.7112 0.6096)
			(layers "B.Cu" "B.Mask" "B.Paste")
			(net "UNNAMED_14_OPTICAL_I141_A")
		)
		(pad "2" smd rect
			(at -0.5334 0)
			(size 0.7112 0.6096)
			(layers "B.Cu" "B.Mask" "B.Paste")
			(net "UNNAMED_14_RESISTOR_I58_2")
		)
		(zone
			(layer "B.Cu")
			(hatch none 0.5)
			(connect_pads
				(clearance 0)
			)
			(min_thickness 0.25)
			(keepout
				(tracks allowed)
				(vias not_allowed)
				(pads allowed)
				(copperpour not_allowed)
				(footprints allowed)
			)
			(placement
				(enabled no)
				(sheetname "")
			)
			(fill
				(thermal_gap 0.5)
				(thermal_bridge_width 0.5)
				(island_removal_mode 0)
			)
			(polygon
				(pts
					(xy 140.8938 -104.8258) (xy 140.8938 -104.2162) (xy 141.0462 -104.2162) (xy 141.0462 -104.8258)
				)
			)
		)
	)
	(footprint ""
		(layer "B.Cu")
		(at 105.347262 -51.823112 180)
		(property "Reference" "C112"
			(at -0.824738 0.977138 0)
			(unlocked yes)
			(layer "B.SilkS")
			(effects
				(font
					(size 0.635 0.4064)
					(thickness 0.1524)
				)
				(justify mirror)
			)
		)
		(property "Value" "VAL*"
			(at 0 3.718306 180)
			(unlocked yes)
			(layer "B.Fab")
			(hide yes)
			(effects
				(font
					(size 0.7874 0.5842)
					(thickness 0.127)
				)
				(justify mirror)
			)
		)
		(property "Device Type" "CAPACITOR-G105-0B104-CK,0.1UF,A"
			(at 0 1.432306 180)
			(unlocked yes)
			(layer "B.Fab")
			(hide yes)
			(effects
				(font
					(size 0.7874 0.5842)
					(thickness 0.127)
				)
				(justify mirror)
			)
		)
		(property "User Part Number" "PARTNUM*"
			(at 0 2.575306 180)
			(unlocked yes)
			(layer "Cmts.User")
			(hide yes)
			(effects
				(font
					(size 0.7874 0.5842)
					(thickness 0.127)
				)
				(justify mirror)
			)
		)
		(property "Tolerance" "TOL*"
			(at 0 4.861306 180)
			(unlocked yes)
			(layer "Cmts.User")
			(hide yes)
			(effects
				(font
					(size 0.7874 0.5842)
					(thickness 0.127)
				)
				(justify mirror)
			)
		)
		(duplicate_pad_numbers_are_jumpers no)
		(fp_line
			(start 0.970026 0.4699)
			(end 0.970026 -0.4699)
			(stroke
				(width 0.1)
				(type default)
			)
			(layer "B.SilkS")
		)
		(fp_line
			(start 0.970026 -0.4699)
			(end -0.970026 -0.4699)
			(stroke
				(width 0.1)
				(type default)
			)
			(layer "B.SilkS")
		)
		(fp_line
			(start -0.970026 0.4699)
			(end 0.970026 0.4699)
			(stroke
				(width 0.1)
				(type default)
			)
			(layer "B.SilkS")
		)
		(fp_line
			(start -0.970026 -0.4699)
			(end -0.970026 0.4699)
			(stroke
				(width 0.1)
				(type default)
			)
			(layer "B.SilkS")
		)
		(fp_poly
			(pts
				(xy 0.970026 0.4699) (xy -0.970026 0.4699) (xy -0.970026 -0.4699) (xy 0.970026 -0.4699)
			)
			(stroke
				(width 0)
				(type default)
			)
			(fill no)
			(layer "B.CrtYd")
		)
		(fp_line
			(start 0.508 0.3048)
			(end 0.508 -0.3048)
			(stroke
				(width 0.1)
				(type default)
			)
			(layer "B.Fab")
		)
		(fp_line
			(start 0.508 -0.3048)
			(end -0.508 -0.3048)
			(stroke
				(width 0.1)
				(type default)
			)
			(layer "B.Fab")
		)
		(fp_line
			(start -0.508 0.3048)
			(end 0.508 0.3048)
			(stroke
				(width 0.1)
				(type default)
			)
			(layer "B.Fab")
		)
		(fp_line
			(start -0.508 -0.3048)
			(end -0.508 0.3048)
			(stroke
				(width 0.1)
				(type default)
			)
			(layer "B.Fab")
		)
		(pad "1" smd circle
			(at 0.500126 0)
			(size 0.635 0.635)
			(layers "B.Cu" "B.Mask" "B.Paste")
			(net "XP3R3V_FPGA")
		)
		(pad "2" smd circle
			(at -0.500126 0)
			(size 0.635 0.635)
			(layers "B.Cu" "B.Mask" "B.Paste")
			(net "SG")
		)
	)
	(footprint ""
		(layer "B.Cu")
		(at 110.49 -61.976 -90)
		(property "Reference" "R207"
			(at -3.81 0.03937 270)
			(unlocked yes)
			(layer "B.SilkS")
			(effects
				(font
					(size 0.7874 0.5842)
					(thickness 0.1524)
				)
				(justify mirror)
			)
		)
		(property "Value" "VAL*"
			(at -0.02032 2.13233 270)
			(unlocked yes)
			(layer "B.Fab")
			(hide yes)
			(effects
				(font
					(size 0.7874 0.5842)
					(thickness 0.1524)
				)
				(justify mirror)
			)
		)
		(property "Device Type" "RESISTOR-G155-149R9-01,49.9OHMA"
			(at -0.008382 1.210564 270)
			(unlocked yes)
			(layer "B.Fab")
			(hide yes)
			(effects
				(font
					(size 0.7874 0.5842)
					(thickness 0.1524)
				)
				(justify mirror)
			)
		)
		(property "User Part Number" "PARTNUM*"
			(at -0.02032 4.024884 270)
			(unlocked yes)
			(layer "Cmts.User")
			(hide yes)
			(effects
				(font
					(size 0.7874 0.5842)
					(thickness 0.1524)
				)
				(justify mirror)
			)
		)
		(property "Tolerance" "TOL*"
			(at -0.044704 3.05435 270)
			(unlocked yes)
			(layer "Cmts.User")
			(hide yes)
			(effects
				(font
					(size 0.7874 0.5842)
					(thickness 0.1524)
				)
				(justify mirror)
			)
		)
		(duplicate_pad_numbers_are_jumpers no)
		(fp_line
			(start -1.143 0.5588)
			(end -1.143 -0.5588)
			(stroke
				(width 0.1)
				(type default)
			)
			(layer "B.SilkS")
		)
		(fp_line
			(start 1.143 0.5588)
			(end -1.143 0.5588)
			(stroke
				(width 0.1)
				(type default)
			)
			(layer "B.SilkS")
		)
		(fp_line
			(start -1.143 -0.5588)
			(end 1.143 -0.5588)
			(stroke
				(width 0.1)
				(type default)
			)
			(layer "B.SilkS")
		)
		(fp_line
			(start 1.143 -0.5588)
			(end 1.143 0.5588)
			(stroke
				(width 0.1)
				(type default)
			)
			(layer "B.SilkS")
		)
		(fp_rect
			(start -1.143 0.5588)
			(end 1.143 -0.5588)
			(stroke
				(width 0)
				(type default)
			)
			(fill no)
			(layer "B.CrtYd")
		)
		(fp_line
			(start -0.508 0.3048)
			(end -0.508 -0.3048)
			(stroke
				(width 0.1)
				(type default)
			)
			(layer "B.Fab")
		)
		(fp_line
			(start 0.508 0.3048)
			(end -0.508 0.3048)
			(stroke
				(width 0.1)
				(type default)
			)
			(layer "B.Fab")
		)
		(fp_line
			(start -0.508 -0.3048)
			(end 0.508 -0.3048)
			(stroke
				(width 0.1)
				(type default)
			)
			(layer "B.Fab")
		)
		(fp_line
			(start 0.508 -0.3048)
			(end 0.508 0.3048)
			(stroke
				(width 0.1)
				(type default)
			)
			(layer "B.Fab")
		)
		(pad "1" smd rect
			(at 0.5334 0 90)
			(size 0.7112 0.6096)
			(layers "B.Cu" "B.Mask" "B.Paste")
			(net "CCLK_0")
		)
		(pad "2" smd rect
			(at -0.5334 0 90)
			(size 0.7112 0.6096)
			(layers "B.Cu" "B.Mask" "B.Paste")
			(net "FPGA_FLASH_CLK")
		)
		(zone
			(layer "B.Cu")
			(hatch none 0.5)
			(connect_pads
				(clearance 0)
			)
			(min_thickness 0.25)
			(keepout
				(tracks allowed)
				(vias not_allowed)
				(pads allowed)
				(copperpour not_allowed)
				(footprints allowed)
			)
			(placement
				(enabled no)
				(sheetname "")
			)
			(fill
				(thermal_gap 0.5)
				(thermal_bridge_width 0.5)
				(island_removal_mode 0)
			)
			(polygon
				(pts
					(xy 110.1852 -62.0522) (xy 110.1852 -61.8998) (xy 110.7948 -61.8998) (xy 110.7948 -62.0522)
				)
			)
		)
	)
	(footprint ""
		(layer "B.Cu")
		(at 77.089 -49.403 180)
		(property "Reference" "C64"
			(at -3.048 -0.03937 0)
			(unlocked yes)
			(layer "B.SilkS")
			(effects
				(font
					(size 0.7874 0.5842)
					(thickness 0.1524)
				)
				(justify mirror)
			)
		)
		(property "Value" "VAL*"
			(at -0.0762 3.134106 180)
			(unlocked yes)
			(layer "B.Fab")
			(hide yes)
			(effects
				(font
					(size 0.7874 0.5842)
					(thickness 0.1524)
				)
				(justify mirror)
			)
		)
		(property "Tolerance" "TOL*"
			(at -0.0762 4.048506 180)
			(unlocked yes)
			(layer "Cmts.User")
			(hide yes)
			(effects
				(font
					(size 0.7874 0.5842)
					(thickness 0.1524)
				)
				(justify mirror)
			)
		)
		(property "User Part Number" "PARTNUM*"
			(at -0.1016 5.013706 180)
			(unlocked yes)
			(layer "Cmts.User")
			(hide yes)
			(effects
				(font
					(size 0.7874 0.5842)
					(thickness 0.1524)
				)
				(justify mirror)
			)
		)
		(property "Device Type" "CAPACITOR-G107-0F106-EM,10UF,2A"
			(at -0.0508 2.194306 180)
			(unlocked yes)
			(layer "B.Fab")
			(hide yes)
			(effects
				(font
					(size 0.7874 0.5842)
					(thickness 0.1524)
				)
				(justify mirror)
			)
		)
		(duplicate_pad_numbers_are_jumpers no)
		(fp_line
			(start 1.5748 0.9398)
			(end -1.5748 0.9398)
			(stroke
				(width 0.1)
				(type default)
			)
			(layer "B.SilkS")
		)
		(fp_line
			(start 1.5748 -0.9398)
			(end 1.5748 0.9398)
			(stroke
				(width 0.1)
				(type default)
			)
			(layer "B.SilkS")
		)
		(fp_line
			(start -1.5748 0.9398)
			(end -1.5748 -0.9398)
			(stroke
				(width 0.1)
				(type default)
			)
			(layer "B.SilkS")
		)
		(fp_line
			(start -1.5748 -0.9398)
			(end 1.5748 -0.9398)
			(stroke
				(width 0.1)
				(type default)
			)
			(layer "B.SilkS")
		)
		(fp_rect
			(start 1.5748 0.9398)
			(end -1.5748 -0.9398)
			(stroke
				(width 0)
				(type default)
			)
			(fill no)
			(layer "B.CrtYd")
		)
		(fp_line
			(start 1.016 0.635)
			(end -1.016 0.635)
			(stroke
				(width 0.1)
				(type default)
			)
			(layer "B.Fab")
		)
		(fp_line
			(start 1.016 -0.635)
			(end 1.016 0.635)
			(stroke
				(width 0.1)
				(type default)
			)
			(layer "B.Fab")
		)
		(fp_line
			(start -1.016 0.635)
			(end -1.016 -0.635)
			(stroke
				(width 0.1)
				(type default)
			)
			(layer "B.Fab")
		)
		(fp_line
			(start -1.016 -0.635)
			(end 1.016 -0.635)
			(stroke
				(width 0.1)
				(type default)
			)
			(layer "B.Fab")
		)
		(pad "1" smd rect
			(at 0.8382 0)
			(size 0.9652 1.3716)
			(layers "B.Cu" "B.Mask" "B.Paste")
			(net "XP5R0V_MAC_USB")
		)
		(pad "2" smd rect
			(at -0.8382 0)
			(size 0.9652 1.3716)
			(layers "B.Cu" "B.Mask" "B.Paste")
			(net "SG")
		)
		(zone
			(layer "B.Cu")
			(hatch none 0.5)
			(connect_pads
				(clearance 0)
			)
			(min_thickness 0.25)
			(keepout
				(tracks allowed)
				(vias not_allowed)
				(pads allowed)
				(copperpour not_allowed)
				(footprints allowed)
			)
			(placement
				(enabled no)
				(sheetname "")
			)
			(fill
				(thermal_gap 0.5)
				(thermal_bridge_width 0.5)
				(island_removal_mode 0)
			)
			(polygon
				(pts
					(xy 76.8604 -50.038) (xy 76.8604 -48.768) (xy 77.3176 -48.768) (xy 77.3176 -50.038)
				)
			)
		)
	)
	(footprint ""
		(layer "B.Cu")
		(at 107.84713 -41.32326 -90)
		(property "Reference" "C166"
			(at 1.016 41.38422 270)
			(unlocked yes)
			(layer "B.SilkS")
			(effects
				(font
					(size 0.635 0.4064)
					(thickness 0.1524)
				)
				(justify mirror)
			)
		)
		(property "Value" "VAL*"
			(at 0 3.718306 270)
			(unlocked yes)
			(layer "B.Fab")
			(hide yes)
			(effects
				(font
					(size 0.7874 0.5842)
					(thickness 0.127)
				)
				(justify mirror)
			)
		)
		(property "Device Type" "CAPACITOR-G105-0B104-CK,0.1UF,A"
			(at 0 1.432306 270)
			(unlocked yes)
			(layer "B.Fab")
			(hide yes)
			(effects
				(font
					(size 0.7874 0.5842)
					(thickness 0.127)
				)
				(justify mirror)
			)
		)
		(property "User Part Number" "PARTNUM*"
			(at 0 2.575306 270)
			(unlocked yes)
			(layer "Cmts.User")
			(hide yes)
			(effects
				(font
					(size 0.7874 0.5842)
					(thickness 0.127)
				)
				(justify mirror)
			)
		)
		(property "Tolerance" "TOL*"
			(at 0 4.861306 270)
			(unlocked yes)
			(layer "Cmts.User")
			(hide yes)
			(effects
				(font
					(size 0.7874 0.5842)
					(thickness 0.127)
				)
				(justify mirror)
			)
		)
		(duplicate_pad_numbers_are_jumpers no)
		(fp_line
			(start -0.970026 0.4699)
			(end 0.970026 0.4699)
			(stroke
				(width 0.1)
				(type default)
			)
			(layer "B.SilkS")
		)
		(fp_line
			(start 0.970026 0.4699)
			(end 0.970026 -0.4699)
			(stroke
				(width 0.1)
				(type default)
			)
			(layer "B.SilkS")
		)
		(fp_line
			(start -0.970026 -0.4699)
			(end -0.970026 0.4699)
			(stroke
				(width 0.1)
				(type default)
			)
			(layer "B.SilkS")
		)
		(fp_line
			(start 0.970026 -0.4699)
			(end -0.970026 -0.4699)
			(stroke
				(width 0.1)
				(type default)
			)
			(layer "B.SilkS")
		)
		(fp_poly
			(pts
				(xy 0.970026 0.4699) (xy -0.970026 0.4699) (xy -0.970026 -0.4699) (xy 0.970026 -0.4699)
			)
			(stroke
				(width 0)
				(type default)
			)
			(fill no)
			(layer "B.CrtYd")
		)
		(fp_line
			(start -0.508 0.3048)
			(end 0.508 0.3048)
			(stroke
				(width 0.1)
				(type default)
			)
			(layer "B.Fab")
		)
		(fp_line
			(start 0.508 0.3048)
			(end 0.508 -0.3048)
			(stroke
				(width 0.1)
				(type default)
			)
			(layer "B.Fab")
		)
		(fp_line
			(start -0.508 -0.3048)
			(end -0.508 0.3048)
			(stroke
				(width 0.1)
				(type default)
			)
			(layer "B.Fab")
		)
		(fp_line
			(start 0.508 -0.3048)
			(end -0.508 -0.3048)
			(stroke
				(width 0.1)
				(type default)
			)
			(layer "B.Fab")
		)
		(pad "1" smd circle
			(at 0.500126 0 90)
			(size 0.635 0.635)
			(layers "B.Cu" "B.Mask" "B.Paste")
			(net "XP1R0V_FPGA_VCCINT")
		)
		(pad "2" smd circle
			(at -0.500126 0 90)
			(size 0.635 0.635)
			(layers "B.Cu" "B.Mask" "B.Paste")
			(net "SG")
		)
	)
	(footprint ""
		(layer "B.Cu")
		(at 102.84714 -49.323244 -90)
		(property "Reference" "C170"
			(at -2.111756 0.26289 270)
			(unlocked yes)
			(layer "B.SilkS")
			(effects
				(font
					(size 0.635 0.4064)
					(thickness 0.1524)
				)
				(justify mirror)
			)
		)
		(property "Value" "VAL*"
			(at 0 3.718306 270)
			(unlocked yes)
			(layer "B.Fab")
			(hide yes)
			(effects
				(font
					(size 0.7874 0.5842)
					(thickness 0.127)
				)
				(justify mirror)
			)
		)
		(property "Device Type" "CAPACITOR-G105-0F475-BM,4.7UF,A"
			(at 0 1.432306 270)
			(unlocked yes)
			(layer "B.Fab")
			(hide yes)
			(effects
				(font
					(size 0.7874 0.5842)
					(thickness 0.127)
				)
				(justify mirror)
			)
		)
		(property "User Part Number" "PARTNUM*"
			(at 0 2.575306 270)
			(unlocked yes)
			(layer "Cmts.User")
			(hide yes)
			(effects
				(font
					(size 0.7874 0.5842)
					(thickness 0.127)
				)
				(justify mirror)
			)
		)
		(property "Tolerance" "TOL*"
			(at 0 4.861306 270)
			(unlocked yes)
			(layer "Cmts.User")
			(hide yes)
			(effects
				(font
					(size 0.7874 0.5842)
					(thickness 0.127)
				)
				(justify mirror)
			)
		)
		(duplicate_pad_numbers_are_jumpers no)
		(fp_line
			(start -0.970026 0.4699)
			(end 0.970026 0.4699)
			(stroke
				(width 0.1)
				(type default)
			)
			(layer "B.SilkS")
		)
		(fp_line
			(start 0.970026 0.4699)
			(end 0.970026 -0.4699)
			(stroke
				(width 0.1)
				(type default)
			)
			(layer "B.SilkS")
		)
		(fp_line
			(start -0.970026 -0.4699)
			(end -0.970026 0.4699)
			(stroke
				(width 0.1)
				(type default)
			)
			(layer "B.SilkS")
		)
		(fp_line
			(start 0.970026 -0.4699)
			(end -0.970026 -0.4699)
			(stroke
				(width 0.1)
				(type default)
			)
			(layer "B.SilkS")
		)
		(fp_poly
			(pts
				(xy 0.970026 0.4699) (xy -0.970026 0.4699) (xy -0.970026 -0.4699) (xy 0.970026 -0.4699)
			)
			(stroke
				(width 0)
				(type default)
			)
			(fill no)
			(layer "B.CrtYd")
		)
		(fp_line
			(start -0.508 0.3048)
			(end 0.508 0.3048)
			(stroke
				(width 0.1)
				(type default)
			)
			(layer "B.Fab")
		)
		(fp_line
			(start 0.508 0.3048)
			(end 0.508 -0.3048)
			(stroke
				(width 0.1)
				(type default)
			)
			(layer "B.Fab")
		)
		(fp_line
			(start -0.508 -0.3048)
			(end -0.508 0.3048)
			(stroke
				(width 0.1)
				(type default)
			)
			(layer "B.Fab")
		)
		(fp_line
			(start 0.508 -0.3048)
			(end -0.508 -0.3048)
			(stroke
				(width 0.1)
				(type default)
			)
			(layer "B.Fab")
		)
		(pad "1" smd circle
			(at 0.500126 0 90)
			(size 0.635 0.635)
			(layers "B.Cu" "B.Mask" "B.Paste")
			(net "XP3R3V_FPGA")
		)
		(pad "2" smd circle
			(at -0.500126 0 90)
			(size 0.635 0.635)
			(layers "B.Cu" "B.Mask" "B.Paste")
			(net "SG")
		)
	)
	(footprint ""
		(layer "B.Cu")
		(at 16.6624 -15.621 180)
		(property "Reference" "C82"
			(at -0.2286 -1.18237 0)
			(unlocked yes)
			(layer "B.SilkS")
			(effects
				(font
					(size 0.7874 0.5842)
					(thickness 0.1524)
				)
				(justify mirror)
			)
		)
		(property "Value" "VAL*"
			(at -0.0762 2.067306 180)
			(unlocked yes)
			(layer "B.Fab")
			(hide yes)
			(effects
				(font
					(size 0.7874 0.5842)
					(thickness 0.1524)
				)
				(justify mirror)
			)
		)
		(property "Device Type" "CAPACITOR-G105-0B104-CK,0.1UF,A"
			(at -0.0508 1.127506 180)
			(unlocked yes)
			(layer "B.Fab")
			(hide yes)
			(effects
				(font
					(size 0.7874 0.5842)
					(thickness 0.1524)
				)
				(justify mirror)
			)
		)
		(property "User Part Number" "PARTNUM*"
			(at -0.1016 4.023106 180)
			(unlocked yes)
			(layer "Cmts.User")
			(hide yes)
			(effects
				(font
					(size 0.7874 0.5842)
					(thickness 0.1524)
				)
				(justify mirror)
			)
		)
		(property "Tolerance" "TOL*"
			(at -0.0762 3.032506 180)
			(unlocked yes)
			(layer "Cmts.User")
			(hide yes)
			(effects
				(font
					(size 0.7874 0.5842)
					(thickness 0.1524)
				)
				(justify mirror)
			)
		)
		(duplicate_pad_numbers_are_jumpers no)
		(fp_line
			(start 1.143 0.5588)
			(end -1.143 0.5588)
			(stroke
				(width 0.1)
				(type default)
			)
			(layer "B.SilkS")
		)
		(fp_line
			(start 1.143 -0.5588)
			(end 1.143 0.5588)
			(stroke
				(width 0.1)
				(type default)
			)
			(layer "B.SilkS")
		)
		(fp_line
			(start -1.143 0.5588)
			(end -1.143 -0.5588)
			(stroke
				(width 0.1)
				(type default)
			)
			(layer "B.SilkS")
		)
		(fp_line
			(start -1.143 -0.5588)
			(end 1.143 -0.5588)
			(stroke
				(width 0.1)
				(type default)
			)
			(layer "B.SilkS")
		)
		(fp_rect
			(start -1.143 0.5588)
			(end 1.143 -0.5588)
			(stroke
				(width 0)
				(type default)
			)
			(fill no)
			(layer "B.CrtYd")
		)
		(fp_line
			(start 0.508 0.3048)
			(end -0.508 0.3048)
			(stroke
				(width 0.1)
				(type default)
			)
			(layer "B.Fab")
		)
		(fp_line
			(start 0.508 -0.3048)
			(end 0.508 0.3048)
			(stroke
				(width 0.1)
				(type default)
			)
			(layer "B.Fab")
		)
		(fp_line
			(start -0.508 0.3048)
			(end -0.508 -0.3048)
			(stroke
				(width 0.1)
				(type default)
			)
			(layer "B.Fab")
		)
		(fp_line
			(start -0.508 -0.3048)
			(end 0.508 -0.3048)
			(stroke
				(width 0.1)
				(type default)
			)
			(layer "B.Fab")
		)
		(pad "1" smd rect
			(at 0.5334 0)
			(size 0.7112 0.6096)
			(layers "B.Cu" "B.Mask" "B.Paste")
			(net "XP3R3V_FPGA")
		)
		(pad "2" smd rect
			(at -0.5334 0)
			(size 0.7112 0.6096)
			(layers "B.Cu" "B.Mask" "B.Paste")
			(net "SG")
		)
		(zone
			(layer "B.Cu")
			(hatch none 0.5)
			(connect_pads
				(clearance 0)
			)
			(min_thickness 0.25)
			(keepout
				(tracks allowed)
				(vias not_allowed)
				(pads allowed)
				(copperpour not_allowed)
				(footprints allowed)
			)
			(placement
				(enabled no)
				(sheetname "")
			)
			(fill
				(thermal_gap 0.5)
				(thermal_bridge_width 0.5)
				(island_removal_mode 0)
			)
			(polygon
				(pts
					(xy 16.7386 -15.9258) (xy 16.5862 -15.9258) (xy 16.5862 -15.3162) (xy 16.7386 -15.3162)
				)
			)
		)
	)
	(footprint ""
		(layer "B.Cu")
		(at 124.587 -41.402)
		(property "Reference" "R217"
			(at 3.429 0.16637 0)
			(unlocked yes)
			(layer "B.SilkS")
			(effects
				(font
					(size 0.7874 0.5842)
					(thickness 0.1524)
				)
				(justify mirror)
			)
		)
		(property "Value" "VAL*"
			(at -0.02032 2.13233 0)
			(unlocked yes)
			(layer "B.Fab")
			(hide yes)
			(effects
				(font
					(size 0.7874 0.5842)
					(thickness 0.1524)
				)
				(justify mirror)
			)
		)
		(property "Tolerance" "TOL*"
			(at -0.044704 3.05435 0)
			(unlocked yes)
			(layer "Cmts.User")
			(hide yes)
			(effects
				(font
					(size 0.7874 0.5842)
					(thickness 0.1524)
				)
				(justify mirror)
			)
		)
		(property "User Part Number" "PARTNUM*"
			(at -0.02032 4.024884 0)
			(unlocked yes)
			(layer "Cmts.User")
			(hide yes)
			(effects
				(font
					(size 0.7874 0.5842)
					(thickness 0.1524)
				)
				(justify mirror)
			)
		)
		(property "Device Type" "RESISTOR-G155-11000-01,100OHM,A"
			(at -0.008382 1.210564 0)
			(unlocked yes)
			(layer "B.Fab")
			(hide yes)
			(effects
				(font
					(size 0.7874 0.5842)
					(thickness 0.1524)
				)
				(justify mirror)
			)
		)
		(duplicate_pad_numbers_are_jumpers no)
		(fp_line
			(start -1.143 -0.5588)
			(end 1.143 -0.5588)
			(stroke
				(width 0.1)
				(type default)
			)
			(layer "B.SilkS")
		)
		(fp_line
			(start -1.143 0.5588)
			(end -1.143 -0.5588)
			(stroke
				(width 0.1)
				(type default)
			)
			(layer "B.SilkS")
		)
		(fp_line
			(start 1.143 -0.5588)
			(end 1.143 0.5588)
			(stroke
				(width 0.1)
				(type default)
			)
			(layer "B.SilkS")
		)
		(fp_line
			(start 1.143 0.5588)
			(end -1.143 0.5588)
			(stroke
				(width 0.1)
				(type default)
			)
			(layer "B.SilkS")
		)
		(fp_rect
			(start -1.143 0.5588)
			(end 1.143 -0.5588)
			(stroke
				(width 0)
				(type default)
			)
			(fill no)
			(layer "B.CrtYd")
		)
		(fp_line
			(start -0.508 -0.3048)
			(end 0.508 -0.3048)
			(stroke
				(width 0.1)
				(type default)
			)
			(layer "B.Fab")
		)
		(fp_line
			(start -0.508 0.3048)
			(end -0.508 -0.3048)
			(stroke
				(width 0.1)
				(type default)
			)
			(layer "B.Fab")
		)
		(fp_line
			(start 0.508 -0.3048)
			(end 0.508 0.3048)
			(stroke
				(width 0.1)
				(type default)
			)
			(layer "B.Fab")
		)
		(fp_line
			(start 0.508 0.3048)
			(end -0.508 0.3048)
			(stroke
				(width 0.1)
				(type default)
			)
			(layer "B.Fab")
		)
		(pad "1" smd rect
			(at 0.5334 0 180)
			(size 0.7112 0.6096)
			(layers "B.Cu" "B.Mask" "B.Paste")
			(net "XP3R3V_FPGA")
		)
		(pad "2" smd rect
			(at -0.5334 0 180)
			(size 0.7112 0.6096)
			(layers "B.Cu" "B.Mask" "B.Paste")
			(net "FPGA_M1")
		)
		(zone
			(layer "B.Cu")
			(hatch none 0.5)
			(connect_pads
				(clearance 0)
			)
			(min_thickness 0.25)
			(keepout
				(tracks allowed)
				(vias not_allowed)
				(pads allowed)
				(copperpour not_allowed)
				(footprints allowed)
			)
			(placement
				(enabled no)
				(sheetname "")
			)
			(fill
				(thermal_gap 0.5)
				(thermal_bridge_width 0.5)
				(island_removal_mode 0)
			)
			(polygon
				(pts
					(xy 124.5108 -41.0972) (xy 124.6632 -41.0972) (xy 124.6632 -41.7068) (xy 124.5108 -41.7068)
				)
			)
		)
	)
	(footprint ""
		(layer "B.Cu")
		(at 117.729 -98.933)
		(property "Reference" "C80"
			(at -1.016 1.30937 0)
			(unlocked yes)
			(layer "B.SilkS")
			(effects
				(font
					(size 0.7874 0.5842)
					(thickness 0.1524)
				)
				(justify mirror)
			)
		)
		(property "Value" "VAL*"
			(at -0.0762 2.067306 0)
			(unlocked yes)
			(layer "B.Fab")
			(hide yes)
			(effects
				(font
					(size 0.7874 0.5842)
					(thickness 0.1524)
				)
				(justify mirror)
			)
		)
		(property "Tolerance" "TOL*"
			(at -0.0762 3.032506 0)
			(unlocked yes)
			(layer "Cmts.User")
			(hide yes)
			(effects
				(font
					(size 0.7874 0.5842)
					(thickness 0.1524)
				)
				(justify mirror)
			)
		)
		(property "User Part Number" "PARTNUM*"
			(at -0.1016 4.023106 0)
			(unlocked yes)
			(layer "Cmts.User")
			(hide yes)
			(effects
				(font
					(size 0.7874 0.5842)
					(thickness 0.1524)
				)
				(justify mirror)
			)
		)
		(property "Device Type" "CAPACITOR-G105-0B104-CK,0.1UF,A"
			(at -0.0508 1.127506 0)
			(unlocked yes)
			(layer "B.Fab")
			(hide yes)
			(effects
				(font
					(size 0.7874 0.5842)
					(thickness 0.1524)
				)
				(justify mirror)
			)
		)
		(duplicate_pad_numbers_are_jumpers no)
		(fp_line
			(start -1.143 -0.5588)
			(end 1.143 -0.5588)
			(stroke
				(width 0.1)
				(type default)
			)
			(layer "B.SilkS")
		)
		(fp_line
			(start -1.143 0.5588)
			(end -1.143 -0.5588)
			(stroke
				(width 0.1)
				(type default)
			)
			(layer "B.SilkS")
		)
		(fp_line
			(start 1.143 -0.5588)
			(end 1.143 0.5588)
			(stroke
				(width 0.1)
				(type default)
			)
			(layer "B.SilkS")
		)
		(fp_line
			(start 1.143 0.5588)
			(end -1.143 0.5588)
			(stroke
				(width 0.1)
				(type default)
			)
			(layer "B.SilkS")
		)
		(fp_rect
			(start -1.143 -0.5588)
			(end 1.143 0.5588)
			(stroke
				(width 0)
				(type default)
			)
			(fill no)
			(layer "B.CrtYd")
		)
		(fp_line
			(start -0.508 -0.3048)
			(end 0.508 -0.3048)
			(stroke
				(width 0.1)
				(type default)
			)
			(layer "B.Fab")
		)
		(fp_line
			(start -0.508 0.3048)
			(end -0.508 -0.3048)
			(stroke
				(width 0.1)
				(type default)
			)
			(layer "B.Fab")
		)
		(fp_line
			(start 0.508 -0.3048)
			(end 0.508 0.3048)
			(stroke
				(width 0.1)
				(type default)
			)
			(layer "B.Fab")
		)
		(fp_line
			(start 0.508 0.3048)
			(end -0.508 0.3048)
			(stroke
				(width 0.1)
				(type default)
			)
			(layer "B.Fab")
		)
		(pad "1" smd rect
			(at 0.5334 0 180)
			(size 0.7112 0.6096)
			(layers "B.Cu" "B.Mask" "B.Paste")
			(net "XP3R3V_GPS")
		)
		(pad "2" smd rect
			(at -0.5334 0 180)
			(size 0.7112 0.6096)
			(layers "B.Cu" "B.Mask" "B.Paste")
			(net "SG")
		)
		(zone
			(layer "B.Cu")
			(hatch none 0.5)
			(connect_pads
				(clearance 0)
			)
			(min_thickness 0.25)
			(keepout
				(tracks allowed)
				(vias not_allowed)
				(pads allowed)
				(copperpour not_allowed)
				(footprints allowed)
			)
			(placement
				(enabled no)
				(sheetname "")
			)
			(fill
				(thermal_gap 0.5)
				(thermal_bridge_width 0.5)
				(island_removal_mode 0)
			)
			(polygon
				(pts
					(xy 117.6528 -99.2378) (xy 117.6528 -98.6282) (xy 117.8052 -98.6282) (xy 117.8052 -99.2378)
				)
			)
		)
	)
	(footprint ""
		(layer "B.Cu")
		(at 147.066 -103.505)
		(property "Reference" "R262"
			(at 1.016 3.08737 0)
			(unlocked yes)
			(layer "B.SilkS")
			(effects
				(font
					(size 0.7874 0.5842)
					(thickness 0.1524)
				)
				(justify mirror)
			)
		)
		(property "Value" "VAL*"
			(at -0.02032 2.13233 0)
			(unlocked yes)
			(layer "B.Fab")
			(hide yes)
			(effects
				(font
					(size 0.7874 0.5842)
					(thickness 0.1524)
				)
				(justify mirror)
			)
		)
		(property "Tolerance" "TOL*"
			(at -0.044704 3.05435 0)
			(unlocked yes)
			(layer "Cmts.User")
			(hide yes)
			(effects
				(font
					(size 0.7874 0.5842)
					(thickness 0.1524)
				)
				(justify mirror)
			)
		)
		(property "User Part Number" "PARTNUM*"
			(at -0.02032 4.024884 0)
			(unlocked yes)
			(layer "Cmts.User")
			(hide yes)
			(effects
				(font
					(size 0.7874 0.5842)
					(thickness 0.1524)
				)
				(justify mirror)
			)
		)
		(property "Device Type" "RESISTOR-G155-11001-01,1KOHM,1%"
			(at -0.008382 1.210564 0)
			(unlocked yes)
			(layer "B.Fab")
			(hide yes)
			(effects
				(font
					(size 0.7874 0.5842)
					(thickness 0.1524)
				)
				(justify mirror)
			)
		)
		(duplicate_pad_numbers_are_jumpers no)
		(fp_line
			(start -1.143 -0.5588)
			(end 1.143 -0.5588)
			(stroke
				(width 0.1)
				(type default)
			)
			(layer "B.SilkS")
		)
		(fp_line
			(start -1.143 0.5588)
			(end -1.143 -0.5588)
			(stroke
				(width 0.1)
				(type default)
			)
			(layer "B.SilkS")
		)
		(fp_line
			(start 1.143 -0.5588)
			(end 1.143 0.5588)
			(stroke
				(width 0.1)
				(type default)
			)
			(layer "B.SilkS")
		)
		(fp_line
			(start 1.143 0.5588)
			(end -1.143 0.5588)
			(stroke
				(width 0.1)
				(type default)
			)
			(layer "B.SilkS")
		)
		(fp_rect
			(start 1.143 0.5588)
			(end -1.143 -0.5588)
			(stroke
				(width 0)
				(type default)
			)
			(fill no)
			(layer "B.CrtYd")
		)
		(fp_line
			(start -0.508 -0.3048)
			(end 0.508 -0.3048)
			(stroke
				(width 0.1)
				(type default)
			)
			(layer "B.Fab")
		)
		(fp_line
			(start -0.508 0.3048)
			(end -0.508 -0.3048)
			(stroke
				(width 0.1)
				(type default)
			)
			(layer "B.Fab")
		)
		(fp_line
			(start 0.508 -0.3048)
			(end 0.508 0.3048)
			(stroke
				(width 0.1)
				(type default)
			)
			(layer "B.Fab")
		)
		(fp_line
			(start 0.508 0.3048)
			(end -0.508 0.3048)
			(stroke
				(width 0.1)
				(type default)
			)
			(layer "B.Fab")
		)
		(pad "1" smd rect
			(at 0.5334 0 180)
			(size 0.7112 0.6096)
			(layers "B.Cu" "B.Mask" "B.Paste")
			(net "UNNAMED_14_RESISTOR_I65_2")
		)
		(pad "2" smd rect
			(at -0.5334 0 180)
			(size 0.7112 0.6096)
			(layers "B.Cu" "B.Mask" "B.Paste")
			(net "XP12R0V")
		)
		(zone
			(layer "B.Cu")
			(hatch none 0.5)
			(connect_pads
				(clearance 0)
			)
			(min_thickness 0.25)
			(keepout
				(tracks allowed)
				(vias not_allowed)
				(pads allowed)
				(copperpour not_allowed)
				(footprints allowed)
			)
			(placement
				(enabled no)
				(sheetname "")
			)
			(fill
				(thermal_gap 0.5)
				(thermal_bridge_width 0.5)
				(island_removal_mode 0)
			)
			(polygon
				(pts
					(xy 147.1422 -103.2002) (xy 147.1422 -103.8098) (xy 146.9898 -103.8098) (xy 146.9898 -103.2002)
				)
			)
		)
	)
	(footprint ""
		(layer "B.Cu")
		(at 126.0094 -68.7578 -90)
		(property "Reference" "R174"
			(at 1.7018 1.33477 270)
			(unlocked yes)
			(layer "B.SilkS")
			(effects
				(font
					(size 0.7874 0.5842)
					(thickness 0.1524)
				)
				(justify mirror)
			)
		)
		(property "Value" "VAL*"
			(at -0.02032 2.13233 270)
			(unlocked yes)
			(layer "B.Fab")
			(hide yes)
			(effects
				(font
					(size 0.7874 0.5842)
					(thickness 0.1524)
				)
				(justify mirror)
			)
		)
		(property "Tolerance" "TOL*"
			(at -0.044704 3.05435 270)
			(unlocked yes)
			(layer "Cmts.User")
			(hide yes)
			(effects
				(font
					(size 0.7874 0.5842)
					(thickness 0.1524)
				)
				(justify mirror)
			)
		)
		(property "User Part Number" "PARTNUM*"
			(at -0.02032 4.024884 270)
			(unlocked yes)
			(layer "Cmts.User")
			(hide yes)
			(effects
				(font
					(size 0.7874 0.5842)
					(thickness 0.1524)
				)
				(justify mirror)
			)
		)
		(property "Device Type" "RESISTOR-G155-11002-01,10KOHM,A"
			(at -0.008382 1.210564 270)
			(unlocked yes)
			(layer "B.Fab")
			(hide yes)
			(effects
				(font
					(size 0.7874 0.5842)
					(thickness 0.1524)
				)
				(justify mirror)
			)
		)
		(duplicate_pad_numbers_are_jumpers no)
		(fp_line
			(start -1.143 0.5588)
			(end -1.143 -0.5588)
			(stroke
				(width 0.1)
				(type default)
			)
			(layer "B.SilkS")
		)
		(fp_line
			(start 1.143 0.5588)
			(end -1.143 0.5588)
			(stroke
				(width 0.1)
				(type default)
			)
			(layer "B.SilkS")
		)
		(fp_line
			(start -1.143 -0.5588)
			(end 1.143 -0.5588)
			(stroke
				(width 0.1)
				(type default)
			)
			(layer "B.SilkS")
		)
		(fp_line
			(start 1.143 -0.5588)
			(end 1.143 0.5588)
			(stroke
				(width 0.1)
				(type default)
			)
			(layer "B.SilkS")
		)
		(fp_rect
			(start -1.143 -0.5588)
			(end 1.143 0.5588)
			(stroke
				(width 0)
				(type default)
			)
			(fill no)
			(layer "B.CrtYd")
		)
		(fp_line
			(start -0.508 0.3048)
			(end -0.508 -0.3048)
			(stroke
				(width 0.1)
				(type default)
			)
			(layer "B.Fab")
		)
		(fp_line
			(start 0.508 0.3048)
			(end -0.508 0.3048)
			(stroke
				(width 0.1)
				(type default)
			)
			(layer "B.Fab")
		)
		(fp_line
			(start -0.508 -0.3048)
			(end 0.508 -0.3048)
			(stroke
				(width 0.1)
				(type default)
			)
			(layer "B.Fab")
		)
		(fp_line
			(start 0.508 -0.3048)
			(end 0.508 0.3048)
			(stroke
				(width 0.1)
				(type default)
			)
			(layer "B.Fab")
		)
		(pad "1" smd rect
			(at 0.5334 0 90)
			(size 0.7112 0.6096)
			(layers "B.Cu" "B.Mask" "B.Paste")
			(net "XP1R8V_EN_R")
		)
		(pad "2" smd rect
			(at -0.5334 0 90)
			(size 0.7112 0.6096)
			(layers "B.Cu" "B.Mask" "B.Paste")
			(net "SG")
		)
		(zone
			(layer "B.Cu")
			(hatch none 0.5)
			(connect_pads
				(clearance 0)
			)
			(min_thickness 0.25)
			(keepout
				(tracks allowed)
				(vias not_allowed)
				(pads allowed)
				(copperpour not_allowed)
				(footprints allowed)
			)
			(placement
				(enabled no)
				(sheetname "")
			)
			(fill
				(thermal_gap 0.5)
				(thermal_bridge_width 0.5)
				(island_removal_mode 0)
			)
			(polygon
				(pts
					(xy 126.3142 -68.834) (xy 125.7046 -68.834) (xy 125.7046 -68.6816) (xy 126.3142 -68.6816)
				)
			)
		)
	)
	(footprint ""
		(layer "B.Cu")
		(at 124.587 -44.831 180)
		(property "Reference" "R209"
			(at -3.683 -0.16637 0)
			(unlocked yes)
			(layer "B.SilkS")
			(effects
				(font
					(size 0.7874 0.5842)
					(thickness 0.1524)
				)
				(justify mirror)
			)
		)
		(property "Value" "VAL*"
			(at -0.02032 2.13233 180)
			(unlocked yes)
			(layer "B.Fab")
			(hide yes)
			(effects
				(font
					(size 0.7874 0.5842)
					(thickness 0.1524)
				)
				(justify mirror)
			)
		)
		(property "Device Type" "RESISTOR-G155-14701-01,4.7KOHMA"
			(at -0.008382 1.210564 180)
			(unlocked yes)
			(layer "B.Fab")
			(hide yes)
			(effects
				(font
					(size 0.7874 0.5842)
					(thickness 0.1524)
				)
				(justify mirror)
			)
		)
		(property "User Part Number" "PARTNUM*"
			(at -0.02032 4.024884 180)
			(unlocked yes)
			(layer "Cmts.User")
			(hide yes)
			(effects
				(font
					(size 0.7874 0.5842)
					(thickness 0.1524)
				)
				(justify mirror)
			)
		)
		(property "Tolerance" "TOL*"
			(at -0.044704 3.05435 180)
			(unlocked yes)
			(layer "Cmts.User")
			(hide yes)
			(effects
				(font
					(size 0.7874 0.5842)
					(thickness 0.1524)
				)
				(justify mirror)
			)
		)
		(duplicate_pad_numbers_are_jumpers no)
		(fp_line
			(start 1.143 0.5588)
			(end -1.143 0.5588)
			(stroke
				(width 0.1)
				(type default)
			)
			(layer "B.SilkS")
		)
		(fp_line
			(start 1.143 -0.5588)
			(end 1.143 0.5588)
			(stroke
				(width 0.1)
				(type default)
			)
			(layer "B.SilkS")
		)
		(fp_line
			(start -1.143 0.5588)
			(end -1.143 -0.5588)
			(stroke
				(width 0.1)
				(type default)
			)
			(layer "B.SilkS")
		)
		(fp_line
			(start -1.143 -0.5588)
			(end 1.143 -0.5588)
			(stroke
				(width 0.1)
				(type default)
			)
			(layer "B.SilkS")
		)
		(fp_rect
			(start -1.143 0.5588)
			(end 1.143 -0.5588)
			(stroke
				(width 0)
				(type default)
			)
			(fill no)
			(layer "B.CrtYd")
		)
		(fp_line
			(start 0.508 0.3048)
			(end -0.508 0.3048)
			(stroke
				(width 0.1)
				(type default)
			)
			(layer "B.Fab")
		)
		(fp_line
			(start 0.508 -0.3048)
			(end 0.508 0.3048)
			(stroke
				(width 0.1)
				(type default)
			)
			(layer "B.Fab")
		)
		(fp_line
			(start -0.508 0.3048)
			(end -0.508 -0.3048)
			(stroke
				(width 0.1)
				(type default)
			)
			(layer "B.Fab")
		)
		(fp_line
			(start -0.508 -0.3048)
			(end 0.508 -0.3048)
			(stroke
				(width 0.1)
				(type default)
			)
			(layer "B.Fab")
		)
		(pad "1" smd rect
			(at 0.5334 0)
			(size 0.7112 0.6096)
			(layers "B.Cu" "B.Mask" "B.Paste")
			(net "FPGA_CFG_INIT_N")
		)
		(pad "2" smd rect
			(at -0.5334 0)
			(size 0.7112 0.6096)
			(layers "B.Cu" "B.Mask" "B.Paste")
			(net "XP3R3V_FPGA")
		)
		(zone
			(layer "B.Cu")
			(hatch none 0.5)
			(connect_pads
				(clearance 0)
			)
			(min_thickness 0.25)
			(keepout
				(tracks allowed)
				(vias not_allowed)
				(pads allowed)
				(copperpour not_allowed)
				(footprints allowed)
			)
			(placement
				(enabled no)
				(sheetname "")
			)
			(fill
				(thermal_gap 0.5)
				(thermal_bridge_width 0.5)
				(island_removal_mode 0)
			)
			(polygon
				(pts
					(xy 124.6632 -45.1358) (xy 124.5108 -45.1358) (xy 124.5108 -44.5262) (xy 124.6632 -44.5262)
				)
			)
		)
	)
	(footprint ""
		(layer "B.Cu")
		(at 146.1516 -59.563 90)
		(property "Reference" "R251"
			(at 0.889 2.78003 270)
			(unlocked yes)
			(layer "B.SilkS")
			(effects
				(font
					(size 0.7874 0.5842)
					(thickness 0.1524)
				)
				(justify mirror)
			)
		)
		(property "Value" "VAL*"
			(at -0.02032 2.13233 90)
			(unlocked yes)
			(layer "B.Fab")
			(hide yes)
			(effects
				(font
					(size 0.7874 0.5842)
					(thickness 0.1524)
				)
				(justify mirror)
			)
		)
		(property "Tolerance" "TOL*"
			(at -0.044704 3.05435 90)
			(unlocked yes)
			(layer "Cmts.User")
			(hide yes)
			(effects
				(font
					(size 0.7874 0.5842)
					(thickness 0.1524)
				)
				(justify mirror)
			)
		)
		(property "User Part Number" "PARTNUM*"
			(at -0.02032 4.024884 90)
			(unlocked yes)
			(layer "Cmts.User")
			(hide yes)
			(effects
				(font
					(size 0.7874 0.5842)
					(thickness 0.1524)
				)
				(justify mirror)
			)
		)
		(property "Device Type" "RESISTOR-G155-03322-01,33.2KOHA"
			(at -0.008382 1.210564 90)
			(unlocked yes)
			(layer "B.Fab")
			(hide yes)
			(effects
				(font
					(size 0.7874 0.5842)
					(thickness 0.1524)
				)
				(justify mirror)
			)
		)
		(duplicate_pad_numbers_are_jumpers no)
		(fp_line
			(start 1.143 -0.5588)
			(end 1.143 0.5588)
			(stroke
				(width 0.1)
				(type default)
			)
			(layer "B.SilkS")
		)
		(fp_line
			(start -1.143 -0.5588)
			(end 1.143 -0.5588)
			(stroke
				(width 0.1)
				(type default)
			)
			(layer "B.SilkS")
		)
		(fp_line
			(start 1.143 0.5588)
			(end -1.143 0.5588)
			(stroke
				(width 0.1)
				(type default)
			)
			(layer "B.SilkS")
		)
		(fp_line
			(start -1.143 0.5588)
			(end -1.143 -0.5588)
			(stroke
				(width 0.1)
				(type default)
			)
			(layer "B.SilkS")
		)
		(fp_poly
			(pts
				(xy 1.143 0.5588) (xy -1.143 0.5588) (xy -1.143 -0.5588) (xy 1.143 -0.5588)
			)
			(stroke
				(width 0)
				(type default)
			)
			(fill no)
			(layer "B.CrtYd")
		)
		(fp_line
			(start 0.508 -0.3048)
			(end 0.508 0.3048)
			(stroke
				(width 0.1)
				(type default)
			)
			(layer "B.Fab")
		)
		(fp_line
			(start -0.508 -0.3048)
			(end 0.508 -0.3048)
			(stroke
				(width 0.1)
				(type default)
			)
			(layer "B.Fab")
		)
		(fp_line
			(start 0.508 0.3048)
			(end -0.508 0.3048)
			(stroke
				(width 0.1)
				(type default)
			)
			(layer "B.Fab")
		)
		(fp_line
			(start -0.508 0.3048)
			(end -0.508 -0.3048)
			(stroke
				(width 0.1)
				(type default)
			)
			(layer "B.Fab")
		)
		(pad "1" smd rect
			(at 0.5334 0 270)
			(size 0.7112 0.6096)
			(layers "B.Cu" "B.Mask" "B.Paste")
			(net "XP1R0V_AGND")
		)
		(pad "2" smd rect
			(at -0.5334 0 270)
			(size 0.7112 0.6096)
			(layers "B.Cu" "B.Mask" "B.Paste")
			(net "XP1R0V_FB_R_TO_AGND")
		)
		(zone
			(layer "B.Cu")
			(hatch none 0.5)
			(connect_pads
				(clearance 0)
			)
			(min_thickness 0.25)
			(keepout
				(tracks allowed)
				(vias not_allowed)
				(pads allowed)
				(copperpour not_allowed)
				(footprints allowed)
			)
			(placement
				(enabled no)
				(sheetname "")
			)
			(fill
				(thermal_gap 0.5)
				(thermal_bridge_width 0.5)
				(island_removal_mode 0)
			)
			(polygon
				(pts
					(xy 146.4564 -59.6392) (xy 145.8468 -59.6392) (xy 145.8468 -59.4868) (xy 146.4564 -59.4868)
				)
			)
		)
		(zone
			(layer "B.Cu")
			(hatch none 0.5)
			(connect_pads
				(clearance 0)
			)
			(min_thickness 0.25)
			(keepout
				(tracks not_allowed)
				(vias allowed)
				(pads allowed)
				(copperpour not_allowed)
				(footprints allowed)
			)
			(placement
				(enabled no)
				(sheetname "")
			)
			(fill
				(thermal_gap 0.5)
				(thermal_bridge_width 0.5)
				(island_removal_mode 0)
			)
			(polygon
				(pts
					(xy 146.4564 -59.6392) (xy 145.8468 -59.6392) (xy 145.8468 -59.4868) (xy 146.4564 -59.4868)
				)
			)
		)
	)
	(footprint ""
		(layer "B.Cu")
		(at 106.847132 -47.323248 -90)
		(property "Reference" "C221"
			(at -1.444752 -0.944118 270)
			(unlocked yes)
			(layer "B.SilkS")
			(effects
				(font
					(size 0.635 0.4064)
					(thickness 0.1524)
				)
				(justify mirror)
			)
		)
		(property "Value" "VAL*"
			(at 0 3.718306 270)
			(unlocked yes)
			(layer "B.Fab")
			(hide yes)
			(effects
				(font
					(size 0.7874 0.5842)
					(thickness 0.127)
				)
				(justify mirror)
			)
		)
		(property "Tolerance" "TOL*"
			(at 0 4.861306 270)
			(unlocked yes)
			(layer "Cmts.User")
			(hide yes)
			(effects
				(font
					(size 0.7874 0.5842)
					(thickness 0.127)
				)
				(justify mirror)
			)
		)
		(property "User Part Number" "PARTNUM*"
			(at 0 2.575306 270)
			(unlocked yes)
			(layer "Cmts.User")
			(hide yes)
			(effects
				(font
					(size 0.7874 0.5842)
					(thickness 0.127)
				)
				(justify mirror)
			)
		)
		(property "Device Type" "CAPACITOR-G105-0B104-CK,0.1UF,A"
			(at 0 1.432306 270)
			(unlocked yes)
			(layer "B.Fab")
			(hide yes)
			(effects
				(font
					(size 0.7874 0.5842)
					(thickness 0.127)
				)
				(justify mirror)
			)
		)
		(duplicate_pad_numbers_are_jumpers no)
		(fp_line
			(start -0.970026 0.4699)
			(end 0.970026 0.4699)
			(stroke
				(width 0.1)
				(type default)
			)
			(layer "B.SilkS")
		)
		(fp_line
			(start 0.970026 0.4699)
			(end 0.970026 -0.4699)
			(stroke
				(width 0.1)
				(type default)
			)
			(layer "B.SilkS")
		)
		(fp_line
			(start -0.970026 -0.4699)
			(end -0.970026 0.4699)
			(stroke
				(width 0.1)
				(type default)
			)
			(layer "B.SilkS")
		)
		(fp_line
			(start 0.970026 -0.4699)
			(end -0.970026 -0.4699)
			(stroke
				(width 0.1)
				(type default)
			)
			(layer "B.SilkS")
		)
		(fp_poly
			(pts
				(xy 0.970026 0.4699) (xy -0.970026 0.4699) (xy -0.970026 -0.4699) (xy 0.970026 -0.4699)
			)
			(stroke
				(width 0)
				(type default)
			)
			(fill no)
			(layer "B.CrtYd")
		)
		(fp_line
			(start -0.508 0.3048)
			(end 0.508 0.3048)
			(stroke
				(width 0.1)
				(type default)
			)
			(layer "B.Fab")
		)
		(fp_line
			(start 0.508 0.3048)
			(end 0.508 -0.3048)
			(stroke
				(width 0.1)
				(type default)
			)
			(layer "B.Fab")
		)
		(fp_line
			(start -0.508 -0.3048)
			(end -0.508 0.3048)
			(stroke
				(width 0.1)
				(type default)
			)
			(layer "B.Fab")
		)
		(fp_line
			(start 0.508 -0.3048)
			(end -0.508 -0.3048)
			(stroke
				(width 0.1)
				(type default)
			)
			(layer "B.Fab")
		)
		(pad "1" smd circle
			(at 0.500126 0 90)
			(size 0.635 0.635)
			(layers "B.Cu" "B.Mask" "B.Paste")
			(net "XP3R3V_FPGA")
		)
		(pad "2" smd circle
			(at -0.500126 0 90)
			(size 0.635 0.635)
			(layers "B.Cu" "B.Mask" "B.Paste")
			(net "SG")
		)
	)
	(footprint ""
		(layer "B.Cu")
		(at 8.509 -72.39 -90)
		(property "Reference" "R333"
			(at 0.381 -2.62763 270)
			(unlocked yes)
			(layer "B.SilkS")
			(effects
				(font
					(size 0.7874 0.5842)
					(thickness 0.1524)
				)
				(justify mirror)
			)
		)
		(property "Value" "VAL*"
			(at -0.02032 2.13233 270)
			(unlocked yes)
			(layer "B.Fab")
			(hide yes)
			(effects
				(font
					(size 0.7874 0.5842)
					(thickness 0.1524)
				)
				(justify mirror)
			)
		)
		(property "Tolerance" "TOL*"
			(at -0.044704 3.05435 270)
			(unlocked yes)
			(layer "Cmts.User")
			(hide yes)
			(effects
				(font
					(size 0.7874 0.5842)
					(thickness 0.1524)
				)
				(justify mirror)
			)
		)
		(property "User Part Number" "PARTNUM*"
			(at -0.02032 4.024884 270)
			(unlocked yes)
			(layer "Cmts.User")
			(hide yes)
			(effects
				(font
					(size 0.7874 0.5842)
					(thickness 0.1524)
				)
				(justify mirror)
			)
		)
		(property "Device Type" "RESISTOR-G155-14701-01,4.7KOHMA"
			(at -0.008382 1.210564 270)
			(unlocked yes)
			(layer "B.Fab")
			(hide yes)
			(effects
				(font
					(size 0.7874 0.5842)
					(thickness 0.1524)
				)
				(justify mirror)
			)
		)
		(duplicate_pad_numbers_are_jumpers no)
		(fp_line
			(start -1.143 0.5588)
			(end -1.143 -0.5588)
			(stroke
				(width 0.1)
				(type default)
			)
			(layer "B.SilkS")
		)
		(fp_line
			(start 1.143 0.5588)
			(end -1.143 0.5588)
			(stroke
				(width 0.1)
				(type default)
			)
			(layer "B.SilkS")
		)
		(fp_line
			(start -1.143 -0.5588)
			(end 1.143 -0.5588)
			(stroke
				(width 0.1)
				(type default)
			)
			(layer "B.SilkS")
		)
		(fp_line
			(start 1.143 -0.5588)
			(end 1.143 0.5588)
			(stroke
				(width 0.1)
				(type default)
			)
			(layer "B.SilkS")
		)
		(fp_rect
			(start 1.143 -0.5588)
			(end -1.143 0.5588)
			(stroke
				(width 0)
				(type default)
			)
			(fill no)
			(layer "B.CrtYd")
		)
		(fp_line
			(start -0.508 0.3048)
			(end -0.508 -0.3048)
			(stroke
				(width 0.1)
				(type default)
			)
			(layer "B.Fab")
		)
		(fp_line
			(start 0.508 0.3048)
			(end -0.508 0.3048)
			(stroke
				(width 0.1)
				(type default)
			)
			(layer "B.Fab")
		)
		(fp_line
			(start -0.508 -0.3048)
			(end 0.508 -0.3048)
			(stroke
				(width 0.1)
				(type default)
			)
			(layer "B.Fab")
		)
		(fp_line
			(start 0.508 -0.3048)
			(end 0.508 0.3048)
			(stroke
				(width 0.1)
				(type default)
			)
			(layer "B.Fab")
		)
		(pad "1" smd rect
			(at 0.5334 0 90)
			(size 0.7112 0.6096)
			(layers "B.Cu" "B.Mask" "B.Paste")
			(net "XP3R3V_FPGA")
		)
		(pad "2" smd rect
			(at -0.5334 0 90)
			(size 0.7112 0.6096)
			(layers "B.Cu" "B.Mask" "B.Paste")
			(net "UNNAMED_6_LM75BDPTSSOP8_I34_A2")
		)
		(zone
			(layer "B.Cu")
			(hatch none 0.5)
			(connect_pads
				(clearance 0)
			)
			(min_thickness 0.25)
			(keepout
				(tracks allowed)
				(vias not_allowed)
				(pads allowed)
				(copperpour not_allowed)
				(footprints allowed)
			)
			(placement
				(enabled no)
				(sheetname "")
			)
			(fill
				(thermal_gap 0.5)
				(thermal_bridge_width 0.5)
				(island_removal_mode 0)
			)
			(polygon
				(pts
					(xy 8.8138 -72.3138) (xy 8.8138 -72.4662) (xy 8.2042 -72.4662) (xy 8.2042 -72.3138)
				)
			)
		)
	)
	(footprint ""
		(layer "B.Cu")
		(at 140.97 -103.378)
		(property "Reference" "R139"
			(at -0.889 3.72237 0)
			(unlocked yes)
			(layer "B.SilkS")
			(effects
				(font
					(size 0.7874 0.5842)
					(thickness 0.1524)
				)
				(justify mirror)
			)
		)
		(property "Value" "VAL*"
			(at -0.02032 2.13233 0)
			(unlocked yes)
			(layer "B.Fab")
			(hide yes)
			(effects
				(font
					(size 0.7874 0.5842)
					(thickness 0.1524)
				)
				(justify mirror)
			)
		)
		(property "Tolerance" "TOL*"
			(at -0.044704 3.05435 0)
			(unlocked yes)
			(layer "Cmts.User")
			(hide yes)
			(effects
				(font
					(size 0.7874 0.5842)
					(thickness 0.1524)
				)
				(justify mirror)
			)
		)
		(property "User Part Number" "PARTNUM*"
			(at -0.02032 4.024884 0)
			(unlocked yes)
			(layer "Cmts.User")
			(hide yes)
			(effects
				(font
					(size 0.7874 0.5842)
					(thickness 0.1524)
				)
				(justify mirror)
			)
		)
		(property "Device Type" "RESISTOR-G155-133R0-01,33OHM,1%"
			(at -0.008382 1.210564 0)
			(unlocked yes)
			(layer "B.Fab")
			(hide yes)
			(effects
				(font
					(size 0.7874 0.5842)
					(thickness 0.1524)
				)
				(justify mirror)
			)
		)
		(duplicate_pad_numbers_are_jumpers no)
		(fp_line
			(start -1.143 -0.5588)
			(end 1.143 -0.5588)
			(stroke
				(width 0.1)
				(type default)
			)
			(layer "B.SilkS")
		)
		(fp_line
			(start -1.143 0.5588)
			(end -1.143 -0.5588)
			(stroke
				(width 0.1)
				(type default)
			)
			(layer "B.SilkS")
		)
		(fp_line
			(start 1.143 -0.5588)
			(end 1.143 0.5588)
			(stroke
				(width 0.1)
				(type default)
			)
			(layer "B.SilkS")
		)
		(fp_line
			(start 1.143 0.5588)
			(end -1.143 0.5588)
			(stroke
				(width 0.1)
				(type default)
			)
			(layer "B.SilkS")
		)
		(fp_rect
			(start -1.143 -0.5588)
			(end 1.143 0.5588)
			(stroke
				(width 0)
				(type default)
			)
			(fill no)
			(layer "B.CrtYd")
		)
		(fp_line
			(start -0.508 -0.3048)
			(end 0.508 -0.3048)
			(stroke
				(width 0.1)
				(type default)
			)
			(layer "B.Fab")
		)
		(fp_line
			(start -0.508 0.3048)
			(end -0.508 -0.3048)
			(stroke
				(width 0.1)
				(type default)
			)
			(layer "B.Fab")
		)
		(fp_line
			(start 0.508 -0.3048)
			(end 0.508 0.3048)
			(stroke
				(width 0.1)
				(type default)
			)
			(layer "B.Fab")
		)
		(fp_line
			(start 0.508 0.3048)
			(end -0.508 0.3048)
			(stroke
				(width 0.1)
				(type default)
			)
			(layer "B.Fab")
		)
		(pad "1" smd rect
			(at 0.5334 0 180)
			(size 0.7112 0.6096)
			(layers "B.Cu" "B.Mask" "B.Paste")
			(net "UNNAMED_14_RESISTOR_I58_2")
		)
		(pad "2" smd rect
			(at -0.5334 0 180)
			(size 0.7112 0.6096)
			(layers "B.Cu" "B.Mask" "B.Paste")
			(net "XP2R5V_FPGA")
		)
		(zone
			(layer "B.Cu")
			(hatch none 0.5)
			(connect_pads
				(clearance 0)
			)
			(min_thickness 0.25)
			(keepout
				(tracks allowed)
				(vias not_allowed)
				(pads allowed)
				(copperpour not_allowed)
				(footprints allowed)
			)
			(placement
				(enabled no)
				(sheetname "")
			)
			(fill
				(thermal_gap 0.5)
				(thermal_bridge_width 0.5)
				(island_removal_mode 0)
			)
			(polygon
				(pts
					(xy 140.8938 -103.6828) (xy 140.8938 -103.0732) (xy 141.0462 -103.0732) (xy 141.0462 -103.6828)
				)
			)
		)
	)
	(footprint ""
		(layer "B.Cu")
		(at 133.9342 -106.172254 -90)
		(property "Reference" "R210"
			(at 7.747254 -1.15443 270)
			(unlocked yes)
			(layer "B.SilkS")
			(effects
				(font
					(size 0.7874 0.5842)
					(thickness 0.1524)
				)
				(justify mirror)
			)
		)
		(property "Value" "VAL*"
			(at -0.02032 2.13233 270)
			(unlocked yes)
			(layer "B.Fab")
			(hide yes)
			(effects
				(font
					(size 0.7874 0.5842)
					(thickness 0.1524)
				)
				(justify mirror)
			)
		)
		(property "Device Type" "RESISTOR-G155-13300-01,330OHM,A"
			(at -0.008382 1.210564 270)
			(unlocked yes)
			(layer "B.Fab")
			(hide yes)
			(effects
				(font
					(size 0.7874 0.5842)
					(thickness 0.1524)
				)
				(justify mirror)
			)
		)
		(property "User Part Number" "PARTNUM*"
			(at -0.02032 4.024884 270)
			(unlocked yes)
			(layer "Cmts.User")
			(hide yes)
			(effects
				(font
					(size 0.7874 0.5842)
					(thickness 0.1524)
				)
				(justify mirror)
			)
		)
		(property "Tolerance" "TOL*"
			(at -0.044704 3.05435 270)
			(unlocked yes)
			(layer "Cmts.User")
			(hide yes)
			(effects
				(font
					(size 0.7874 0.5842)
					(thickness 0.1524)
				)
				(justify mirror)
			)
		)
		(duplicate_pad_numbers_are_jumpers no)
		(fp_line
			(start -1.143 0.5588)
			(end -1.143 -0.5588)
			(stroke
				(width 0.1)
				(type default)
			)
			(layer "B.SilkS")
		)
		(fp_line
			(start 1.143 0.5588)
			(end -1.143 0.5588)
			(stroke
				(width 0.1)
				(type default)
			)
			(layer "B.SilkS")
		)
		(fp_line
			(start -1.143 -0.5588)
			(end 1.143 -0.5588)
			(stroke
				(width 0.1)
				(type default)
			)
			(layer "B.SilkS")
		)
		(fp_line
			(start 1.143 -0.5588)
			(end 1.143 0.5588)
			(stroke
				(width 0.1)
				(type default)
			)
			(layer "B.SilkS")
		)
		(fp_rect
			(start 1.143 0.5588)
			(end -1.143 -0.5588)
			(stroke
				(width 0)
				(type default)
			)
			(fill no)
			(layer "B.CrtYd")
		)
		(fp_line
			(start -0.508 0.3048)
			(end -0.508 -0.3048)
			(stroke
				(width 0.1)
				(type default)
			)
			(layer "B.Fab")
		)
		(fp_line
			(start 0.508 0.3048)
			(end -0.508 0.3048)
			(stroke
				(width 0.1)
				(type default)
			)
			(layer "B.Fab")
		)
		(fp_line
			(start -0.508 -0.3048)
			(end 0.508 -0.3048)
			(stroke
				(width 0.1)
				(type default)
			)
			(layer "B.Fab")
		)
		(fp_line
			(start 0.508 -0.3048)
			(end 0.508 0.3048)
			(stroke
				(width 0.1)
				(type default)
			)
			(layer "B.Fab")
		)
		(pad "1" smd rect
			(at 0.5334 0 90)
			(size 0.7112 0.6096)
			(layers "B.Cu" "B.Mask" "B.Paste")
			(net "FPGA_DONE")
		)
		(pad "2" smd rect
			(at -0.5334 0 90)
			(size 0.7112 0.6096)
			(layers "B.Cu" "B.Mask" "B.Paste")
			(net "XP3R3V_FPGA")
		)
		(zone
			(layer "B.Cu")
			(hatch none 0.5)
			(connect_pads
				(clearance 0)
			)
			(min_thickness 0.25)
			(keepout
				(tracks allowed)
				(vias not_allowed)
				(pads allowed)
				(copperpour not_allowed)
				(footprints allowed)
			)
			(placement
				(enabled no)
				(sheetname "")
			)
			(fill
				(thermal_gap 0.5)
				(thermal_bridge_width 0.5)
				(island_removal_mode 0)
			)
			(polygon
				(pts
					(xy 133.6294 -106.096054) (xy 134.239 -106.096054) (xy 134.239 -106.248454) (xy 133.6294 -106.248454)
				)
			)
		)
	)
	(footprint ""
		(layer "B.Cu")
		(at 111.125 -98.171)
		(property "Reference" "R319"
			(at 0.254 1.81737 0)
			(unlocked yes)
			(layer "B.SilkS")
			(effects
				(font
					(size 0.7874 0.5842)
					(thickness 0.1524)
				)
				(justify mirror)
			)
		)
		(property "Value" "VAL*"
			(at -0.02032 2.13233 0)
			(unlocked yes)
			(layer "B.Fab")
			(hide yes)
			(effects
				(font
					(size 0.7874 0.5842)
					(thickness 0.1524)
				)
				(justify mirror)
			)
		)
		(property "Tolerance" "TOL*"
			(at -0.044704 3.05435 0)
			(unlocked yes)
			(layer "Cmts.User")
			(hide yes)
			(effects
				(font
					(size 0.7874 0.5842)
					(thickness 0.1524)
				)
				(justify mirror)
			)
		)
		(property "User Part Number" "PARTNUM*"
			(at -0.02032 4.024884 0)
			(unlocked yes)
			(layer "Cmts.User")
			(hide yes)
			(effects
				(font
					(size 0.7874 0.5842)
					(thickness 0.1524)
				)
				(justify mirror)
			)
		)
		(property "Device Type" "RESISTOR-G155-133R0-01,33OHM,1%"
			(at -0.008382 1.210564 0)
			(unlocked yes)
			(layer "B.Fab")
			(hide yes)
			(effects
				(font
					(size 0.7874 0.5842)
					(thickness 0.1524)
				)
				(justify mirror)
			)
		)
		(duplicate_pad_numbers_are_jumpers no)
		(fp_line
			(start -1.143 -0.5588)
			(end 1.143 -0.5588)
			(stroke
				(width 0.1)
				(type default)
			)
			(layer "B.SilkS")
		)
		(fp_line
			(start -1.143 0.5588)
			(end -1.143 -0.5588)
			(stroke
				(width 0.1)
				(type default)
			)
			(layer "B.SilkS")
		)
		(fp_line
			(start 1.143 -0.5588)
			(end 1.143 0.5588)
			(stroke
				(width 0.1)
				(type default)
			)
			(layer "B.SilkS")
		)
		(fp_line
			(start 1.143 0.5588)
			(end -1.143 0.5588)
			(stroke
				(width 0.1)
				(type default)
			)
			(layer "B.SilkS")
		)
		(fp_poly
			(pts
				(xy 1.143 0.5588) (xy -1.143 0.5588) (xy -1.143 -0.5588) (xy 1.143 -0.5588)
			)
			(stroke
				(width 0)
				(type default)
			)
			(fill no)
			(layer "B.CrtYd")
		)
		(fp_line
			(start -0.508 -0.3048)
			(end 0.508 -0.3048)
			(stroke
				(width 0.1)
				(type default)
			)
			(layer "B.Fab")
		)
		(fp_line
			(start -0.508 0.3048)
			(end -0.508 -0.3048)
			(stroke
				(width 0.1)
				(type default)
			)
			(layer "B.Fab")
		)
		(fp_line
			(start 0.508 -0.3048)
			(end 0.508 0.3048)
			(stroke
				(width 0.1)
				(type default)
			)
			(layer "B.Fab")
		)
		(fp_line
			(start 0.508 0.3048)
			(end -0.508 0.3048)
			(stroke
				(width 0.1)
				(type default)
			)
			(layer "B.Fab")
		)
		(pad "1" smd rect
			(at 0.5334 0 180)
			(size 0.7112 0.6096)
			(layers "B.Cu" "B.Mask" "B.Paste")
			(net "FPGA_OUT_RGB_LED_SHUTDOWN_N")
		)
		(pad "2" smd rect
			(at -0.5334 0 180)
			(size 0.7112 0.6096)
			(layers "B.Cu" "B.Mask" "B.Paste")
			(net "RGB_LED_SHUTDOWN_N")
		)
		(zone
			(layer "B.Cu")
			(hatch none 0.5)
			(connect_pads
				(clearance 0)
			)
			(min_thickness 0.25)
			(keepout
				(tracks allowed)
				(vias not_allowed)
				(pads allowed)
				(copperpour not_allowed)
				(footprints allowed)
			)
			(placement
				(enabled no)
				(sheetname "")
			)
			(fill
				(thermal_gap 0.5)
				(thermal_bridge_width 0.5)
				(island_removal_mode 0)
			)
			(polygon
				(pts
					(xy 111.2012 -97.8662) (xy 111.2012 -98.4758) (xy 111.0488 -98.4758) (xy 111.0488 -97.8662)
				)
			)
		)
		(zone
			(layer "B.Cu")
			(hatch none 0.5)
			(connect_pads
				(clearance 0)
			)
			(min_thickness 0.25)
			(keepout
				(tracks not_allowed)
				(vias allowed)
				(pads allowed)
				(copperpour not_allowed)
				(footprints allowed)
			)
			(placement
				(enabled no)
				(sheetname "")
			)
			(fill
				(thermal_gap 0.5)
				(thermal_bridge_width 0.5)
				(island_removal_mode 0)
			)
			(polygon
				(pts
					(xy 111.2012 -97.8662) (xy 111.2012 -98.4758) (xy 111.0488 -98.4758) (xy 111.0488 -97.8662)
				)
			)
		)
	)
	(footprint ""
		(layer "B.Cu")
		(at 53.467 -87.122 90)
		(property "Reference" "R454"
			(at 5.16763 0.635 0)
			(unlocked yes)
			(layer "B.SilkS")
			(effects
				(font
					(size 0.7874 0.5842)
					(thickness 0.1524)
				)
				(justify mirror)
			)
		)
		(property "Value" "VAL*"
			(at -0.0508 2.245106 90)
			(unlocked yes)
			(layer "B.Fab")
			(hide yes)
			(effects
				(font
					(size 0.7874 0.5842)
					(thickness 0.1524)
				)
				(justify mirror)
			)
		)
		(property "User Part Number" "PARTNUM*"
			(at -0.0762 4.302506 90)
			(unlocked yes)
			(layer "Cmts.User")
			(hide yes)
			(effects
				(font
					(size 0.7874 0.5842)
					(thickness 0.1524)
				)
				(justify mirror)
			)
		)
		(property "Device Type" "RESISTOR-G155-02101-01,2.1KOHMA"
			(at -0.0762 1.254506 90)
			(unlocked yes)
			(layer "B.Fab")
			(hide yes)
			(effects
				(font
					(size 0.7874 0.5842)
					(thickness 0.1524)
				)
				(justify mirror)
			)
		)
		(property "Tolerance" "TOL*"
			(at -0.0508 3.261106 90)
			(unlocked yes)
			(layer "Cmts.User")
			(hide yes)
			(effects
				(font
					(size 0.7874 0.5842)
					(thickness 0.1524)
				)
				(justify mirror)
			)
		)
		(duplicate_pad_numbers_are_jumpers no)
		(fp_line
			(start 1.143 -0.5588)
			(end 1.143 0.5588)
			(stroke
				(width 0.1)
				(type default)
			)
			(layer "B.SilkS")
		)
		(fp_line
			(start -1.143 -0.5588)
			(end 1.143 -0.5588)
			(stroke
				(width 0.1)
				(type default)
			)
			(layer "B.SilkS")
		)
		(fp_line
			(start 1.143 0.5588)
			(end -1.143 0.5588)
			(stroke
				(width 0.1)
				(type default)
			)
			(layer "B.SilkS")
		)
		(fp_line
			(start -1.143 0.5588)
			(end -1.143 -0.5588)
			(stroke
				(width 0.1)
				(type default)
			)
			(layer "B.SilkS")
		)
		(fp_poly
			(pts
				(xy 1.143 0.5588) (xy -1.143 0.5588) (xy -1.143 -0.5588) (xy 1.143 -0.5588)
			)
			(stroke
				(width 0)
				(type default)
			)
			(fill no)
			(layer "B.CrtYd")
		)
		(fp_line
			(start 0.508 -0.3048)
			(end 0.508 0.3048)
			(stroke
				(width 0.1)
				(type default)
			)
			(layer "B.Fab")
		)
		(fp_line
			(start -0.508 -0.3048)
			(end 0.508 -0.3048)
			(stroke
				(width 0.1)
				(type default)
			)
			(layer "B.Fab")
		)
		(fp_line
			(start 0.508 0.3048)
			(end -0.508 0.3048)
			(stroke
				(width 0.1)
				(type default)
			)
			(layer "B.Fab")
		)
		(fp_line
			(start -0.508 0.3048)
			(end -0.508 -0.3048)
			(stroke
				(width 0.1)
				(type default)
			)
			(layer "B.Fab")
		)
		(pad "1" smd rect
			(at 0.5334 0 270)
			(size 0.7112 0.6096)
			(layers "B.Cu" "B.Mask" "B.Paste")
			(net "FTDI_EE_DAT")
		)
		(pad "2" smd rect
			(at -0.5334 0 270)
			(size 0.7112 0.6096)
			(layers "B.Cu" "B.Mask" "B.Paste")
			(net "FTDI_EE_DO")
		)
		(zone
			(layer "B.Cu")
			(hatch none 0.5)
			(connect_pads
				(clearance 0)
			)
			(min_thickness 0.25)
			(keepout
				(tracks allowed)
				(vias not_allowed)
				(pads allowed)
				(copperpour not_allowed)
				(footprints allowed)
			)
			(placement
				(enabled no)
				(sheetname "")
			)
			(fill
				(thermal_gap 0.5)
				(thermal_bridge_width 0.5)
				(island_removal_mode 0)
			)
			(polygon
				(pts
					(xy 53.7718 -87.1982) (xy 53.1622 -87.1982) (xy 53.1622 -87.0458) (xy 53.7718 -87.0458)
				)
			)
		)
		(zone
			(layer "B.Cu")
			(hatch none 0.5)
			(connect_pads
				(clearance 0)
			)
			(min_thickness 0.25)
			(keepout
				(tracks not_allowed)
				(vias allowed)
				(pads allowed)
				(copperpour not_allowed)
				(footprints allowed)
			)
			(placement
				(enabled no)
				(sheetname "")
			)
			(fill
				(thermal_gap 0.5)
				(thermal_bridge_width 0.5)
				(island_removal_mode 0)
			)
			(polygon
				(pts
					(xy 53.7718 -87.1982) (xy 53.1622 -87.1982) (xy 53.1622 -87.0458) (xy 53.7718 -87.0458)
				)
			)
		)
	)
	(footprint ""
		(layer "B.Cu")
		(at 52.9082 -74.9808 90)
		(property "Reference" "R409"
			(at 4.064 0.08763 270)
			(unlocked yes)
			(layer "B.SilkS")
			(effects
				(font
					(size 0.7874 0.5842)
					(thickness 0.1524)
				)
				(justify mirror)
			)
		)
		(property "Value" "VAL*"
			(at -0.02032 2.13233 90)
			(unlocked yes)
			(layer "B.Fab")
			(hide yes)
			(effects
				(font
					(size 0.7874 0.5842)
					(thickness 0.1524)
				)
				(justify mirror)
			)
		)
		(property "Device Type" "RESISTOR-G155-11001-01,1KOHM,1%"
			(at -0.008382 1.210564 90)
			(unlocked yes)
			(layer "B.Fab")
			(hide yes)
			(effects
				(font
					(size 0.7874 0.5842)
					(thickness 0.1524)
				)
				(justify mirror)
			)
		)
		(property "User Part Number" "PARTNUM*"
			(at -0.02032 4.024884 90)
			(unlocked yes)
			(layer "Cmts.User")
			(hide yes)
			(effects
				(font
					(size 0.7874 0.5842)
					(thickness 0.1524)
				)
				(justify mirror)
			)
		)
		(property "Tolerance" "TOL*"
			(at -0.044704 3.05435 90)
			(unlocked yes)
			(layer "Cmts.User")
			(hide yes)
			(effects
				(font
					(size 0.7874 0.5842)
					(thickness 0.1524)
				)
				(justify mirror)
			)
		)
		(duplicate_pad_numbers_are_jumpers no)
		(fp_line
			(start 1.143 -0.5588)
			(end 1.143 0.5588)
			(stroke
				(width 0.1)
				(type default)
			)
			(layer "B.SilkS")
		)
		(fp_line
			(start -1.143 -0.5588)
			(end 1.143 -0.5588)
			(stroke
				(width 0.1)
				(type default)
			)
			(layer "B.SilkS")
		)
		(fp_line
			(start 1.143 0.5588)
			(end -1.143 0.5588)
			(stroke
				(width 0.1)
				(type default)
			)
			(layer "B.SilkS")
		)
		(fp_line
			(start -1.143 0.5588)
			(end -1.143 -0.5588)
			(stroke
				(width 0.1)
				(type default)
			)
			(layer "B.SilkS")
		)
		(fp_rect
			(start 1.143 0.5588)
			(end -1.143 -0.5588)
			(stroke
				(width 0)
				(type default)
			)
			(fill no)
			(layer "B.CrtYd")
		)
		(fp_line
			(start 0.508 -0.3048)
			(end 0.508 0.3048)
			(stroke
				(width 0.1)
				(type default)
			)
			(layer "B.Fab")
		)
		(fp_line
			(start -0.508 -0.3048)
			(end 0.508 -0.3048)
			(stroke
				(width 0.1)
				(type default)
			)
			(layer "B.Fab")
		)
		(fp_line
			(start 0.508 0.3048)
			(end -0.508 0.3048)
			(stroke
				(width 0.1)
				(type default)
			)
			(layer "B.Fab")
		)
		(fp_line
			(start -0.508 0.3048)
			(end -0.508 -0.3048)
			(stroke
				(width 0.1)
				(type default)
			)
			(layer "B.Fab")
		)
		(pad "1" smd rect
			(at 0.5334 0 270)
			(size 0.7112 0.6096)
			(layers "B.Cu" "B.Mask" "B.Paste")
			(net "UNNAMED_6_LM75BDPTSSOP8_I59_A2")
		)
		(pad "2" smd rect
			(at -0.5334 0 270)
			(size 0.7112 0.6096)
			(layers "B.Cu" "B.Mask" "B.Paste")
			(net "SG")
		)
		(zone
			(layer "B.Cu")
			(hatch none 0.5)
			(connect_pads
				(clearance 0)
			)
			(min_thickness 0.25)
			(keepout
				(tracks allowed)
				(vias not_allowed)
				(pads allowed)
				(copperpour not_allowed)
				(footprints allowed)
			)
			(placement
				(enabled no)
				(sheetname "")
			)
			(fill
				(thermal_gap 0.5)
				(thermal_bridge_width 0.5)
				(island_removal_mode 0)
			)
			(polygon
				(pts
					(xy 53.213 -75.057) (xy 52.6034 -75.057) (xy 52.6034 -74.9046) (xy 53.213 -74.9046)
				)
			)
		)
		(zone
			(layer "B.Cu")
			(hatch none 0.5)
			(connect_pads
				(clearance 0)
			)
			(min_thickness 0.25)
			(keepout
				(tracks not_allowed)
				(vias allowed)
				(pads allowed)
				(copperpour not_allowed)
				(footprints allowed)
			)
			(placement
				(enabled no)
				(sheetname "")
			)
			(fill
				(thermal_gap 0.5)
				(thermal_bridge_width 0.5)
				(island_removal_mode 0)
			)
			(polygon
				(pts
					(xy 53.213 -75.057) (xy 52.6034 -75.057) (xy 52.6034 -74.9046) (xy 53.213 -74.9046)
				)
			)
		)
	)
	(footprint ""
		(layer "B.Cu")
		(at 80.899 -96.266 90)
		(property "Reference" "R39"
			(at -0.127 -1.69037 270)
			(unlocked yes)
			(layer "B.SilkS")
			(effects
				(font
					(size 0.7874 0.5842)
					(thickness 0.1524)
				)
				(justify mirror)
			)
		)
		(property "Value" "VAL*"
			(at -0.0508 3.159506 90)
			(unlocked yes)
			(layer "B.Fab")
			(hide yes)
			(effects
				(font
					(size 0.7874 0.5842)
					(thickness 0.1524)
				)
				(justify mirror)
			)
		)
		(property "Device Type" "RESISTOR-G157-12R20-01,2.2OHM,A"
			(at 0 2.194306 90)
			(unlocked yes)
			(layer "B.Fab")
			(hide yes)
			(effects
				(font
					(size 0.7874 0.5842)
					(thickness 0.1524)
				)
				(justify mirror)
			)
		)
		(property "User Part Number" "PARTNUM*"
			(at -0.0508 5.089906 90)
			(unlocked yes)
			(layer "Cmts.User")
			(hide yes)
			(effects
				(font
					(size 0.7874 0.5842)
					(thickness 0.1524)
				)
				(justify mirror)
			)
		)
		(property "Tolerance" "TOL*"
			(at -0.0508 4.124706 90)
			(unlocked yes)
			(layer "Cmts.User")
			(hide yes)
			(effects
				(font
					(size 0.7874 0.5842)
					(thickness 0.1524)
				)
				(justify mirror)
			)
		)
		(duplicate_pad_numbers_are_jumpers no)
		(fp_line
			(start 1.5748 -0.9398)
			(end 1.5748 0.9398)
			(stroke
				(width 0.1)
				(type default)
			)
			(layer "B.SilkS")
		)
		(fp_line
			(start -1.5748 -0.9398)
			(end 1.5748 -0.9398)
			(stroke
				(width 0.1)
				(type default)
			)
			(layer "B.SilkS")
		)
		(fp_line
			(start 1.5748 0.9398)
			(end -1.5748 0.9398)
			(stroke
				(width 0.1)
				(type default)
			)
			(layer "B.SilkS")
		)
		(fp_line
			(start -1.5748 0.9398)
			(end -1.5748 -0.9398)
			(stroke
				(width 0.1)
				(type default)
			)
			(layer "B.SilkS")
		)
		(fp_rect
			(start -1.5748 0.9398)
			(end 1.5748 -0.9398)
			(stroke
				(width 0)
				(type default)
			)
			(fill no)
			(layer "B.CrtYd")
		)
		(fp_line
			(start 1.016 -0.635)
			(end 1.016 0.635)
			(stroke
				(width 0.1)
				(type default)
			)
			(layer "B.Fab")
		)
		(fp_line
			(start -1.016 -0.635)
			(end 1.016 -0.635)
			(stroke
				(width 0.1)
				(type default)
			)
			(layer "B.Fab")
		)
		(fp_line
			(start 1.016 0.635)
			(end -1.016 0.635)
			(stroke
				(width 0.1)
				(type default)
			)
			(layer "B.Fab")
		)
		(fp_line
			(start -1.016 0.635)
			(end -1.016 -0.635)
			(stroke
				(width 0.1)
				(type default)
			)
			(layer "B.Fab")
		)
		(pad "1" smd rect
			(at 0.8382 0 270)
			(size 0.9652 1.3716)
			(layers "B.Cu" "B.Mask" "B.Paste")
			(net "UNNAMED_517_CAPACITOR_I29_2")
		)
		(pad "2" smd rect
			(at -0.8382 0 270)
			(size 0.9652 1.3716)
			(layers "B.Cu" "B.Mask" "B.Paste")
			(net "SG")
		)
		(zone
			(layer "B.Cu")
			(hatch none 0.5)
			(connect_pads
				(clearance 0)
			)
			(min_thickness 0.25)
			(keepout
				(tracks allowed)
				(vias not_allowed)
				(pads allowed)
				(copperpour not_allowed)
				(footprints allowed)
			)
			(placement
				(enabled no)
				(sheetname "")
			)
			(fill
				(thermal_gap 0.5)
				(thermal_bridge_width 0.5)
				(island_removal_mode 0)
			)
			(polygon
				(pts
					(xy 81.534 -96.0374) (xy 81.534 -96.4946) (xy 80.264 -96.4946) (xy 80.264 -96.0374)
				)
			)
		)
	)
	(footprint ""
		(layer "B.Cu")
		(at 85.09 -73.279 -90)
		(property "Reference" "R363"
			(at 3.556 0.03937 270)
			(unlocked yes)
			(layer "B.SilkS")
			(effects
				(font
					(size 0.7874 0.5842)
					(thickness 0.1524)
				)
				(justify mirror)
			)
		)
		(property "Value" "VAL*"
			(at -0.02032 2.13233 270)
			(unlocked yes)
			(layer "B.Fab")
			(hide yes)
			(effects
				(font
					(size 0.7874 0.5842)
					(thickness 0.1524)
				)
				(justify mirror)
			)
		)
		(property "Tolerance" "TOL*"
			(at -0.044704 3.05435 270)
			(unlocked yes)
			(layer "Cmts.User")
			(hide yes)
			(effects
				(font
					(size 0.7874 0.5842)
					(thickness 0.1524)
				)
				(justify mirror)
			)
		)
		(property "User Part Number" "PARTNUM*"
			(at -0.02032 4.024884 270)
			(unlocked yes)
			(layer "Cmts.User")
			(hide yes)
			(effects
				(font
					(size 0.7874 0.5842)
					(thickness 0.1524)
				)
				(justify mirror)
			)
		)
		(property "Device Type" "RESISTOR-G155-133R0-01,33OHM,1%"
			(at -0.008382 1.210564 270)
			(unlocked yes)
			(layer "B.Fab")
			(hide yes)
			(effects
				(font
					(size 0.7874 0.5842)
					(thickness 0.1524)
				)
				(justify mirror)
			)
		)
		(duplicate_pad_numbers_are_jumpers no)
		(fp_line
			(start -1.143 0.5588)
			(end -1.143 -0.5588)
			(stroke
				(width 0.1)
				(type default)
			)
			(layer "B.SilkS")
		)
		(fp_line
			(start 1.143 0.5588)
			(end -1.143 0.5588)
			(stroke
				(width 0.1)
				(type default)
			)
			(layer "B.SilkS")
		)
		(fp_line
			(start -1.143 -0.5588)
			(end 1.143 -0.5588)
			(stroke
				(width 0.1)
				(type default)
			)
			(layer "B.SilkS")
		)
		(fp_line
			(start 1.143 -0.5588)
			(end 1.143 0.5588)
			(stroke
				(width 0.1)
				(type default)
			)
			(layer "B.SilkS")
		)
		(fp_rect
			(start 1.143 0.5588)
			(end -1.143 -0.5588)
			(stroke
				(width 0)
				(type default)
			)
			(fill no)
			(layer "B.CrtYd")
		)
		(fp_line
			(start -0.508 0.3048)
			(end -0.508 -0.3048)
			(stroke
				(width 0.1)
				(type default)
			)
			(layer "B.Fab")
		)
		(fp_line
			(start 0.508 0.3048)
			(end -0.508 0.3048)
			(stroke
				(width 0.1)
				(type default)
			)
			(layer "B.Fab")
		)
		(fp_line
			(start -0.508 -0.3048)
			(end 0.508 -0.3048)
			(stroke
				(width 0.1)
				(type default)
			)
			(layer "B.Fab")
		)
		(fp_line
			(start 0.508 -0.3048)
			(end 0.508 0.3048)
			(stroke
				(width 0.1)
				(type default)
			)
			(layer "B.Fab")
		)
		(pad "1" smd rect
			(at 0.5334 0 90)
			(size 0.7112 0.6096)
			(layers "B.Cu" "B.Mask" "B.Paste")
			(net "R_BNO080_EVN_SCL")
		)
		(pad "2" smd rect
			(at -0.5334 0 90)
			(size 0.7112 0.6096)
			(layers "B.Cu" "B.Mask" "B.Paste")
			(net "BNO080_EVN_SCL")
		)
		(zone
			(layer "B.Cu")
			(hatch none 0.5)
			(connect_pads
				(clearance 0)
			)
			(min_thickness 0.25)
			(keepout
				(tracks allowed)
				(vias not_allowed)
				(pads allowed)
				(copperpour not_allowed)
				(footprints allowed)
			)
			(placement
				(enabled no)
				(sheetname "")
			)
			(fill
				(thermal_gap 0.5)
				(thermal_bridge_width 0.5)
				(island_removal_mode 0)
			)
			(polygon
				(pts
					(xy 84.7852 -73.2028) (xy 85.3948 -73.2028) (xy 85.3948 -73.3552) (xy 84.7852 -73.3552)
				)
			)
		)
		(zone
			(layer "B.Cu")
			(hatch none 0.5)
			(connect_pads
				(clearance 0)
			)
			(min_thickness 0.25)
			(keepout
				(tracks not_allowed)
				(vias allowed)
				(pads allowed)
				(copperpour not_allowed)
				(footprints allowed)
			)
			(placement
				(enabled no)
				(sheetname "")
			)
			(fill
				(thermal_gap 0.5)
				(thermal_bridge_width 0.5)
				(island_removal_mode 0)
			)
			(polygon
				(pts
					(xy 84.7852 -73.2028) (xy 85.3948 -73.2028) (xy 85.3948 -73.3552) (xy 84.7852 -73.3552)
				)
			)
		)
	)
	(footprint ""
		(layer "B.Cu")
		(at 76.454 -55.372 90)
		(property "Reference" "Q2"
			(at 0 3.77063 270)
			(unlocked yes)
			(layer "B.SilkS")
			(effects
				(font
					(size 0.7874 0.5842)
					(thickness 0.1524)
				)
				(justify mirror)
			)
		)
		(property "Value" ""
			(at 0 0 90)
			(layer "B.Fab")
			(effects
				(font
					(size 1.27 1.27)
				)
				(justify mirror)
			)
		)
		(property "User Part Number" "PARTNUM*"
			(at 0.074676 4.841748 90)
			(unlocked yes)
			(layer "Cmts.User")
			(hide yes)
			(effects
				(font
					(size 0.7874 0.5842)
					(thickness 0.000001)
				)
				(justify mirror)
			)
		)
		(property "Device Type" "POWERMOS_3P_NCH_V1-G121-10200-A"
			(at 0.051562 3.91414 90)
			(unlocked yes)
			(layer "B.Fab")
			(hide yes)
			(effects
				(font
					(size 0.7874 0.5842)
					(thickness 0.000001)
				)
				(justify mirror)
			)
		)
		(duplicate_pad_numbers_are_jumpers no)
		(fp_line
			(start 0.7493 -2.0574)
			(end -0.7493 -2.0574)
			(stroke
				(width 0.1)
				(type default)
			)
			(layer "B.SilkS")
		)
		(fp_line
			(start -0.7493 -2.0574)
			(end -0.7493 -0.9144)
			(stroke
				(width 0.1)
				(type default)
			)
			(layer "B.SilkS")
		)
		(fp_line
			(start 1.7018 -0.9144)
			(end 0.7493 -0.9144)
			(stroke
				(width 0.1)
				(type default)
			)
			(layer "B.SilkS")
		)
		(fp_line
			(start 0.7493 -0.9144)
			(end 0.7493 -2.0574)
			(stroke
				(width 0.1)
				(type default)
			)
			(layer "B.SilkS")
		)
		(fp_line
			(start -0.7493 -0.9144)
			(end -1.7018 -0.9144)
			(stroke
				(width 0.1)
				(type default)
			)
			(layer "B.SilkS")
		)
		(fp_line
			(start -1.7018 -0.9144)
			(end -1.7018 2.0574)
			(stroke
				(width 0.1)
				(type default)
			)
			(layer "B.SilkS")
		)
		(fp_line
			(start 0.1905 0.9144)
			(end 0.1905 2.0574)
			(stroke
				(width 0.1)
				(type default)
			)
			(layer "B.SilkS")
		)
		(fp_line
			(start -0.1905 0.9144)
			(end 0.1905 0.9144)
			(stroke
				(width 0.1)
				(type default)
			)
			(layer "B.SilkS")
		)
		(fp_line
			(start 1.7018 2.0574)
			(end 1.7018 -0.9144)
			(stroke
				(width 0.1)
				(type default)
			)
			(layer "B.SilkS")
		)
		(fp_line
			(start 0.1905 2.0574)
			(end 1.7018 2.0574)
			(stroke
				(width 0.1)
				(type default)
			)
			(layer "B.SilkS")
		)
		(fp_line
			(start -0.1905 2.0574)
			(end -0.1905 0.9144)
			(stroke
				(width 0.1)
				(type default)
			)
			(layer "B.SilkS")
		)
		(fp_line
			(start -1.7018 2.0574)
			(end -0.1905 2.0574)
			(stroke
				(width 0.1)
				(type default)
			)
			(layer "B.SilkS")
		)
		(fp_poly
			(pts
				(arc
					(start 1.27 2.921)
					(mid 1.27 2.159)
					(end 1.27 2.921)
				)
			)
			(stroke
				(width 0)
				(type default)
			)
			(fill yes)
			(layer "B.SilkS")
		)
		(fp_poly
			(pts
				(xy 1.7018 2.0828) (xy 1.7018 -0.9144) (xy 0.762 -0.9144) (xy 0.762 -2.0574) (xy -0.762 -2.0574)
				(xy -0.762 -0.9144) (xy -1.7018 -0.9144) (xy -1.7018 2.0828)
			)
			(stroke
				(width 0)
				(type default)
			)
			(fill no)
			(layer "B.CrtYd")
		)
		(fp_line
			(start 0.2286 -1.143)
			(end -0.2286 -1.143)
			(stroke
				(width 0.1)
				(type default)
			)
			(layer "B.Fab")
		)
		(fp_line
			(start -0.2286 -1.143)
			(end -0.2286 -0.6604)
			(stroke
				(width 0.1)
				(type default)
			)
			(layer "B.Fab")
		)
		(fp_line
			(start 0.2286 -0.9144)
			(end -0.2286 -0.9144)
			(stroke
				(width 0.1)
				(type default)
			)
			(layer "B.Fab")
		)
		(fp_line
			(start 1.4478 -0.6604)
			(end -1.4478 -0.6604)
			(stroke
				(width 0.1)
				(type default)
			)
			(layer "B.Fab")
		)
		(fp_line
			(start 1.4478 -0.6604)
			(end 1.3716 -0.5842)
			(stroke
				(width 0.1)
				(type default)
			)
			(layer "B.Fab")
		)
		(fp_line
			(start 0.2286 -0.6604)
			(end 0.2286 -1.143)
			(stroke
				(width 0.1)
				(type default)
			)
			(layer "B.Fab")
		)
		(fp_line
			(start -0.2286 -0.6604)
			(end 0.2286 -0.6604)
			(stroke
				(width 0.1)
				(type default)
			)
			(layer "B.Fab")
		)
		(fp_line
			(start -1.4478 -0.6604)
			(end -1.4478 0.6604)
			(stroke
				(width 0.1)
				(type default)
			)
			(layer "B.Fab")
		)
		(fp_line
			(start 1.3716 -0.5842)
			(end -1.3716 -0.5842)
			(stroke
				(width 0.1)
				(type default)
			)
			(layer "B.Fab")
		)
		(fp_line
			(start -1.3716 -0.5842)
			(end -1.4478 -0.6604)
			(stroke
				(width 0.1)
				(type default)
			)
			(layer "B.Fab")
		)
		(fp_line
			(start -1.3716 -0.5842)
			(end -1.3716 0.5842)
			(stroke
				(width 0.1)
				(type default)
			)
			(layer "B.Fab")
		)
		(fp_line
			(start 1.3716 0.5842)
			(end 1.3716 -0.5842)
			(stroke
				(width 0.1)
				(type default)
			)
			(layer "B.Fab")
		)
		(fp_line
			(start -1.3716 0.5842)
			(end 1.3716 0.5842)
			(stroke
				(width 0.1)
				(type default)
			)
			(layer "B.Fab")
		)
		(fp_line
			(start -1.3716 0.5842)
			(end -1.4478 0.6604)
			(stroke
				(width 0.1)
				(type default)
			)
			(layer "B.Fab")
		)
		(fp_line
			(start 1.4478 0.6604)
			(end 1.4478 -0.6604)
			(stroke
				(width 0.1)
				(type default)
			)
			(layer "B.Fab")
		)
		(fp_line
			(start 1.4478 0.6604)
			(end 1.3716 0.5842)
			(stroke
				(width 0.1)
				(type default)
			)
			(layer "B.Fab")
		)
		(fp_line
			(start 1.1684 0.6604)
			(end 0.7112 0.6604)
			(stroke
				(width 0.1)
				(type default)
			)
			(layer "B.Fab")
		)
		(fp_line
			(start 0.7112 0.6604)
			(end 0.7112 1.143)
			(stroke
				(width 0.1)
				(type default)
			)
			(layer "B.Fab")
		)
		(fp_line
			(start -0.7112 0.6604)
			(end -1.1684 0.6604)
			(stroke
				(width 0.1)
				(type default)
			)
			(layer "B.Fab")
		)
		(fp_line
			(start -1.1684 0.6604)
			(end -1.1684 1.143)
			(stroke
				(width 0.1)
				(type default)
			)
			(layer "B.Fab")
		)
		(fp_line
			(start -1.4478 0.6604)
			(end 1.4478 0.6604)
			(stroke
				(width 0.1)
				(type default)
			)
			(layer "B.Fab")
		)
		(fp_line
			(start 1.1684 0.9144)
			(end 0.7112 0.9144)
			(stroke
				(width 0.1)
				(type default)
			)
			(layer "B.Fab")
		)
		(fp_line
			(start -0.7112 0.9144)
			(end -1.1684 0.9144)
			(stroke
				(width 0.1)
				(type default)
			)
			(layer "B.Fab")
		)
		(fp_line
			(start 1.1684 1.143)
			(end 1.1684 0.6604)
			(stroke
				(width 0.1)
				(type default)
			)
			(layer "B.Fab")
		)
		(fp_line
			(start 0.7112 1.143)
			(end 1.1684 1.143)
			(stroke
				(width 0.1)
				(type default)
			)
			(layer "B.Fab")
		)
		(fp_line
			(start -0.7112 1.143)
			(end -0.7112 0.6604)
			(stroke
				(width 0.1)
				(type default)
			)
			(layer "B.Fab")
		)
		(fp_line
			(start -1.1684 1.143)
			(end -0.7112 1.143)
			(stroke
				(width 0.1)
				(type default)
			)
			(layer "B.Fab")
		)
		(fp_poly
			(pts
				(arc
					(start 1.016 2.794)
					(mid 1.016 2.032)
					(end 1.016 2.794)
				)
			)
			(stroke
				(width 0)
				(type default)
			)
			(fill yes)
			(layer "B.Fab")
		)
		(fp_text user "2"
			(at -1.42875 2.667 0)
			(unlocked yes)
			(layer "B.SilkS")
			(effects
				(font
					(size 0.635 0.4064)
					(thickness 0.1524)
				)
				(justify mirror)
			)
		)
		(fp_text user "2"
			(at -1.05537 2.54 0)
			(unlocked yes)
			(layer "B.Fab")
			(effects
				(font
					(size 0.7874 0.5842)
					(thickness 0.1524)
				)
				(justify mirror)
			)
		)
		(pad "1" smd rect
			(at 0.9398 1.1049 270)
			(size 0.9906 1.397)
			(layers "B.Cu" "B.Mask" "B.Paste")
			(net "USB_PWR_EN")
		)
		(pad "2" smd rect
			(at -0.9398 1.1049 270)
			(size 0.9906 1.397)
			(layers "B.Cu" "B.Mask" "B.Paste")
			(net "SG")
		)
		(pad "3" smd rect
			(at 0 -1.1049 270)
			(size 0.9906 1.397)
			(layers "B.Cu" "B.Mask" "B.Paste")
			(net "UNNAMED_527_POWERMOS3PNCHV1_I23")
		)
	)
	(footprint ""
		(layer "B.Cu")
		(at 82.423 -73.152 90)
		(property "Reference" "C62"
			(at -0.508 1.23063 270)
			(unlocked yes)
			(layer "B.SilkS")
			(effects
				(font
					(size 0.7874 0.5842)
					(thickness 0.1524)
				)
				(justify mirror)
			)
		)
		(property "Value" "VAL*"
			(at -0.0762 2.067306 90)
			(unlocked yes)
			(layer "B.Fab")
			(hide yes)
			(effects
				(font
					(size 0.7874 0.5842)
					(thickness 0.1524)
				)
				(justify mirror)
			)
		)
		(property "Tolerance" "TOL*"
			(at -0.0762 3.032506 90)
			(unlocked yes)
			(layer "Cmts.User")
			(hide yes)
			(effects
				(font
					(size 0.7874 0.5842)
					(thickness 0.1524)
				)
				(justify mirror)
			)
		)
		(property "User Part Number" "PARTNUM*"
			(at -0.1016 4.023106 90)
			(unlocked yes)
			(layer "Cmts.User")
			(hide yes)
			(effects
				(font
					(size 0.7874 0.5842)
					(thickness 0.1524)
				)
				(justify mirror)
			)
		)
		(property "Device Type" "CAPACITOR-G105-0B104-EK,0.1UF,A"
			(at -0.0508 1.127506 90)
			(unlocked yes)
			(layer "B.Fab")
			(hide yes)
			(effects
				(font
					(size 0.7874 0.5842)
					(thickness 0.1524)
				)
				(justify mirror)
			)
		)
		(duplicate_pad_numbers_are_jumpers no)
		(fp_line
			(start 1.143 -0.5588)
			(end 1.143 0.5588)
			(stroke
				(width 0.1)
				(type default)
			)
			(layer "B.SilkS")
		)
		(fp_line
			(start -1.143 -0.5588)
			(end 1.143 -0.5588)
			(stroke
				(width 0.1)
				(type default)
			)
			(layer "B.SilkS")
		)
		(fp_line
			(start 1.143 0.5588)
			(end -1.143 0.5588)
			(stroke
				(width 0.1)
				(type default)
			)
			(layer "B.SilkS")
		)
		(fp_line
			(start -1.143 0.5588)
			(end -1.143 -0.5588)
			(stroke
				(width 0.1)
				(type default)
			)
			(layer "B.SilkS")
		)
		(fp_rect
			(start -1.143 -0.5588)
			(end 1.143 0.5588)
			(stroke
				(width 0)
				(type default)
			)
			(fill no)
			(layer "B.CrtYd")
		)
		(fp_line
			(start 0.508 -0.3048)
			(end 0.508 0.3048)
			(stroke
				(width 0.1)
				(type default)
			)
			(layer "B.Fab")
		)
		(fp_line
			(start -0.508 -0.3048)
			(end 0.508 -0.3048)
			(stroke
				(width 0.1)
				(type default)
			)
			(layer "B.Fab")
		)
		(fp_line
			(start 0.508 0.3048)
			(end -0.508 0.3048)
			(stroke
				(width 0.1)
				(type default)
			)
			(layer "B.Fab")
		)
		(fp_line
			(start -0.508 0.3048)
			(end -0.508 -0.3048)
			(stroke
				(width 0.1)
				(type default)
			)
			(layer "B.Fab")
		)
		(pad "1" smd rect
			(at 0.5334 0 270)
			(size 0.7112 0.6096)
			(layers "B.Cu" "B.Mask" "B.Paste")
			(net "XP5R0V")
		)
		(pad "2" smd rect
			(at -0.5334 0 270)
			(size 0.7112 0.6096)
			(layers "B.Cu" "B.Mask" "B.Paste")
			(net "SG")
		)
		(zone
			(layer "B.Cu")
			(hatch none 0.5)
			(connect_pads
				(clearance 0)
			)
			(min_thickness 0.25)
			(keepout
				(tracks allowed)
				(vias not_allowed)
				(pads allowed)
				(copperpour not_allowed)
				(footprints allowed)
			)
			(placement
				(enabled no)
				(sheetname "")
			)
			(fill
				(thermal_gap 0.5)
				(thermal_bridge_width 0.5)
				(island_removal_mode 0)
			)
			(polygon
				(pts
					(xy 82.1182 -73.0758) (xy 82.7278 -73.0758) (xy 82.7278 -73.2282) (xy 82.1182 -73.2282)
				)
			)
		)
	)
	(footprint ""
		(layer "B.Cu")
		(at 151.892 -44.704 90)
		(property "Reference" "R434"
			(at -9.94537 0.635 0)
			(unlocked yes)
			(layer "B.SilkS")
			(effects
				(font
					(size 0.7874 0.5842)
					(thickness 0.1524)
				)
				(justify mirror)
			)
		)
		(property "Value" "VAL*"
			(at -0.02032 2.13233 90)
			(unlocked yes)
			(layer "B.Fab")
			(hide yes)
			(effects
				(font
					(size 0.7874 0.5842)
					(thickness 0.1524)
				)
				(justify mirror)
			)
		)
		(property "Tolerance" "TOL*"
			(at -0.044704 3.05435 90)
			(unlocked yes)
			(layer "Cmts.User")
			(hide yes)
			(effects
				(font
					(size 0.7874 0.5842)
					(thickness 0.1524)
				)
				(justify mirror)
			)
		)
		(property "User Part Number" "PARTNUM*"
			(at -0.02032 4.024884 90)
			(unlocked yes)
			(layer "Cmts.User")
			(hide yes)
			(effects
				(font
					(size 0.7874 0.5842)
					(thickness 0.1524)
				)
				(justify mirror)
			)
		)
		(property "Device Type" "RESISTOR-G155-133R0-01,33OHM,1%"
			(at -0.008382 1.210564 90)
			(unlocked yes)
			(layer "B.Fab")
			(hide yes)
			(effects
				(font
					(size 0.7874 0.5842)
					(thickness 0.1524)
				)
				(justify mirror)
			)
		)
		(duplicate_pad_numbers_are_jumpers no)
		(fp_line
			(start 1.143 -0.5588)
			(end 1.143 0.5588)
			(stroke
				(width 0.1)
				(type default)
			)
			(layer "B.SilkS")
		)
		(fp_line
			(start -1.143 -0.5588)
			(end 1.143 -0.5588)
			(stroke
				(width 0.1)
				(type default)
			)
			(layer "B.SilkS")
		)
		(fp_line
			(start 1.143 0.5588)
			(end -1.143 0.5588)
			(stroke
				(width 0.1)
				(type default)
			)
			(layer "B.SilkS")
		)
		(fp_line
			(start -1.143 0.5588)
			(end -1.143 -0.5588)
			(stroke
				(width 0.1)
				(type default)
			)
			(layer "B.SilkS")
		)
		(fp_poly
			(pts
				(xy 1.143 0.5588) (xy -1.143 0.5588) (xy -1.143 -0.5588) (xy 1.143 -0.5588)
			)
			(stroke
				(width 0)
				(type default)
			)
			(fill no)
			(layer "B.CrtYd")
		)
		(fp_line
			(start 0.508 -0.3048)
			(end 0.508 0.3048)
			(stroke
				(width 0.1)
				(type default)
			)
			(layer "B.Fab")
		)
		(fp_line
			(start -0.508 -0.3048)
			(end 0.508 -0.3048)
			(stroke
				(width 0.1)
				(type default)
			)
			(layer "B.Fab")
		)
		(fp_line
			(start 0.508 0.3048)
			(end -0.508 0.3048)
			(stroke
				(width 0.1)
				(type default)
			)
			(layer "B.Fab")
		)
		(fp_line
			(start -0.508 0.3048)
			(end -0.508 -0.3048)
			(stroke
				(width 0.1)
				(type default)
			)
			(layer "B.Fab")
		)
		(pad "1" smd rect
			(at 0.5334 0 270)
			(size 0.7112 0.6096)
			(layers "B.Cu" "B.Mask" "B.Paste")
			(net "UNNAMED_16_CONNHDR2X6FSSMT_I1_1")
		)
		(pad "2" smd rect
			(at -0.5334 0 270)
			(size 0.7112 0.6096)
			(layers "B.Cu" "B.Mask" "B.Paste")
			(net "FPGA_IO_0")
		)
		(zone
			(layer "B.Cu")
			(hatch none 0.5)
			(connect_pads
				(clearance 0)
			)
			(min_thickness 0.25)
			(keepout
				(tracks allowed)
				(vias not_allowed)
				(pads allowed)
				(copperpour not_allowed)
				(footprints allowed)
			)
			(placement
				(enabled no)
				(sheetname "")
			)
			(fill
				(thermal_gap 0.5)
				(thermal_bridge_width 0.5)
				(island_removal_mode 0)
			)
			(polygon
				(pts
					(xy 152.1968 -44.7802) (xy 151.5872 -44.7802) (xy 151.5872 -44.6278) (xy 152.1968 -44.6278)
				)
			)
		)
		(zone
			(layer "B.Cu")
			(hatch none 0.5)
			(connect_pads
				(clearance 0)
			)
			(min_thickness 0.25)
			(keepout
				(tracks not_allowed)
				(vias allowed)
				(pads allowed)
				(copperpour not_allowed)
				(footprints allowed)
			)
			(placement
				(enabled no)
				(sheetname "")
			)
			(fill
				(thermal_gap 0.5)
				(thermal_bridge_width 0.5)
				(island_removal_mode 0)
			)
			(polygon
				(pts
					(xy 152.1968 -44.7802) (xy 151.5872 -44.7802) (xy 151.5872 -44.6278) (xy 152.1968 -44.6278)
				)
			)
		)
	)
	(footprint ""
		(layer "B.Cu")
		(at 19.304 -61.5442 90)
		(property "Reference" "R315"
			(at -0.381 -3.84937 270)
			(unlocked yes)
			(layer "B.SilkS")
			(effects
				(font
					(size 0.7874 0.5842)
					(thickness 0.1524)
				)
				(justify mirror)
			)
		)
		(property "Value" "VAL*"
			(at -0.02032 2.13233 90)
			(unlocked yes)
			(layer "B.Fab")
			(hide yes)
			(effects
				(font
					(size 0.7874 0.5842)
					(thickness 0.1524)
				)
				(justify mirror)
			)
		)
		(property "Tolerance" "TOL*"
			(at -0.044704 3.05435 90)
			(unlocked yes)
			(layer "Cmts.User")
			(hide yes)
			(effects
				(font
					(size 0.7874 0.5842)
					(thickness 0.1524)
				)
				(justify mirror)
			)
		)
		(property "User Part Number" "PARTNUM*"
			(at -0.02032 4.024884 90)
			(unlocked yes)
			(layer "Cmts.User")
			(hide yes)
			(effects
				(font
					(size 0.7874 0.5842)
					(thickness 0.1524)
				)
				(justify mirror)
			)
		)
		(property "Device Type" "RESISTOR-G155-100R0-J0,0OHM,-"
			(at -0.008382 1.210564 90)
			(unlocked yes)
			(layer "B.Fab")
			(hide yes)
			(effects
				(font
					(size 0.7874 0.5842)
					(thickness 0.1524)
				)
				(justify mirror)
			)
		)
		(duplicate_pad_numbers_are_jumpers no)
		(fp_line
			(start 1.143 -0.5588)
			(end 1.143 0.5588)
			(stroke
				(width 0.1)
				(type default)
			)
			(layer "B.SilkS")
		)
		(fp_line
			(start -1.143 -0.5588)
			(end 1.143 -0.5588)
			(stroke
				(width 0.1)
				(type default)
			)
			(layer "B.SilkS")
		)
		(fp_line
			(start 1.143 0.5588)
			(end -1.143 0.5588)
			(stroke
				(width 0.1)
				(type default)
			)
			(layer "B.SilkS")
		)
		(fp_line
			(start -1.143 0.5588)
			(end -1.143 -0.5588)
			(stroke
				(width 0.1)
				(type default)
			)
			(layer "B.SilkS")
		)
		(fp_poly
			(pts
				(xy 1.143 0.5588) (xy -1.143 0.5588) (xy -1.143 -0.5588) (xy 1.143 -0.5588)
			)
			(stroke
				(width 0)
				(type default)
			)
			(fill no)
			(layer "B.CrtYd")
		)
		(fp_line
			(start 0.508 -0.3048)
			(end 0.508 0.3048)
			(stroke
				(width 0.1)
				(type default)
			)
			(layer "B.Fab")
		)
		(fp_line
			(start -0.508 -0.3048)
			(end 0.508 -0.3048)
			(stroke
				(width 0.1)
				(type default)
			)
			(layer "B.Fab")
		)
		(fp_line
			(start 0.508 0.3048)
			(end -0.508 0.3048)
			(stroke
				(width 0.1)
				(type default)
			)
			(layer "B.Fab")
		)
		(fp_line
			(start -0.508 0.3048)
			(end -0.508 -0.3048)
			(stroke
				(width 0.1)
				(type default)
			)
			(layer "B.Fab")
		)
		(pad "1" smd rect
			(at 0.5334 0 270)
			(size 0.7112 0.6096)
			(layers "B.Cu" "B.Mask" "B.Paste")
			(net "ICP10100_I2C_SCL")
		)
		(pad "2" smd rect
			(at -0.5334 0 270)
			(size 0.7112 0.6096)
			(layers "B.Cu" "B.Mask" "B.Paste")
			(net "BF_ICP10100_I2C_SCL")
		)
		(zone
			(layer "B.Cu")
			(hatch none 0.5)
			(connect_pads
				(clearance 0)
			)
			(min_thickness 0.25)
			(keepout
				(tracks allowed)
				(vias not_allowed)
				(pads allowed)
				(copperpour not_allowed)
				(footprints allowed)
			)
			(placement
				(enabled no)
				(sheetname "")
			)
			(fill
				(thermal_gap 0.5)
				(thermal_bridge_width 0.5)
				(island_removal_mode 0)
			)
			(polygon
				(pts
					(xy 19.6088 -61.6204) (xy 18.9992 -61.6204) (xy 18.9992 -61.468) (xy 19.6088 -61.468)
				)
			)
		)
		(zone
			(layer "B.Cu")
			(hatch none 0.5)
			(connect_pads
				(clearance 0)
			)
			(min_thickness 0.25)
			(keepout
				(tracks not_allowed)
				(vias allowed)
				(pads allowed)
				(copperpour not_allowed)
				(footprints allowed)
			)
			(placement
				(enabled no)
				(sheetname "")
			)
			(fill
				(thermal_gap 0.5)
				(thermal_bridge_width 0.5)
				(island_removal_mode 0)
			)
			(polygon
				(pts
					(xy 19.6088 -61.6204) (xy 18.9992 -61.6204) (xy 18.9992 -61.468) (xy 19.6088 -61.468)
				)
			)
		)
	)
	(footprint ""
		(layer "B.Cu")
		(at 151.892 -36.576 90)
		(property "Reference" "R431"
			(at -4.99237 0.635 0)
			(unlocked yes)
			(layer "B.SilkS")
			(effects
				(font
					(size 0.7874 0.5842)
					(thickness 0.1524)
				)
				(justify mirror)
			)
		)
		(property "Value" "VAL*"
			(at -0.02032 2.13233 90)
			(unlocked yes)
			(layer "B.Fab")
			(hide yes)
			(effects
				(font
					(size 0.7874 0.5842)
					(thickness 0.1524)
				)
				(justify mirror)
			)
		)
		(property "Tolerance" "TOL*"
			(at -0.044704 3.05435 90)
			(unlocked yes)
			(layer "Cmts.User")
			(hide yes)
			(effects
				(font
					(size 0.7874 0.5842)
					(thickness 0.1524)
				)
				(justify mirror)
			)
		)
		(property "User Part Number" "PARTNUM*"
			(at -0.02032 4.024884 90)
			(unlocked yes)
			(layer "Cmts.User")
			(hide yes)
			(effects
				(font
					(size 0.7874 0.5842)
					(thickness 0.1524)
				)
				(justify mirror)
			)
		)
		(property "Device Type" "RESISTOR-G155-133R0-01,33OHM,1%"
			(at -0.008382 1.210564 90)
			(unlocked yes)
			(layer "B.Fab")
			(hide yes)
			(effects
				(font
					(size 0.7874 0.5842)
					(thickness 0.1524)
				)
				(justify mirror)
			)
		)
		(duplicate_pad_numbers_are_jumpers no)
		(fp_line
			(start 1.143 -0.5588)
			(end 1.143 0.5588)
			(stroke
				(width 0.1)
				(type default)
			)
			(layer "B.SilkS")
		)
		(fp_line
			(start -1.143 -0.5588)
			(end 1.143 -0.5588)
			(stroke
				(width 0.1)
				(type default)
			)
			(layer "B.SilkS")
		)
		(fp_line
			(start 1.143 0.5588)
			(end -1.143 0.5588)
			(stroke
				(width 0.1)
				(type default)
			)
			(layer "B.SilkS")
		)
		(fp_line
			(start -1.143 0.5588)
			(end -1.143 -0.5588)
			(stroke
				(width 0.1)
				(type default)
			)
			(layer "B.SilkS")
		)
		(fp_poly
			(pts
				(xy 1.143 0.5588) (xy -1.143 0.5588) (xy -1.143 -0.5588) (xy 1.143 -0.5588)
			)
			(stroke
				(width 0)
				(type default)
			)
			(fill no)
			(layer "B.CrtYd")
		)
		(fp_line
			(start 0.508 -0.3048)
			(end 0.508 0.3048)
			(stroke
				(width 0.1)
				(type default)
			)
			(layer "B.Fab")
		)
		(fp_line
			(start -0.508 -0.3048)
			(end 0.508 -0.3048)
			(stroke
				(width 0.1)
				(type default)
			)
			(layer "B.Fab")
		)
		(fp_line
			(start 0.508 0.3048)
			(end -0.508 0.3048)
			(stroke
				(width 0.1)
				(type default)
			)
			(layer "B.Fab")
		)
		(fp_line
			(start -0.508 0.3048)
			(end -0.508 -0.3048)
			(stroke
				(width 0.1)
				(type default)
			)
			(layer "B.Fab")
		)
		(pad "1" smd rect
			(at 0.5334 0 270)
			(size 0.7112 0.6096)
			(layers "B.Cu" "B.Mask" "B.Paste")
			(net "UNNAMED_16_CONNHDR2X6FSSMT_I1_5")
		)
		(pad "2" smd rect
			(at -0.5334 0 270)
			(size 0.7112 0.6096)
			(layers "B.Cu" "B.Mask" "B.Paste")
			(net "FPGA_IO_3")
		)
		(zone
			(layer "B.Cu")
			(hatch none 0.5)
			(connect_pads
				(clearance 0)
			)
			(min_thickness 0.25)
			(keepout
				(tracks allowed)
				(vias not_allowed)
				(pads allowed)
				(copperpour not_allowed)
				(footprints allowed)
			)
			(placement
				(enabled no)
				(sheetname "")
			)
			(fill
				(thermal_gap 0.5)
				(thermal_bridge_width 0.5)
				(island_removal_mode 0)
			)
			(polygon
				(pts
					(xy 152.1968 -36.6522) (xy 151.5872 -36.6522) (xy 151.5872 -36.4998) (xy 152.1968 -36.4998)
				)
			)
		)
		(zone
			(layer "B.Cu")
			(hatch none 0.5)
			(connect_pads
				(clearance 0)
			)
			(min_thickness 0.25)
			(keepout
				(tracks not_allowed)
				(vias allowed)
				(pads allowed)
				(copperpour not_allowed)
				(footprints allowed)
			)
			(placement
				(enabled no)
				(sheetname "")
			)
			(fill
				(thermal_gap 0.5)
				(thermal_bridge_width 0.5)
				(island_removal_mode 0)
			)
			(polygon
				(pts
					(xy 152.1968 -36.6522) (xy 151.5872 -36.6522) (xy 151.5872 -36.4998) (xy 152.1968 -36.4998)
				)
			)
		)
	)
	(footprint ""
		(layer "B.Cu")
		(at 72.517 -72.771 -90)
		(property "Reference" "C59"
			(at -3.81 -0.59563 270)
			(unlocked yes)
			(layer "B.SilkS")
			(effects
				(font
					(size 0.7874 0.5842)
					(thickness 0.1524)
				)
				(justify mirror)
			)
		)
		(property "Value" "VAL*"
			(at -0.0762 2.067306 270)
			(unlocked yes)
			(layer "B.Fab")
			(hide yes)
			(effects
				(font
					(size 0.7874 0.5842)
					(thickness 0.1524)
				)
				(justify mirror)
			)
		)
		(property "Tolerance" "TOL*"
			(at -0.0762 3.032506 270)
			(unlocked yes)
			(layer "Cmts.User")
			(hide yes)
			(effects
				(font
					(size 0.7874 0.5842)
					(thickness 0.1524)
				)
				(justify mirror)
			)
		)
		(property "User Part Number" "PARTNUM*"
			(at -0.1016 4.023106 270)
			(unlocked yes)
			(layer "Cmts.User")
			(hide yes)
			(effects
				(font
					(size 0.7874 0.5842)
					(thickness 0.1524)
				)
				(justify mirror)
			)
		)
		(property "Device Type" "CAPACITOR-G105-0B104-EK,0.1UF,A"
			(at -0.0508 1.127506 270)
			(unlocked yes)
			(layer "B.Fab")
			(hide yes)
			(effects
				(font
					(size 0.7874 0.5842)
					(thickness 0.1524)
				)
				(justify mirror)
			)
		)
		(duplicate_pad_numbers_are_jumpers no)
		(fp_line
			(start -1.143 0.5588)
			(end -1.143 -0.5588)
			(stroke
				(width 0.1)
				(type default)
			)
			(layer "B.SilkS")
		)
		(fp_line
			(start 1.143 0.5588)
			(end -1.143 0.5588)
			(stroke
				(width 0.1)
				(type default)
			)
			(layer "B.SilkS")
		)
		(fp_line
			(start -1.143 -0.5588)
			(end 1.143 -0.5588)
			(stroke
				(width 0.1)
				(type default)
			)
			(layer "B.SilkS")
		)
		(fp_line
			(start 1.143 -0.5588)
			(end 1.143 0.5588)
			(stroke
				(width 0.1)
				(type default)
			)
			(layer "B.SilkS")
		)
		(fp_rect
			(start 1.143 -0.5588)
			(end -1.143 0.5588)
			(stroke
				(width 0)
				(type default)
			)
			(fill no)
			(layer "B.CrtYd")
		)
		(fp_line
			(start -0.508 0.3048)
			(end -0.508 -0.3048)
			(stroke
				(width 0.1)
				(type default)
			)
			(layer "B.Fab")
		)
		(fp_line
			(start 0.508 0.3048)
			(end -0.508 0.3048)
			(stroke
				(width 0.1)
				(type default)
			)
			(layer "B.Fab")
		)
		(fp_line
			(start -0.508 -0.3048)
			(end 0.508 -0.3048)
			(stroke
				(width 0.1)
				(type default)
			)
			(layer "B.Fab")
		)
		(fp_line
			(start 0.508 -0.3048)
			(end 0.508 0.3048)
			(stroke
				(width 0.1)
				(type default)
			)
			(layer "B.Fab")
		)
		(pad "1" smd rect
			(at 0.5334 0 90)
			(size 0.7112 0.6096)
			(layers "B.Cu" "B.Mask" "B.Paste")
			(net "XP5R0V_MAC")
		)
		(pad "2" smd rect
			(at -0.5334 0 90)
			(size 0.7112 0.6096)
			(layers "B.Cu" "B.Mask" "B.Paste")
			(net "SG")
		)
		(zone
			(layer "B.Cu")
			(hatch none 0.5)
			(connect_pads
				(clearance 0)
			)
			(min_thickness 0.25)
			(keepout
				(tracks allowed)
				(vias not_allowed)
				(pads allowed)
				(copperpour not_allowed)
				(footprints allowed)
			)
			(placement
				(enabled no)
				(sheetname "")
			)
			(fill
				(thermal_gap 0.5)
				(thermal_bridge_width 0.5)
				(island_removal_mode 0)
			)
			(polygon
				(pts
					(xy 72.8218 -72.6948) (xy 72.8218 -72.8472) (xy 72.2122 -72.8472) (xy 72.2122 -72.6948)
				)
			)
		)
	)
	(footprint ""
		(layer "B.Cu")
		(at 80.899 -73.152 -90)
		(property "Reference" "L3"
			(at -2.3622 0.29337 270)
			(unlocked yes)
			(layer "B.SilkS")
			(effects
				(font
					(size 0.7874 0.5842)
					(thickness 0.1524)
				)
				(justify left mirror)
			)
		)
		(property "Value" "VAL*"
			(at 0.9398 3.70967 270)
			(unlocked yes)
			(layer "B.Fab")
			(hide yes)
			(effects
				(font
					(size 0.7874 0.5842)
					(thickness 0.1524)
				)
				(justify left mirror)
			)
		)
		(property "Tolerance" "TOL*"
			(at 0.9906 5.00507 270)
			(unlocked yes)
			(layer "Cmts.User")
			(hide yes)
			(effects
				(font
					(size 0.7874 0.5842)
					(thickness 0.1524)
				)
				(justify left mirror)
			)
		)
		(property "User Part Number" "PARTNUM*"
			(at 2.54 2.46507 270)
			(unlocked yes)
			(layer "Cmts.User")
			(hide yes)
			(effects
				(font
					(size 0.7874 0.5842)
					(thickness 0.1524)
				)
				(justify left mirror)
			)
		)
		(property "Device Type" "FERRITEBEAD-G191-10101-01,26OHA"
			(at 0.9906 1.22047 270)
			(unlocked yes)
			(layer "B.Fab")
			(hide yes)
			(effects
				(font
					(size 0.7874 0.5842)
					(thickness 0.1524)
				)
				(justify left mirror)
			)
		)
		(duplicate_pad_numbers_are_jumpers no)
		(fp_line
			(start -1.3208 0.7112)
			(end 1.3208 0.7112)
			(stroke
				(width 0.1)
				(type default)
			)
			(layer "B.SilkS")
		)
		(fp_line
			(start 1.3208 0.7112)
			(end 1.3208 -0.7112)
			(stroke
				(width 0.1)
				(type default)
			)
			(layer "B.SilkS")
		)
		(fp_line
			(start -1.3208 -0.7112)
			(end -1.3208 0.7112)
			(stroke
				(width 0.1)
				(type default)
			)
			(layer "B.SilkS")
		)
		(fp_line
			(start 1.3208 -0.7112)
			(end -1.3208 -0.7112)
			(stroke
				(width 0.1)
				(type default)
			)
			(layer "B.SilkS")
		)
		(fp_rect
			(start 1.3208 0.7112)
			(end -1.3208 -0.7112)
			(stroke
				(width 0)
				(type default)
			)
			(fill no)
			(layer "B.CrtYd")
		)
		(fp_line
			(start -0.8128 0.4572)
			(end 0.8128 0.4572)
			(stroke
				(width 0.1)
				(type default)
			)
			(layer "B.Fab")
		)
		(fp_line
			(start 0.8128 0.4572)
			(end 0.8128 -0.4572)
			(stroke
				(width 0.1)
				(type default)
			)
			(layer "B.Fab")
		)
		(fp_line
			(start -0.8128 -0.4572)
			(end -0.8128 0.4572)
			(stroke
				(width 0.1)
				(type default)
			)
			(layer "B.Fab")
		)
		(fp_line
			(start 0.8128 -0.4572)
			(end -0.8128 -0.4572)
			(stroke
				(width 0.1)
				(type default)
			)
			(layer "B.Fab")
		)
		(pad "1" smd rect
			(at 0.6858 0 90)
			(size 0.762 0.8636)
			(layers "B.Cu" "B.Mask" "B.Paste")
			(net "XP5R0V_MAC")
		)
		(pad "2" smd rect
			(at -0.6858 0 90)
			(size 0.762 0.8636)
			(layers "B.Cu" "B.Mask" "B.Paste")
			(net "XP5R0V")
		)
		(zone
			(layer "B.Cu")
			(hatch none 0.5)
			(connect_pads
				(clearance 0)
			)
			(min_thickness 0.25)
			(keepout
				(tracks not_allowed)
				(vias allowed)
				(pads allowed)
				(copperpour not_allowed)
				(footprints allowed)
			)
			(placement
				(enabled no)
				(sheetname "")
			)
			(fill
				(thermal_gap 0.5)
				(thermal_bridge_width 0.5)
				(island_removal_mode 0)
			)
			(polygon
				(pts
					(xy 80.4418 -72.9996) (xy 81.3562 -72.9996) (xy 81.3562 -73.3044) (xy 80.4418 -73.3044)
				)
			)
		)
		(zone
			(layer "B.Cu")
			(hatch none 0.5)
			(connect_pads
				(clearance 0)
			)
			(min_thickness 0.25)
			(keepout
				(tracks allowed)
				(vias not_allowed)
				(pads allowed)
				(copperpour not_allowed)
				(footprints allowed)
			)
			(placement
				(enabled no)
				(sheetname "")
			)
			(fill
				(thermal_gap 0.5)
				(thermal_bridge_width 0.5)
				(island_removal_mode 0)
			)
			(polygon
				(pts
					(xy 80.4418 -72.9996) (xy 81.3562 -72.9996) (xy 81.3562 -73.3044) (xy 80.4418 -73.3044)
				)
			)
		)
	)
	(footprint ""
		(layer "B.Cu")
		(at 104.34701 -49.823116)
		(property "Reference" "C153"
			(at -0.20701 -0.945134 0)
			(unlocked yes)
			(layer "B.SilkS")
			(effects
				(font
					(size 0.635 0.4064)
					(thickness 0.1524)
				)
				(justify mirror)
			)
		)
		(property "Value" "VAL*"
			(at 0 3.718306 0)
			(unlocked yes)
			(layer "B.Fab")
			(hide yes)
			(effects
				(font
					(size 0.7874 0.5842)
					(thickness 0.127)
				)
				(justify mirror)
			)
		)
		(property "Device Type" "CAPACITOR-G105-0B104-CK,0.1UF,A"
			(at 0 1.432306 0)
			(unlocked yes)
			(layer "B.Fab")
			(hide yes)
			(effects
				(font
					(size 0.7874 0.5842)
					(thickness 0.127)
				)
				(justify mirror)
			)
		)
		(property "User Part Number" "PARTNUM*"
			(at 0 2.575306 0)
			(unlocked yes)
			(layer "Cmts.User")
			(hide yes)
			(effects
				(font
					(size 0.7874 0.5842)
					(thickness 0.127)
				)
				(justify mirror)
			)
		)
		(property "Tolerance" "TOL*"
			(at 0 4.861306 0)
			(unlocked yes)
			(layer "Cmts.User")
			(hide yes)
			(effects
				(font
					(size 0.7874 0.5842)
					(thickness 0.127)
				)
				(justify mirror)
			)
		)
		(duplicate_pad_numbers_are_jumpers no)
		(fp_line
			(start -0.970026 -0.4699)
			(end -0.970026 0.4699)
			(stroke
				(width 0.1)
				(type default)
			)
			(layer "B.SilkS")
		)
		(fp_line
			(start -0.970026 0.4699)
			(end 0.970026 0.4699)
			(stroke
				(width 0.1)
				(type default)
			)
			(layer "B.SilkS")
		)
		(fp_line
			(start 0.970026 -0.4699)
			(end -0.970026 -0.4699)
			(stroke
				(width 0.1)
				(type default)
			)
			(layer "B.SilkS")
		)
		(fp_line
			(start 0.970026 0.4699)
			(end 0.970026 -0.4699)
			(stroke
				(width 0.1)
				(type default)
			)
			(layer "B.SilkS")
		)
		(fp_poly
			(pts
				(xy 0.970026 0.4699) (xy -0.970026 0.4699) (xy -0.970026 -0.4699) (xy 0.970026 -0.4699)
			)
			(stroke
				(width 0)
				(type default)
			)
			(fill no)
			(layer "B.CrtYd")
		)
		(fp_line
			(start -0.508 -0.3048)
			(end -0.508 0.3048)
			(stroke
				(width 0.1)
				(type default)
			)
			(layer "B.Fab")
		)
		(fp_line
			(start -0.508 0.3048)
			(end 0.508 0.3048)
			(stroke
				(width 0.1)
				(type default)
			)
			(layer "B.Fab")
		)
		(fp_line
			(start 0.508 -0.3048)
			(end -0.508 -0.3048)
			(stroke
				(width 0.1)
				(type default)
			)
			(layer "B.Fab")
		)
		(fp_line
			(start 0.508 0.3048)
			(end 0.508 -0.3048)
			(stroke
				(width 0.1)
				(type default)
			)
			(layer "B.Fab")
		)
		(pad "1" smd circle
			(at 0.500126 0 180)
			(size 0.635 0.635)
			(layers "B.Cu" "B.Mask" "B.Paste")
			(net "XP3R3V_FPGA")
		)
		(pad "2" smd circle
			(at -0.500126 0 180)
			(size 0.635 0.635)
			(layers "B.Cu" "B.Mask" "B.Paste")
			(net "SG")
		)
	)
	(footprint ""
		(layer "B.Cu")
		(at 109.22 -51.0032 -90)
		(property "Reference" "C149"
			(at -0.9398 -0.98425 270)
			(unlocked yes)
			(layer "B.SilkS")
			(effects
				(font
					(size 0.635 0.4064)
					(thickness 0.1524)
				)
				(justify mirror)
			)
		)
		(property "Value" "VAL*"
			(at -0.0762 2.067306 270)
			(unlocked yes)
			(layer "B.Fab")
			(hide yes)
			(effects
				(font
					(size 0.7874 0.5842)
					(thickness 0.1524)
				)
				(justify mirror)
			)
		)
		(property "Device Type" "CAPACITOR-G105-0B104-CK,0.1UF,A"
			(at -0.0508 1.127506 270)
			(unlocked yes)
			(layer "B.Fab")
			(hide yes)
			(effects
				(font
					(size 0.7874 0.5842)
					(thickness 0.1524)
				)
				(justify mirror)
			)
		)
		(property "User Part Number" "PARTNUM*"
			(at -0.1016 4.023106 270)
			(unlocked yes)
			(layer "Cmts.User")
			(hide yes)
			(effects
				(font
					(size 0.7874 0.5842)
					(thickness 0.1524)
				)
				(justify mirror)
			)
		)
		(property "Tolerance" "TOL*"
			(at -0.0762 3.032506 270)
			(unlocked yes)
			(layer "Cmts.User")
			(hide yes)
			(effects
				(font
					(size 0.7874 0.5842)
					(thickness 0.1524)
				)
				(justify mirror)
			)
		)
		(duplicate_pad_numbers_are_jumpers no)
		(fp_line
			(start -1.143 0.5588)
			(end -1.143 -0.5588)
			(stroke
				(width 0.1)
				(type default)
			)
			(layer "B.SilkS")
		)
		(fp_line
			(start 1.143 0.5588)
			(end -1.143 0.5588)
			(stroke
				(width 0.1)
				(type default)
			)
			(layer "B.SilkS")
		)
		(fp_line
			(start -1.143 -0.5588)
			(end 1.143 -0.5588)
			(stroke
				(width 0.1)
				(type default)
			)
			(layer "B.SilkS")
		)
		(fp_line
			(start 1.143 -0.5588)
			(end 1.143 0.5588)
			(stroke
				(width 0.1)
				(type default)
			)
			(layer "B.SilkS")
		)
		(fp_rect
			(start 1.143 0.5588)
			(end -1.143 -0.5588)
			(stroke
				(width 0)
				(type default)
			)
			(fill no)
			(layer "B.CrtYd")
		)
		(fp_line
			(start -0.508 0.3048)
			(end -0.508 -0.3048)
			(stroke
				(width 0.1)
				(type default)
			)
			(layer "B.Fab")
		)
		(fp_line
			(start 0.508 0.3048)
			(end -0.508 0.3048)
			(stroke
				(width 0.1)
				(type default)
			)
			(layer "B.Fab")
		)
		(fp_line
			(start -0.508 -0.3048)
			(end 0.508 -0.3048)
			(stroke
				(width 0.1)
				(type default)
			)
			(layer "B.Fab")
		)
		(fp_line
			(start 0.508 -0.3048)
			(end 0.508 0.3048)
			(stroke
				(width 0.1)
				(type default)
			)
			(layer "B.Fab")
		)
		(pad "1" smd rect
			(at 0.5334 0 90)
			(size 0.7112 0.6096)
			(layers "B.Cu" "B.Mask" "B.Paste")
			(net "XP3R3V_FPGA")
		)
		(pad "2" smd rect
			(at -0.5334 0 90)
			(size 0.7112 0.6096)
			(layers "B.Cu" "B.Mask" "B.Paste")
			(net "SG")
		)
		(zone
			(layer "B.Cu")
			(hatch none 0.5)
			(connect_pads
				(clearance 0)
			)
			(min_thickness 0.25)
			(keepout
				(tracks allowed)
				(vias not_allowed)
				(pads allowed)
				(copperpour not_allowed)
				(footprints allowed)
			)
			(placement
				(enabled no)
				(sheetname "")
			)
			(fill
				(thermal_gap 0.5)
				(thermal_bridge_width 0.5)
				(island_removal_mode 0)
			)
			(polygon
				(pts
					(xy 108.9152 -50.927) (xy 109.5248 -50.927) (xy 109.5248 -51.0794) (xy 108.9152 -51.0794)
				)
			)
		)
	)
	(footprint ""
		(layer "B.Cu")
		(at 73.914 -58.928 90)
		(property "Reference" "R44"
			(at 2.54 6.81863 270)
			(unlocked yes)
			(layer "B.SilkS")
			(effects
				(font
					(size 0.7874 0.5842)
					(thickness 0.1524)
				)
				(justify mirror)
			)
		)
		(property "Value" "VAL*"
			(at -0.02032 2.13233 90)
			(unlocked yes)
			(layer "B.Fab")
			(hide yes)
			(effects
				(font
					(size 0.7874 0.5842)
					(thickness 0.1524)
				)
				(justify mirror)
			)
		)
		(property "Tolerance" "TOL*"
			(at -0.044704 3.05435 90)
			(unlocked yes)
			(layer "Cmts.User")
			(hide yes)
			(effects
				(font
					(size 0.7874 0.5842)
					(thickness 0.1524)
				)
				(justify mirror)
			)
		)
		(property "User Part Number" "PARTNUM*"
			(at -0.02032 4.024884 90)
			(unlocked yes)
			(layer "Cmts.User")
			(hide yes)
			(effects
				(font
					(size 0.7874 0.5842)
					(thickness 0.1524)
				)
				(justify mirror)
			)
		)
		(property "Device Type" "RESISTOR-G155-14701-01,4.7KOHMA"
			(at -0.008382 1.210564 90)
			(unlocked yes)
			(layer "B.Fab")
			(hide yes)
			(effects
				(font
					(size 0.7874 0.5842)
					(thickness 0.1524)
				)
				(justify mirror)
			)
		)
		(duplicate_pad_numbers_are_jumpers no)
		(fp_line
			(start 1.143 -0.5588)
			(end 1.143 0.5588)
			(stroke
				(width 0.1)
				(type default)
			)
			(layer "B.SilkS")
		)
		(fp_line
			(start -1.143 -0.5588)
			(end 1.143 -0.5588)
			(stroke
				(width 0.1)
				(type default)
			)
			(layer "B.SilkS")
		)
		(fp_line
			(start 1.143 0.5588)
			(end -1.143 0.5588)
			(stroke
				(width 0.1)
				(type default)
			)
			(layer "B.SilkS")
		)
		(fp_line
			(start -1.143 0.5588)
			(end -1.143 -0.5588)
			(stroke
				(width 0.1)
				(type default)
			)
			(layer "B.SilkS")
		)
		(fp_rect
			(start 1.143 0.5588)
			(end -1.143 -0.5588)
			(stroke
				(width 0)
				(type default)
			)
			(fill no)
			(layer "B.CrtYd")
		)
		(fp_line
			(start 0.508 -0.3048)
			(end 0.508 0.3048)
			(stroke
				(width 0.1)
				(type default)
			)
			(layer "B.Fab")
		)
		(fp_line
			(start -0.508 -0.3048)
			(end 0.508 -0.3048)
			(stroke
				(width 0.1)
				(type default)
			)
			(layer "B.Fab")
		)
		(fp_line
			(start 0.508 0.3048)
			(end -0.508 0.3048)
			(stroke
				(width 0.1)
				(type default)
			)
			(layer "B.Fab")
		)
		(fp_line
			(start -0.508 0.3048)
			(end -0.508 -0.3048)
			(stroke
				(width 0.1)
				(type default)
			)
			(layer "B.Fab")
		)
		(pad "1" smd rect
			(at 0.5334 0 270)
			(size 0.7112 0.6096)
			(layers "B.Cu" "B.Mask" "B.Paste")
			(net "XP5R0V_MAC")
		)
		(pad "2" smd rect
			(at -0.5334 0 270)
			(size 0.7112 0.6096)
			(layers "B.Cu" "B.Mask" "B.Paste")
			(net "UNNAMED_527_POWERMOS3PNCHV1_I23")
		)
		(zone
			(layer "B.Cu")
			(hatch none 0.5)
			(connect_pads
				(clearance 0)
			)
			(min_thickness 0.25)
			(keepout
				(tracks allowed)
				(vias not_allowed)
				(pads allowed)
				(copperpour not_allowed)
				(footprints allowed)
			)
			(placement
				(enabled no)
				(sheetname "")
			)
			(fill
				(thermal_gap 0.5)
				(thermal_bridge_width 0.5)
				(island_removal_mode 0)
			)
			(polygon
				(pts
					(xy 74.2188 -59.0042) (xy 73.6092 -59.0042) (xy 73.6092 -58.8518) (xy 74.2188 -58.8518)
				)
			)
		)
		(zone
			(layer "B.Cu")
			(hatch none 0.5)
			(connect_pads
				(clearance 0)
			)
			(min_thickness 0.25)
			(keepout
				(tracks not_allowed)
				(vias allowed)
				(pads allowed)
				(copperpour not_allowed)
				(footprints allowed)
			)
			(placement
				(enabled no)
				(sheetname "")
			)
			(fill
				(thermal_gap 0.5)
				(thermal_bridge_width 0.5)
				(island_removal_mode 0)
			)
			(polygon
				(pts
					(xy 74.2188 -59.0042) (xy 73.6092 -59.0042) (xy 73.6092 -58.8518) (xy 74.2188 -58.8518)
				)
			)
		)
	)
	(footprint ""
		(layer "B.Cu")
		(at 33.528 -90.805 90)
		(property "Reference" "L22"
			(at 3.175 -0.03937 270)
			(unlocked yes)
			(layer "B.SilkS")
			(effects
				(font
					(size 0.7874 0.5842)
					(thickness 0.1524)
				)
				(justify mirror)
			)
		)
		(property "Value" "VAL*"
			(at -0.014732 2.526538 90)
			(unlocked yes)
			(layer "B.Fab")
			(hide yes)
			(effects
				(font
					(size 0.7874 0.5842)
					(thickness 0.000001)
				)
				(justify mirror)
			)
		)
		(property "Tolerance" "TOL*"
			(at -0.014732 3.503676 90)
			(unlocked yes)
			(layer "Cmts.User")
			(hide yes)
			(effects
				(font
					(size 0.7874 0.5842)
					(thickness 0.000001)
				)
				(justify mirror)
			)
		)
		(property "User Part Number" "PARTNUM*"
			(at -0.02794 4.480814 90)
			(unlocked yes)
			(layer "Cmts.User")
			(hide yes)
			(effects
				(font
					(size 0.7874 0.5842)
					(thickness 0.000001)
				)
				(justify mirror)
			)
		)
		(property "Device Type" "FERRITEBEAD-G191-10097-01,600OA"
			(at -0.014732 1.600708 90)
			(unlocked yes)
			(layer "B.Fab")
			(hide yes)
			(effects
				(font
					(size 0.7874 0.5842)
					(thickness 0.000001)
				)
				(justify mirror)
			)
		)
		(duplicate_pad_numbers_are_jumpers no)
		(fp_line
			(start 1.3208 -0.7112)
			(end -1.3208 -0.7112)
			(stroke
				(width 0.1)
				(type default)
			)
			(layer "B.SilkS")
		)
		(fp_line
			(start -1.3208 -0.7112)
			(end -1.3208 0.7112)
			(stroke
				(width 0.1)
				(type default)
			)
			(layer "B.SilkS")
		)
		(fp_line
			(start 1.3208 0.7112)
			(end 1.3208 -0.7112)
			(stroke
				(width 0.1)
				(type default)
			)
			(layer "B.SilkS")
		)
		(fp_line
			(start -1.3208 0.7112)
			(end 1.3208 0.7112)
			(stroke
				(width 0.1)
				(type default)
			)
			(layer "B.SilkS")
		)
		(fp_rect
			(start 1.3208 0.7112)
			(end -1.3208 -0.7112)
			(stroke
				(width 0)
				(type default)
			)
			(fill no)
			(layer "B.CrtYd")
		)
		(fp_line
			(start 0.8128 -0.4572)
			(end -0.8128 -0.4572)
			(stroke
				(width 0.1)
				(type default)
			)
			(layer "B.Fab")
		)
		(fp_line
			(start -0.8128 -0.4572)
			(end -0.8128 0.4572)
			(stroke
				(width 0.1)
				(type default)
			)
			(layer "B.Fab")
		)
		(fp_line
			(start 0.8128 0.4572)
			(end 0.8128 -0.4572)
			(stroke
				(width 0.1)
				(type default)
			)
			(layer "B.Fab")
		)
		(fp_line
			(start -0.8128 0.4572)
			(end 0.8128 0.4572)
			(stroke
				(width 0.1)
				(type default)
			)
			(layer "B.Fab")
		)
		(pad "1" smd rect
			(at 0.6858 0 270)
			(size 0.762 0.8636)
			(layers "B.Cu" "B.Mask" "B.Paste")
			(net "XP3R3V_FT4232")
		)
		(pad "2" smd rect
			(at -0.6858 0 270)
			(size 0.762 0.8636)
			(layers "B.Cu" "B.Mask" "B.Paste")
			(net "XP3R3V_VPHY")
		)
		(zone
			(layer "B.Cu")
			(hatch none 0.5)
			(connect_pads
				(clearance 0)
			)
			(min_thickness 0.25)
			(keepout
				(tracks allowed)
				(vias not_allowed)
				(pads allowed)
				(copperpour not_allowed)
				(footprints allowed)
			)
			(placement
				(enabled no)
				(sheetname "")
			)
			(fill
				(thermal_gap 0.5)
				(thermal_bridge_width 0.5)
				(island_removal_mode 0)
			)
			(polygon
				(pts
					(xy 33.9852 -90.9574) (xy 33.0708 -90.9574) (xy 33.0708 -90.6526) (xy 33.9852 -90.6526)
				)
			)
		)
		(zone
			(layer "B.Cu")
			(hatch none 0.5)
			(connect_pads
				(clearance 0)
			)
			(min_thickness 0.25)
			(keepout
				(tracks not_allowed)
				(vias allowed)
				(pads allowed)
				(copperpour not_allowed)
				(footprints allowed)
			)
			(placement
				(enabled no)
				(sheetname "")
			)
			(fill
				(thermal_gap 0.5)
				(thermal_bridge_width 0.5)
				(island_removal_mode 0)
			)
			(polygon
				(pts
					(xy 33.9852 -90.9574) (xy 33.0708 -90.9574) (xy 33.0708 -90.6526) (xy 33.9852 -90.6526)
				)
			)
		)
	)
	(footprint ""
		(layer "B.Cu")
		(at 116.346986 -35.82289)
		(property "Reference" "C127"
			(at 0.239014 -0.97536 0)
			(unlocked yes)
			(layer "B.SilkS")
			(effects
				(font
					(size 0.635 0.4064)
					(thickness 0.1524)
				)
				(justify mirror)
			)
		)
		(property "Value" "VAL*"
			(at 0 3.718306 0)
			(unlocked yes)
			(layer "B.Fab")
			(hide yes)
			(effects
				(font
					(size 0.7874 0.5842)
					(thickness 0.127)
				)
				(justify mirror)
			)
		)
		(property "Device Type" "CAPACITOR-G105-0B104-CK,0.1UF,A"
			(at 0 1.432306 0)
			(unlocked yes)
			(layer "B.Fab")
			(hide yes)
			(effects
				(font
					(size 0.7874 0.5842)
					(thickness 0.127)
				)
				(justify mirror)
			)
		)
		(property "User Part Number" "PARTNUM*"
			(at 0 2.575306 0)
			(unlocked yes)
			(layer "Cmts.User")
			(hide yes)
			(effects
				(font
					(size 0.7874 0.5842)
					(thickness 0.127)
				)
				(justify mirror)
			)
		)
		(property "Tolerance" "TOL*"
			(at 0 4.861306 0)
			(unlocked yes)
			(layer "Cmts.User")
			(hide yes)
			(effects
				(font
					(size 0.7874 0.5842)
					(thickness 0.127)
				)
				(justify mirror)
			)
		)
		(duplicate_pad_numbers_are_jumpers no)
		(fp_line
			(start -0.970026 -0.4699)
			(end -0.970026 0.4699)
			(stroke
				(width 0.1)
				(type default)
			)
			(layer "B.SilkS")
		)
		(fp_line
			(start -0.970026 0.4699)
			(end 0.970026 0.4699)
			(stroke
				(width 0.1)
				(type default)
			)
			(layer "B.SilkS")
		)
		(fp_line
			(start 0.970026 -0.4699)
			(end -0.970026 -0.4699)
			(stroke
				(width 0.1)
				(type default)
			)
			(layer "B.SilkS")
		)
		(fp_line
			(start 0.970026 0.4699)
			(end 0.970026 -0.4699)
			(stroke
				(width 0.1)
				(type default)
			)
			(layer "B.SilkS")
		)
		(fp_poly
			(pts
				(xy 0.970026 0.4699) (xy -0.970026 0.4699) (xy -0.970026 -0.4699) (xy 0.970026 -0.4699)
			)
			(stroke
				(width 0)
				(type default)
			)
			(fill no)
			(layer "B.CrtYd")
		)
		(fp_line
			(start -0.508 -0.3048)
			(end -0.508 0.3048)
			(stroke
				(width 0.1)
				(type default)
			)
			(layer "B.Fab")
		)
		(fp_line
			(start -0.508 0.3048)
			(end 0.508 0.3048)
			(stroke
				(width 0.1)
				(type default)
			)
			(layer "B.Fab")
		)
		(fp_line
			(start 0.508 -0.3048)
			(end -0.508 -0.3048)
			(stroke
				(width 0.1)
				(type default)
			)
			(layer "B.Fab")
		)
		(fp_line
			(start 0.508 0.3048)
			(end 0.508 -0.3048)
			(stroke
				(width 0.1)
				(type default)
			)
			(layer "B.Fab")
		)
		(pad "1" smd circle
			(at 0.500126 0 180)
			(size 0.635 0.635)
			(layers "B.Cu" "B.Mask" "B.Paste")
			(net "XP2R5V_FPGA")
		)
		(pad "2" smd circle
			(at -0.500126 0 180)
			(size 0.635 0.635)
			(layers "B.Cu" "B.Mask" "B.Paste")
			(net "SG")
		)
	)
	(footprint ""
		(layer "B.Cu")
		(at 112.84712 -36.323016 90)
		(property "Reference" "C135"
			(at -2.287016 -0.10287 270)
			(unlocked yes)
			(layer "B.SilkS")
			(effects
				(font
					(size 0.635 0.4064)
					(thickness 0.1524)
				)
				(justify mirror)
			)
		)
		(property "Value" "VAL*"
			(at 0 3.718306 90)
			(unlocked yes)
			(layer "B.Fab")
			(hide yes)
			(effects
				(font
					(size 0.7874 0.5842)
					(thickness 0.127)
				)
				(justify mirror)
			)
		)
		(property "Tolerance" "TOL*"
			(at 0 4.861306 90)
			(unlocked yes)
			(layer "Cmts.User")
			(hide yes)
			(effects
				(font
					(size 0.7874 0.5842)
					(thickness 0.127)
				)
				(justify mirror)
			)
		)
		(property "User Part Number" "PARTNUM*"
			(at 0 2.575306 90)
			(unlocked yes)
			(layer "Cmts.User")
			(hide yes)
			(effects
				(font
					(size 0.7874 0.5842)
					(thickness 0.127)
				)
				(justify mirror)
			)
		)
		(property "Device Type" "CAPACITOR-G105-0B104-CK,0.1UF,A"
			(at 0 1.432306 90)
			(unlocked yes)
			(layer "B.Fab")
			(hide yes)
			(effects
				(font
					(size 0.7874 0.5842)
					(thickness 0.127)
				)
				(justify mirror)
			)
		)
		(duplicate_pad_numbers_are_jumpers no)
		(fp_line
			(start 0.970026 -0.4699)
			(end -0.970026 -0.4699)
			(stroke
				(width 0.1)
				(type default)
			)
			(layer "B.SilkS")
		)
		(fp_line
			(start -0.970026 -0.4699)
			(end -0.970026 0.4699)
			(stroke
				(width 0.1)
				(type default)
			)
			(layer "B.SilkS")
		)
		(fp_line
			(start 0.970026 0.4699)
			(end 0.970026 -0.4699)
			(stroke
				(width 0.1)
				(type default)
			)
			(layer "B.SilkS")
		)
		(fp_line
			(start -0.970026 0.4699)
			(end 0.970026 0.4699)
			(stroke
				(width 0.1)
				(type default)
			)
			(layer "B.SilkS")
		)
		(fp_poly
			(pts
				(xy 0.970026 0.4699) (xy -0.970026 0.4699) (xy -0.970026 -0.4699) (xy 0.970026 -0.4699)
			)
			(stroke
				(width 0)
				(type default)
			)
			(fill no)
			(layer "B.CrtYd")
		)
		(fp_line
			(start 0.508 -0.3048)
			(end -0.508 -0.3048)
			(stroke
				(width 0.1)
				(type default)
			)
			(layer "B.Fab")
		)
		(fp_line
			(start -0.508 -0.3048)
			(end -0.508 0.3048)
			(stroke
				(width 0.1)
				(type default)
			)
			(layer "B.Fab")
		)
		(fp_line
			(start 0.508 0.3048)
			(end 0.508 -0.3048)
			(stroke
				(width 0.1)
				(type default)
			)
			(layer "B.Fab")
		)
		(fp_line
			(start -0.508 0.3048)
			(end 0.508 0.3048)
			(stroke
				(width 0.1)
				(type default)
			)
			(layer "B.Fab")
		)
		(pad "1" smd circle
			(at 0.500126 0 270)
			(size 0.635 0.635)
			(layers "B.Cu" "B.Mask" "B.Paste")
			(net "XP2R5V_FPGA")
		)
		(pad "2" smd circle
			(at -0.500126 0 270)
			(size 0.635 0.635)
			(layers "B.Cu" "B.Mask" "B.Paste")
			(net "SG")
		)
	)
	(footprint ""
		(layer "B.Cu")
		(at 145.1102 -68.0974 -90)
		(property "Reference" "CR7"
			(at -3.11023 -0.0508 0)
			(unlocked yes)
			(layer "B.SilkS")
			(effects
				(font
					(size 0.7874 0.5842)
					(thickness 0.1524)
				)
				(justify mirror)
			)
		)
		(property "Value" ""
			(at 0 0 90)
			(layer "B.Fab")
			(effects
				(font
					(size 1.27 1.27)
				)
				(justify mirror)
			)
		)
		(property "Device Type" "DIODE_4_V1-G122-10123-01"
			(at -0.254 2.702306 270)
			(unlocked yes)
			(layer "B.Fab")
			(hide yes)
			(effects
				(font
					(size 0.7874 0.5842)
					(thickness 0.1524)
				)
				(justify mirror)
			)
		)
		(property "User Part Number" "PARTNUM*"
			(at -0.254 3.718306 270)
			(unlocked yes)
			(layer "Cmts.User")
			(hide yes)
			(effects
				(font
					(size 0.7874 0.5842)
					(thickness 0.1524)
				)
				(justify mirror)
			)
		)
		(duplicate_pad_numbers_are_jumpers no)
		(fp_line
			(start -2.0828 1.7018)
			(end 2.0828 1.7018)
			(stroke
				(width 0.1)
				(type default)
			)
			(layer "B.SilkS")
		)
		(fp_line
			(start 2.0828 1.7018)
			(end 2.0828 -1.7018)
			(stroke
				(width 0.1)
				(type default)
			)
			(layer "B.SilkS")
		)
		(fp_line
			(start -2.0828 -1.7018)
			(end -2.0828 1.7018)
			(stroke
				(width 0.1)
				(type default)
			)
			(layer "B.SilkS")
		)
		(fp_line
			(start 2.0828 -1.7018)
			(end -2.0828 -1.7018)
			(stroke
				(width 0.1)
				(type default)
			)
			(layer "B.SilkS")
		)
		(fp_poly
			(pts
				(arc
					(start 2.6162 -1.27)
					(mid 2.6162 -0.508)
					(end 2.6162 -1.27)
				)
			)
			(stroke
				(width 0)
				(type default)
			)
			(fill yes)
			(layer "B.SilkS")
		)
		(fp_rect
			(start -2.3368 1.9304)
			(end 2.3368 -1.9304)
			(stroke
				(width 0)
				(type default)
			)
			(fill no)
			(layer "B.CrtYd")
		)
		(fp_line
			(start -0.6477 1.42875)
			(end 0.6477 1.42875)
			(stroke
				(width 0.1)
				(type default)
			)
			(layer "B.Fab")
		)
		(fp_line
			(start 0.6477 1.42875)
			(end 0.6477 -1.42875)
			(stroke
				(width 0.1)
				(type default)
			)
			(layer "B.Fab")
		)
		(fp_line
			(start -1.143 1.1811)
			(end -0.6477 1.1811)
			(stroke
				(width 0.1)
				(type default)
			)
			(layer "B.Fab")
		)
		(fp_line
			(start -0.6477 1.1811)
			(end -0.6477 0.7239)
			(stroke
				(width 0.1)
				(type default)
			)
			(layer "B.Fab")
		)
		(fp_line
			(start 0.6477 1.1811)
			(end 1.143 1.1811)
			(stroke
				(width 0.1)
				(type default)
			)
			(layer "B.Fab")
		)
		(fp_line
			(start 1.143 1.1811)
			(end 1.143 0.7239)
			(stroke
				(width 0.1)
				(type default)
			)
			(layer "B.Fab")
		)
		(fp_line
			(start -1.143 0.7239)
			(end -1.143 1.1811)
			(stroke
				(width 0.1)
				(type default)
			)
			(layer "B.Fab")
		)
		(fp_line
			(start -0.6477 0.7239)
			(end -1.143 0.7239)
			(stroke
				(width 0.1)
				(type default)
			)
			(layer "B.Fab")
		)
		(fp_line
			(start 0.6477 0.7239)
			(end 0.6477 1.1811)
			(stroke
				(width 0.1)
				(type default)
			)
			(layer "B.Fab")
		)
		(fp_line
			(start 1.143 0.7239)
			(end 0.6477 0.7239)
			(stroke
				(width 0.1)
				(type default)
			)
			(layer "B.Fab")
		)
		(fp_line
			(start 0.6477 -0.3175)
			(end 1.143 -0.3175)
			(stroke
				(width 0.1)
				(type default)
			)
			(layer "B.Fab")
		)
		(fp_line
			(start 1.143 -0.3175)
			(end 1.143 -1.1811)
			(stroke
				(width 0.1)
				(type default)
			)
			(layer "B.Fab")
		)
		(fp_line
			(start -1.143 -0.7239)
			(end -0.6477 -0.7239)
			(stroke
				(width 0.1)
				(type default)
			)
			(layer "B.Fab")
		)
		(fp_line
			(start -0.6477 -0.7239)
			(end -0.6477 -1.1811)
			(stroke
				(width 0.1)
				(type default)
			)
			(layer "B.Fab")
		)
		(fp_line
			(start -1.143 -1.1811)
			(end -1.143 -0.7239)
			(stroke
				(width 0.1)
				(type default)
			)
			(layer "B.Fab")
		)
		(fp_line
			(start -0.6477 -1.1811)
			(end -1.143 -1.1811)
			(stroke
				(width 0.1)
				(type default)
			)
			(layer "B.Fab")
		)
		(fp_line
			(start 0.6477 -1.1811)
			(end 0.6477 -0.3175)
			(stroke
				(width 0.1)
				(type default)
			)
			(layer "B.Fab")
		)
		(fp_line
			(start 1.143 -1.1811)
			(end 0.6477 -1.1811)
			(stroke
				(width 0.1)
				(type default)
			)
			(layer "B.Fab")
		)
		(fp_line
			(start -0.6477 -1.42875)
			(end -0.6477 1.42875)
			(stroke
				(width 0.1)
				(type default)
			)
			(layer "B.Fab")
		)
		(fp_line
			(start 0.6477 -1.42875)
			(end -0.6477 -1.42875)
			(stroke
				(width 0.1)
				(type default)
			)
			(layer "B.Fab")
		)
		(fp_poly
			(pts
				(arc
					(start 0.381 -0.9398)
					(mid 0.381 -0.5588)
					(end 0.381 -0.9398)
				)
			)
			(stroke
				(width 0)
				(type default)
			)
			(fill yes)
			(layer "B.Fab")
		)
		(fp_text user "3"
			(at -1.84023 1.8161 0)
			(unlocked yes)
			(layer "B.SilkS")
			(effects
				(font
					(size 0.7874 0.5842)
					(thickness 0.1524)
				)
				(justify left mirror)
			)
		)
		(fp_text user "2"
			(at 2.85877 0.8001 0)
			(unlocked yes)
			(layer "B.SilkS")
			(effects
				(font
					(size 0.7874 0.5842)
					(thickness 0.1524)
				)
				(justify left mirror)
			)
		)
		(fp_text user "4"
			(at -2.09423 -2.6289 0)
			(unlocked yes)
			(layer "B.SilkS")
			(effects
				(font
					(size 0.7874 0.5842)
					(thickness 0.1524)
				)
				(justify left mirror)
			)
		)
		(fp_text user "3"
			(at -1.76403 0.669036 0)
			(unlocked yes)
			(layer "B.Fab")
			(effects
				(font
					(size 0.7874 0.5842)
					(thickness 0.1524)
				)
				(justify left mirror)
			)
		)
		(fp_text user "2"
			(at 1.83007 0.5842 0)
			(unlocked yes)
			(layer "B.Fab")
			(effects
				(font
					(size 0.7874 0.5842)
					(thickness 0.1524)
				)
				(justify left mirror)
			)
		)
		(fp_text user "4"
			(at -1.78943 -1.261618 0)
			(unlocked yes)
			(layer "B.Fab")
			(effects
				(font
					(size 0.7874 0.5842)
					(thickness 0.1524)
				)
				(justify left mirror)
			)
		)
		(pad "1" smd rect
			(at 1.1049 -0.7493 90)
			(size 1.4478 1.0922)
			(layers "B.Cu" "B.Mask" "B.Paste")
			(net "SG")
		)
		(pad "2" smd rect
			(at 1.1049 0.9525 90)
			(size 1.4478 0.9906)
			(layers "B.Cu" "B.Mask" "B.Paste")
			(net "FT4232_FPGA_TCK")
		)
		(pad "3" smd rect
			(at -1.1049 0.9525 90)
			(size 1.4478 0.9906)
			(layers "B.Cu" "B.Mask" "B.Paste")
			(net "FT4232_FPGA_TDO")
		)
		(pad "4" smd rect
			(at -1.1049 -0.9525 90)
			(size 1.4478 0.9906)
			(layers "B.Cu" "B.Mask" "B.Paste")
			(net "Net_624")
		)
		(zone
			(layer "B.Cu")
			(hatch none 0.5)
			(connect_pads
				(clearance 0)
			)
			(min_thickness 0.25)
			(keepout
				(tracks allowed)
				(vias not_allowed)
				(pads allowed)
				(copperpour not_allowed)
				(footprints allowed)
			)
			(placement
				(enabled no)
				(sheetname "")
			)
			(fill
				(thermal_gap 0.5)
				(thermal_bridge_width 0.5)
				(island_removal_mode 0)
			)
			(polygon
				(pts
					(xy 146.4056 -67.4497) (xy 146.5453 -67.4497) (xy 146.5453 -68.4784) (xy 145.5674 -68.4784) (xy 145.5674 -68.7451)
					(xy 144.653 -68.7451) (xy 144.653 -68.4784) (xy 143.6751 -68.4784) (xy 143.6751 -67.7164) (xy 144.653 -67.7164)
					(xy 144.653 -67.4497) (xy 145.3134 -67.4497) (xy 145.3134 -67.7164) (xy 146.4056 -67.7164)
				)
			)
		)
	)
	(footprint ""
		(layer "B.Cu")
		(at 108.585 -23.876 -90)
		(property "Reference" "C246"
			(at -0.127 2.96037 270)
			(unlocked yes)
			(layer "B.SilkS")
			(effects
				(font
					(size 0.7874 0.5842)
					(thickness 0.1524)
				)
				(justify mirror)
			)
		)
		(property "Value" "VAL*"
			(at -0.0762 2.067306 270)
			(unlocked yes)
			(layer "B.Fab")
			(hide yes)
			(effects
				(font
					(size 0.7874 0.5842)
					(thickness 0.1524)
				)
				(justify mirror)
			)
		)
		(property "Device Type" "CAPACITOR-G105-0C106-BM,10UF,2A"
			(at -0.0508 1.127506 270)
			(unlocked yes)
			(layer "B.Fab")
			(hide yes)
			(effects
				(font
					(size 0.7874 0.5842)
					(thickness 0.1524)
				)
				(justify mirror)
			)
		)
		(property "User Part Number" "PARTNUM*"
			(at -0.1016 4.023106 270)
			(unlocked yes)
			(layer "Cmts.User")
			(hide yes)
			(effects
				(font
					(size 0.7874 0.5842)
					(thickness 0.1524)
				)
				(justify mirror)
			)
		)
		(property "Tolerance" "TOL*"
			(at -0.0762 3.032506 270)
			(unlocked yes)
			(layer "Cmts.User")
			(hide yes)
			(effects
				(font
					(size 0.7874 0.5842)
					(thickness 0.1524)
				)
				(justify mirror)
			)
		)
		(duplicate_pad_numbers_are_jumpers no)
		(fp_line
			(start -1.143 0.5588)
			(end -1.143 -0.5588)
			(stroke
				(width 0.1)
				(type default)
			)
			(layer "B.SilkS")
		)
		(fp_line
			(start 1.143 0.5588)
			(end -1.143 0.5588)
			(stroke
				(width 0.1)
				(type default)
			)
			(layer "B.SilkS")
		)
		(fp_line
			(start -1.143 -0.5588)
			(end 1.143 -0.5588)
			(stroke
				(width 0.1)
				(type default)
			)
			(layer "B.SilkS")
		)
		(fp_line
			(start 1.143 -0.5588)
			(end 1.143 0.5588)
			(stroke
				(width 0.1)
				(type default)
			)
			(layer "B.SilkS")
		)
		(fp_rect
			(start 1.143 0.5588)
			(end -1.143 -0.5588)
			(stroke
				(width 0)
				(type default)
			)
			(fill no)
			(layer "B.CrtYd")
		)
		(fp_line
			(start -0.508 0.3048)
			(end -0.508 -0.3048)
			(stroke
				(width 0.1)
				(type default)
			)
			(layer "B.Fab")
		)
		(fp_line
			(start 0.508 0.3048)
			(end -0.508 0.3048)
			(stroke
				(width 0.1)
				(type default)
			)
			(layer "B.Fab")
		)
		(fp_line
			(start -0.508 -0.3048)
			(end 0.508 -0.3048)
			(stroke
				(width 0.1)
				(type default)
			)
			(layer "B.Fab")
		)
		(fp_line
			(start 0.508 -0.3048)
			(end 0.508 0.3048)
			(stroke
				(width 0.1)
				(type default)
			)
			(layer "B.Fab")
		)
		(pad "1" smd rect
			(at 0.5334 0 90)
			(size 0.7112 0.6096)
			(layers "B.Cu" "B.Mask" "B.Paste")
			(net "VDD3V3_OSC_200M")
		)
		(pad "2" smd rect
			(at -0.5334 0 90)
			(size 0.7112 0.6096)
			(layers "B.Cu" "B.Mask" "B.Paste")
			(net "SG")
		)
		(zone
			(layer "B.Cu")
			(hatch none 0.5)
			(connect_pads
				(clearance 0)
			)
			(min_thickness 0.25)
			(keepout
				(tracks allowed)
				(vias not_allowed)
				(pads allowed)
				(copperpour not_allowed)
				(footprints allowed)
			)
			(placement
				(enabled no)
				(sheetname "")
			)
			(fill
				(thermal_gap 0.5)
				(thermal_bridge_width 0.5)
				(island_removal_mode 0)
			)
			(polygon
				(pts
					(xy 108.2802 -23.7998) (xy 108.8898 -23.7998) (xy 108.8898 -23.9522) (xy 108.2802 -23.9522)
				)
			)
		)
	)
	(footprint ""
		(layer "B.Cu")
		(at 124.587 -47.117)
		(property "Reference" "R92"
			(at 4.064 0.16637 0)
			(unlocked yes)
			(layer "B.SilkS")
			(effects
				(font
					(size 0.7874 0.5842)
					(thickness 0.1524)
				)
				(justify mirror)
			)
		)
		(property "Value" "VAL*"
			(at -0.02032 2.13233 0)
			(unlocked yes)
			(layer "B.Fab")
			(hide yes)
			(effects
				(font
					(size 0.7874 0.5842)
					(thickness 0.1524)
				)
				(justify mirror)
			)
		)
		(property "Tolerance" "TOL*"
			(at -0.044704 3.05435 0)
			(unlocked yes)
			(layer "Cmts.User")
			(hide yes)
			(effects
				(font
					(size 0.7874 0.5842)
					(thickness 0.1524)
				)
				(justify mirror)
			)
		)
		(property "User Part Number" "PARTNUM*"
			(at -0.02032 4.024884 0)
			(unlocked yes)
			(layer "Cmts.User")
			(hide yes)
			(effects
				(font
					(size 0.7874 0.5842)
					(thickness 0.1524)
				)
				(justify mirror)
			)
		)
		(property "Device Type" "RESISTOR-G155-100R0-J0,0OHM,-"
			(at -0.008382 1.210564 0)
			(unlocked yes)
			(layer "B.Fab")
			(hide yes)
			(effects
				(font
					(size 0.7874 0.5842)
					(thickness 0.1524)
				)
				(justify mirror)
			)
		)
		(duplicate_pad_numbers_are_jumpers no)
		(fp_line
			(start -1.143 -0.5588)
			(end 1.143 -0.5588)
			(stroke
				(width 0.1)
				(type default)
			)
			(layer "B.SilkS")
		)
		(fp_line
			(start -1.143 0.5588)
			(end -1.143 -0.5588)
			(stroke
				(width 0.1)
				(type default)
			)
			(layer "B.SilkS")
		)
		(fp_line
			(start 1.143 -0.5588)
			(end 1.143 0.5588)
			(stroke
				(width 0.1)
				(type default)
			)
			(layer "B.SilkS")
		)
		(fp_line
			(start 1.143 0.5588)
			(end -1.143 0.5588)
			(stroke
				(width 0.1)
				(type default)
			)
			(layer "B.SilkS")
		)
		(fp_poly
			(pts
				(xy 1.143 0.5588) (xy -1.143 0.5588) (xy -1.143 -0.5588) (xy 1.143 -0.5588)
			)
			(stroke
				(width 0)
				(type default)
			)
			(fill no)
			(layer "B.CrtYd")
		)
		(fp_line
			(start -0.508 -0.3048)
			(end 0.508 -0.3048)
			(stroke
				(width 0.1)
				(type default)
			)
			(layer "B.Fab")
		)
		(fp_line
			(start -0.508 0.3048)
			(end -0.508 -0.3048)
			(stroke
				(width 0.1)
				(type default)
			)
			(layer "B.Fab")
		)
		(fp_line
			(start 0.508 -0.3048)
			(end 0.508 0.3048)
			(stroke
				(width 0.1)
				(type default)
			)
			(layer "B.Fab")
		)
		(fp_line
			(start 0.508 0.3048)
			(end -0.508 0.3048)
			(stroke
				(width 0.1)
				(type default)
			)
			(layer "B.Fab")
		)
		(pad "1" smd rect
			(at 0.5334 0 180)
			(size 0.7112 0.6096)
			(layers "B.Cu" "B.Mask" "B.Paste")
			(net "R_MAC_10MHZ_RF_OUT")
		)
		(pad "2" smd rect
			(at -0.5334 0 180)
			(size 0.7112 0.6096)
			(layers "B.Cu" "B.Mask" "B.Paste")
			(net "FPGA_IN_MAC_10MHZ_OUT")
		)
		(zone
			(layer "B.Cu")
			(hatch none 0.5)
			(connect_pads
				(clearance 0)
			)
			(min_thickness 0.25)
			(keepout
				(tracks allowed)
				(vias not_allowed)
				(pads allowed)
				(copperpour not_allowed)
				(footprints allowed)
			)
			(placement
				(enabled no)
				(sheetname "")
			)
			(fill
				(thermal_gap 0.5)
				(thermal_bridge_width 0.5)
				(island_removal_mode 0)
			)
			(polygon
				(pts
					(xy 124.6632 -46.8122) (xy 124.6632 -47.4218) (xy 124.5108 -47.4218) (xy 124.5108 -46.8122)
				)
			)
		)
		(zone
			(layer "B.Cu")
			(hatch none 0.5)
			(connect_pads
				(clearance 0)
			)
			(min_thickness 0.25)
			(keepout
				(tracks not_allowed)
				(vias allowed)
				(pads allowed)
				(copperpour not_allowed)
				(footprints allowed)
			)
			(placement
				(enabled no)
				(sheetname "")
			)
			(fill
				(thermal_gap 0.5)
				(thermal_bridge_width 0.5)
				(island_removal_mode 0)
			)
			(polygon
				(pts
					(xy 124.6632 -46.8122) (xy 124.6632 -47.4218) (xy 124.5108 -47.4218) (xy 124.5108 -46.8122)
				)
			)
		)
	)
	(footprint ""
		(layer "B.Cu")
		(at 147.066 -104.648 180)
		(property "Reference" "R256"
			(at -1.016 -3.21437 0)
			(unlocked yes)
			(layer "B.SilkS")
			(effects
				(font
					(size 0.7874 0.5842)
					(thickness 0.1524)
				)
				(justify mirror)
			)
		)
		(property "Value" "VAL*"
			(at -0.02032 2.13233 180)
			(unlocked yes)
			(layer "B.Fab")
			(hide yes)
			(effects
				(font
					(size 0.7874 0.5842)
					(thickness 0.1524)
				)
				(justify mirror)
			)
		)
		(property "Tolerance" "TOL*"
			(at -0.044704 3.05435 180)
			(unlocked yes)
			(layer "Cmts.User")
			(hide yes)
			(effects
				(font
					(size 0.7874 0.5842)
					(thickness 0.1524)
				)
				(justify mirror)
			)
		)
		(property "User Part Number" "PARTNUM*"
			(at -0.02032 4.024884 180)
			(unlocked yes)
			(layer "Cmts.User")
			(hide yes)
			(effects
				(font
					(size 0.7874 0.5842)
					(thickness 0.1524)
				)
				(justify mirror)
			)
		)
		(property "Device Type" "RESISTOR-G155-11001-01,1KOHM,1%"
			(at -0.008382 1.210564 180)
			(unlocked yes)
			(layer "B.Fab")
			(hide yes)
			(effects
				(font
					(size 0.7874 0.5842)
					(thickness 0.1524)
				)
				(justify mirror)
			)
		)
		(duplicate_pad_numbers_are_jumpers no)
		(fp_line
			(start 1.143 0.5588)
			(end -1.143 0.5588)
			(stroke
				(width 0.1)
				(type default)
			)
			(layer "B.SilkS")
		)
		(fp_line
			(start 1.143 -0.5588)
			(end 1.143 0.5588)
			(stroke
				(width 0.1)
				(type default)
			)
			(layer "B.SilkS")
		)
		(fp_line
			(start -1.143 0.5588)
			(end -1.143 -0.5588)
			(stroke
				(width 0.1)
				(type default)
			)
			(layer "B.SilkS")
		)
		(fp_line
			(start -1.143 -0.5588)
			(end 1.143 -0.5588)
			(stroke
				(width 0.1)
				(type default)
			)
			(layer "B.SilkS")
		)
		(fp_rect
			(start -1.143 -0.5588)
			(end 1.143 0.5588)
			(stroke
				(width 0)
				(type default)
			)
			(fill no)
			(layer "B.CrtYd")
		)
		(fp_line
			(start 0.508 0.3048)
			(end -0.508 0.3048)
			(stroke
				(width 0.1)
				(type default)
			)
			(layer "B.Fab")
		)
		(fp_line
			(start 0.508 -0.3048)
			(end 0.508 0.3048)
			(stroke
				(width 0.1)
				(type default)
			)
			(layer "B.Fab")
		)
		(fp_line
			(start -0.508 0.3048)
			(end -0.508 -0.3048)
			(stroke
				(width 0.1)
				(type default)
			)
			(layer "B.Fab")
		)
		(fp_line
			(start -0.508 -0.3048)
			(end 0.508 -0.3048)
			(stroke
				(width 0.1)
				(type default)
			)
			(layer "B.Fab")
		)
		(pad "1" smd rect
			(at 0.5334 0)
			(size 0.7112 0.6096)
			(layers "B.Cu" "B.Mask" "B.Paste")
			(net "UNNAMED_14_OPTICAL_I143_A")
		)
		(pad "2" smd rect
			(at -0.5334 0)
			(size 0.7112 0.6096)
			(layers "B.Cu" "B.Mask" "B.Paste")
			(net "UNNAMED_14_RESISTOR_I65_2")
		)
		(zone
			(layer "B.Cu")
			(hatch none 0.5)
			(connect_pads
				(clearance 0)
			)
			(min_thickness 0.25)
			(keepout
				(tracks allowed)
				(vias not_allowed)
				(pads allowed)
				(copperpour not_allowed)
				(footprints allowed)
			)
			(placement
				(enabled no)
				(sheetname "")
			)
			(fill
				(thermal_gap 0.5)
				(thermal_bridge_width 0.5)
				(island_removal_mode 0)
			)
			(polygon
				(pts
					(xy 147.1422 -104.3432) (xy 147.1422 -104.9528) (xy 146.9898 -104.9528) (xy 146.9898 -104.3432)
				)
			)
		)
	)
	(footprint ""
		(layer "B.Cu")
		(at 142.494 -50.292 180)
		(property "Reference" "C266"
			(at 0.254 -1.56337 0)
			(unlocked yes)
			(layer "B.SilkS")
			(effects
				(font
					(size 0.7874 0.5842)
					(thickness 0.1524)
				)
				(justify mirror)
			)
		)
		(property "Value" "VAL*"
			(at -0.0762 2.067306 180)
			(unlocked yes)
			(layer "B.Fab")
			(hide yes)
			(effects
				(font
					(size 0.7874 0.5842)
					(thickness 0.1524)
				)
				(justify mirror)
			)
		)
		(property "Device Type" "CAPACITOR-G105-0A102-FJ,1000PFA"
			(at -0.0508 1.127506 180)
			(unlocked yes)
			(layer "B.Fab")
			(hide yes)
			(effects
				(font
					(size 0.7874 0.5842)
					(thickness 0.1524)
				)
				(justify mirror)
			)
		)
		(property "User Part Number" "PARTNUM*"
			(at -0.1016 4.023106 180)
			(unlocked yes)
			(layer "Cmts.User")
			(hide yes)
			(effects
				(font
					(size 0.7874 0.5842)
					(thickness 0.1524)
				)
				(justify mirror)
			)
		)
		(property "Tolerance" "TOL*"
			(at -0.0762 3.032506 180)
			(unlocked yes)
			(layer "Cmts.User")
			(hide yes)
			(effects
				(font
					(size 0.7874 0.5842)
					(thickness 0.1524)
				)
				(justify mirror)
			)
		)
		(duplicate_pad_numbers_are_jumpers no)
		(fp_line
			(start 1.143 0.5588)
			(end -1.143 0.5588)
			(stroke
				(width 0.1)
				(type default)
			)
			(layer "B.SilkS")
		)
		(fp_line
			(start 1.143 -0.5588)
			(end 1.143 0.5588)
			(stroke
				(width 0.1)
				(type default)
			)
			(layer "B.SilkS")
		)
		(fp_line
			(start -1.143 0.5588)
			(end -1.143 -0.5588)
			(stroke
				(width 0.1)
				(type default)
			)
			(layer "B.SilkS")
		)
		(fp_line
			(start -1.143 -0.5588)
			(end 1.143 -0.5588)
			(stroke
				(width 0.1)
				(type default)
			)
			(layer "B.SilkS")
		)
		(fp_rect
			(start -1.143 0.5588)
			(end 1.143 -0.5588)
			(stroke
				(width 0)
				(type default)
			)
			(fill no)
			(layer "B.CrtYd")
		)
		(fp_line
			(start 0.508 0.3048)
			(end -0.508 0.3048)
			(stroke
				(width 0.1)
				(type default)
			)
			(layer "B.Fab")
		)
		(fp_line
			(start 0.508 -0.3048)
			(end 0.508 0.3048)
			(stroke
				(width 0.1)
				(type default)
			)
			(layer "B.Fab")
		)
		(fp_line
			(start -0.508 0.3048)
			(end -0.508 -0.3048)
			(stroke
				(width 0.1)
				(type default)
			)
			(layer "B.Fab")
		)
		(fp_line
			(start -0.508 -0.3048)
			(end 0.508 -0.3048)
			(stroke
				(width 0.1)
				(type default)
			)
			(layer "B.Fab")
		)
		(pad "1" smd rect
			(at 0.5334 0)
			(size 0.7112 0.6096)
			(layers "B.Cu" "B.Mask" "B.Paste")
			(net "XP1R0V_SW")
		)
		(pad "2" smd rect
			(at -0.5334 0)
			(size 0.7112 0.6096)
			(layers "B.Cu" "B.Mask" "B.Paste")
			(net "UNNAMED_523_CAPACITOR_I31_2")
		)
		(zone
			(layer "B.Cu")
			(hatch none 0.5)
			(connect_pads
				(clearance 0)
			)
			(min_thickness 0.25)
			(keepout
				(tracks allowed)
				(vias not_allowed)
				(pads allowed)
				(copperpour not_allowed)
				(footprints allowed)
			)
			(placement
				(enabled no)
				(sheetname "")
			)
			(fill
				(thermal_gap 0.5)
				(thermal_bridge_width 0.5)
				(island_removal_mode 0)
			)
			(polygon
				(pts
					(xy 142.5702 -50.5968) (xy 142.4178 -50.5968) (xy 142.4178 -49.9872) (xy 142.5702 -49.9872)
				)
			)
		)
	)
	(footprint ""
		(layer "B.Cu")
		(at 55.88 -16.129 -90)
		(property "Reference" "C290"
			(at -4.064 -0.59563 270)
			(unlocked yes)
			(layer "B.SilkS")
			(effects
				(font
					(size 0.7874 0.5842)
					(thickness 0.1524)
				)
				(justify mirror)
			)
		)
		(property "Value" "VAL*"
			(at -0.0762 2.067306 270)
			(unlocked yes)
			(layer "B.Fab")
			(hide yes)
			(effects
				(font
					(size 0.7874 0.5842)
					(thickness 0.1524)
				)
				(justify mirror)
			)
		)
		(property "Device Type" "CAPACITOR-G105-0B104-EK,0.1UF,A"
			(at -0.0508 1.127506 270)
			(unlocked yes)
			(layer "B.Fab")
			(hide yes)
			(effects
				(font
					(size 0.7874 0.5842)
					(thickness 0.1524)
				)
				(justify mirror)
			)
		)
		(property "User Part Number" "PARTNUM*"
			(at -0.1016 4.023106 270)
			(unlocked yes)
			(layer "Cmts.User")
			(hide yes)
			(effects
				(font
					(size 0.7874 0.5842)
					(thickness 0.1524)
				)
				(justify mirror)
			)
		)
		(property "Tolerance" "TOL*"
			(at -0.0762 3.032506 270)
			(unlocked yes)
			(layer "Cmts.User")
			(hide yes)
			(effects
				(font
					(size 0.7874 0.5842)
					(thickness 0.1524)
				)
				(justify mirror)
			)
		)
		(duplicate_pad_numbers_are_jumpers no)
		(fp_line
			(start -1.143 0.5588)
			(end -1.143 -0.5588)
			(stroke
				(width 0.1)
				(type default)
			)
			(layer "B.SilkS")
		)
		(fp_line
			(start 1.143 0.5588)
			(end -1.143 0.5588)
			(stroke
				(width 0.1)
				(type default)
			)
			(layer "B.SilkS")
		)
		(fp_line
			(start -1.143 -0.5588)
			(end 1.143 -0.5588)
			(stroke
				(width 0.1)
				(type default)
			)
			(layer "B.SilkS")
		)
		(fp_line
			(start 1.143 -0.5588)
			(end 1.143 0.5588)
			(stroke
				(width 0.1)
				(type default)
			)
			(layer "B.SilkS")
		)
		(fp_poly
			(pts
				(xy 1.143 0.5588) (xy -1.143 0.5588) (xy -1.143 -0.5588) (xy 1.143 -0.5588)
			)
			(stroke
				(width 0)
				(type default)
			)
			(fill no)
			(layer "B.CrtYd")
		)
		(fp_line
			(start -0.508 0.3048)
			(end -0.508 -0.3048)
			(stroke
				(width 0.1)
				(type default)
			)
			(layer "B.Fab")
		)
		(fp_line
			(start 0.508 0.3048)
			(end -0.508 0.3048)
			(stroke
				(width 0.1)
				(type default)
			)
			(layer "B.Fab")
		)
		(fp_line
			(start -0.508 -0.3048)
			(end 0.508 -0.3048)
			(stroke
				(width 0.1)
				(type default)
			)
			(layer "B.Fab")
		)
		(fp_line
			(start 0.508 -0.3048)
			(end 0.508 0.3048)
			(stroke
				(width 0.1)
				(type default)
			)
			(layer "B.Fab")
		)
		(pad "1" smd rect
			(at 0.5334 0 90)
			(size 0.7112 0.6096)
			(layers "B.Cu" "B.Mask" "B.Paste")
			(net "XP3R3V_PCIE")
		)
		(pad "2" smd rect
			(at -0.5334 0 90)
			(size 0.7112 0.6096)
			(layers "B.Cu" "B.Mask" "B.Paste")
			(net "SG")
		)
		(zone
			(layer "B.Cu")
			(hatch none 0.5)
			(connect_pads
				(clearance 0)
			)
			(min_thickness 0.25)
			(keepout
				(tracks allowed)
				(vias not_allowed)
				(pads allowed)
				(copperpour not_allowed)
				(footprints allowed)
			)
			(placement
				(enabled no)
				(sheetname "")
			)
			(fill
				(thermal_gap 0.5)
				(thermal_bridge_width 0.5)
				(island_removal_mode 0)
			)
			(polygon
				(pts
					(xy 55.5752 -16.0528) (xy 56.1848 -16.0528) (xy 56.1848 -16.2052) (xy 55.5752 -16.2052)
				)
			)
		)
		(zone
			(layer "B.Cu")
			(hatch none 0.5)
			(connect_pads
				(clearance 0)
			)
			(min_thickness 0.25)
			(keepout
				(tracks not_allowed)
				(vias allowed)
				(pads allowed)
				(copperpour not_allowed)
				(footprints allowed)
			)
			(placement
				(enabled no)
				(sheetname "")
			)
			(fill
				(thermal_gap 0.5)
				(thermal_bridge_width 0.5)
				(island_removal_mode 0)
			)
			(polygon
				(pts
					(xy 55.5752 -16.0528) (xy 56.1848 -16.0528) (xy 56.1848 -16.2052) (xy 55.5752 -16.2052)
				)
			)
		)
	)
	(footprint ""
		(layer "B.Cu")
		(at 21.0566 -42.7736)
		(property "Reference" "R58"
			(at -1.3716 -1.25603 0)
			(unlocked yes)
			(layer "B.SilkS")
			(effects
				(font
					(size 0.7874 0.5842)
					(thickness 0.1524)
				)
				(justify mirror)
			)
		)
		(property "Value" "VAL*"
			(at -0.02032 2.13233 0)
			(unlocked yes)
			(layer "B.Fab")
			(hide yes)
			(effects
				(font
					(size 0.7874 0.5842)
					(thickness 0.1524)
				)
				(justify mirror)
			)
		)
		(property "Device Type" "RESISTOR-G155-133R0-01,33OHM,1%"
			(at -0.008382 1.210564 0)
			(unlocked yes)
			(layer "B.Fab")
			(hide yes)
			(effects
				(font
					(size 0.7874 0.5842)
					(thickness 0.1524)
				)
				(justify mirror)
			)
		)
		(property "User Part Number" "PARTNUM*"
			(at -0.02032 4.024884 0)
			(unlocked yes)
			(layer "Cmts.User")
			(hide yes)
			(effects
				(font
					(size 0.7874 0.5842)
					(thickness 0.1524)
				)
				(justify mirror)
			)
		)
		(property "Tolerance" "TOL*"
			(at -0.044704 3.05435 0)
			(unlocked yes)
			(layer "Cmts.User")
			(hide yes)
			(effects
				(font
					(size 0.7874 0.5842)
					(thickness 0.1524)
				)
				(justify mirror)
			)
		)
		(duplicate_pad_numbers_are_jumpers no)
		(fp_line
			(start -1.143 -0.5588)
			(end 1.143 -0.5588)
			(stroke
				(width 0.1)
				(type default)
			)
			(layer "B.SilkS")
		)
		(fp_line
			(start -1.143 0.5588)
			(end -1.143 -0.5588)
			(stroke
				(width 0.1)
				(type default)
			)
			(layer "B.SilkS")
		)
		(fp_line
			(start 1.143 -0.5588)
			(end 1.143 0.5588)
			(stroke
				(width 0.1)
				(type default)
			)
			(layer "B.SilkS")
		)
		(fp_line
			(start 1.143 0.5588)
			(end -1.143 0.5588)
			(stroke
				(width 0.1)
				(type default)
			)
			(layer "B.SilkS")
		)
		(fp_rect
			(start 1.143 0.5588)
			(end -1.143 -0.5588)
			(stroke
				(width 0)
				(type default)
			)
			(fill no)
			(layer "B.CrtYd")
		)
		(fp_line
			(start -0.508 -0.3048)
			(end 0.508 -0.3048)
			(stroke
				(width 0.1)
				(type default)
			)
			(layer "B.Fab")
		)
		(fp_line
			(start -0.508 0.3048)
			(end -0.508 -0.3048)
			(stroke
				(width 0.1)
				(type default)
			)
			(layer "B.Fab")
		)
		(fp_line
			(start 0.508 -0.3048)
			(end 0.508 0.3048)
			(stroke
				(width 0.1)
				(type default)
			)
			(layer "B.Fab")
		)
		(fp_line
			(start 0.508 0.3048)
			(end -0.508 0.3048)
			(stroke
				(width 0.1)
				(type default)
			)
			(layer "B.Fab")
		)
		(pad "1" smd rect
			(at 0.5334 0 180)
			(size 0.7112 0.6096)
			(layers "B.Cu" "B.Mask" "B.Paste")
			(net "UNNAMED_5_CONNHDR2X2MSSMT_I126_")
		)
		(pad "2" smd rect
			(at -0.5334 0 180)
			(size 0.7112 0.6096)
			(layers "B.Cu" "B.Mask" "B.Paste")
			(net "R_PCA9546_I2C_SDA")
		)
		(zone
			(layer "B.Cu")
			(hatch none 0.5)
			(connect_pads
				(clearance 0)
			)
			(min_thickness 0.25)
			(keepout
				(tracks allowed)
				(vias not_allowed)
				(pads allowed)
				(copperpour not_allowed)
				(footprints allowed)
			)
			(placement
				(enabled no)
				(sheetname "")
			)
			(fill
				(thermal_gap 0.5)
				(thermal_bridge_width 0.5)
				(island_removal_mode 0)
			)
			(polygon
				(pts
					(xy 21.1328 -42.4688) (xy 21.1328 -43.0784) (xy 20.9804 -43.0784) (xy 20.9804 -42.4688)
				)
			)
		)
	)
	(footprint ""
		(layer "B.Cu")
		(at 115.166394 -44.577 180)
		(property "Reference" "C165"
			(at 43.030394 -1.93675 0)
			(unlocked yes)
			(layer "B.SilkS")
			(effects
				(font
					(size 0.635 0.4064)
					(thickness 0.1524)
				)
				(justify mirror)
			)
		)
		(property "Value" "VAL*"
			(at -0.0762 2.067306 180)
			(unlocked yes)
			(layer "B.Fab")
			(hide yes)
			(effects
				(font
					(size 0.7874 0.5842)
					(thickness 0.1524)
				)
				(justify mirror)
			)
		)
		(property "Device Type" "CAPACITOR-G105-0B104-CK,0.1UF,A"
			(at -0.0508 1.127506 180)
			(unlocked yes)
			(layer "B.Fab")
			(hide yes)
			(effects
				(font
					(size 0.7874 0.5842)
					(thickness 0.1524)
				)
				(justify mirror)
			)
		)
		(property "User Part Number" "PARTNUM*"
			(at -0.1016 4.023106 180)
			(unlocked yes)
			(layer "Cmts.User")
			(hide yes)
			(effects
				(font
					(size 0.7874 0.5842)
					(thickness 0.1524)
				)
				(justify mirror)
			)
		)
		(property "Tolerance" "TOL*"
			(at -0.0762 3.032506 180)
			(unlocked yes)
			(layer "Cmts.User")
			(hide yes)
			(effects
				(font
					(size 0.7874 0.5842)
					(thickness 0.1524)
				)
				(justify mirror)
			)
		)
		(duplicate_pad_numbers_are_jumpers no)
		(fp_line
			(start 1.143 0.5588)
			(end -1.143 0.5588)
			(stroke
				(width 0.1)
				(type default)
			)
			(layer "B.SilkS")
		)
		(fp_line
			(start 1.143 -0.5588)
			(end 1.143 0.5588)
			(stroke
				(width 0.1)
				(type default)
			)
			(layer "B.SilkS")
		)
		(fp_line
			(start -1.143 0.5588)
			(end -1.143 -0.5588)
			(stroke
				(width 0.1)
				(type default)
			)
			(layer "B.SilkS")
		)
		(fp_line
			(start -1.143 -0.5588)
			(end 1.143 -0.5588)
			(stroke
				(width 0.1)
				(type default)
			)
			(layer "B.SilkS")
		)
		(fp_rect
			(start 1.143 -0.5588)
			(end -1.143 0.5588)
			(stroke
				(width 0)
				(type default)
			)
			(fill no)
			(layer "B.CrtYd")
		)
		(fp_line
			(start 0.508 0.3048)
			(end -0.508 0.3048)
			(stroke
				(width 0.1)
				(type default)
			)
			(layer "B.Fab")
		)
		(fp_line
			(start 0.508 -0.3048)
			(end 0.508 0.3048)
			(stroke
				(width 0.1)
				(type default)
			)
			(layer "B.Fab")
		)
		(fp_line
			(start -0.508 0.3048)
			(end -0.508 -0.3048)
			(stroke
				(width 0.1)
				(type default)
			)
			(layer "B.Fab")
		)
		(fp_line
			(start -0.508 -0.3048)
			(end 0.508 -0.3048)
			(stroke
				(width 0.1)
				(type default)
			)
			(layer "B.Fab")
		)
		(pad "1" smd rect
			(at 0.5334 0)
			(size 0.7112 0.6096)
			(layers "B.Cu" "B.Mask" "B.Paste")
			(net "XP3R3V_FPGA")
		)
		(pad "2" smd rect
			(at -0.5334 0)
			(size 0.7112 0.6096)
			(layers "B.Cu" "B.Mask" "B.Paste")
			(net "SG")
		)
		(zone
			(layer "B.Cu")
			(hatch none 0.5)
			(connect_pads
				(clearance 0)
			)
			(min_thickness 0.25)
			(keepout
				(tracks allowed)
				(vias not_allowed)
				(pads allowed)
				(copperpour not_allowed)
				(footprints allowed)
			)
			(placement
				(enabled no)
				(sheetname "")
			)
			(fill
				(thermal_gap 0.5)
				(thermal_bridge_width 0.5)
				(island_removal_mode 0)
			)
			(polygon
				(pts
					(xy 115.090194 -44.2722) (xy 115.242594 -44.2722) (xy 115.242594 -44.8818) (xy 115.090194 -44.8818)
				)
			)
		)
	)
	(footprint ""
		(layer "B.Cu")
		(at 88.519 -85.598 180)
		(property "Reference" "R199"
			(at -0.254 5.42163 0)
			(unlocked yes)
			(layer "B.SilkS")
			(effects
				(font
					(size 0.7874 0.5842)
					(thickness 0.1524)
				)
				(justify mirror)
			)
		)
		(property "Value" "VAL*"
			(at -0.02032 2.13233 180)
			(unlocked yes)
			(layer "B.Fab")
			(hide yes)
			(effects
				(font
					(size 0.7874 0.5842)
					(thickness 0.1524)
				)
				(justify mirror)
			)
		)
		(property "Tolerance" "TOL*"
			(at -0.044704 3.05435 180)
			(unlocked yes)
			(layer "Cmts.User")
			(hide yes)
			(effects
				(font
					(size 0.7874 0.5842)
					(thickness 0.1524)
				)
				(justify mirror)
			)
		)
		(property "User Part Number" "PARTNUM*"
			(at -0.02032 4.024884 180)
			(unlocked yes)
			(layer "Cmts.User")
			(hide yes)
			(effects
				(font
					(size 0.7874 0.5842)
					(thickness 0.1524)
				)
				(justify mirror)
			)
		)
		(property "Device Type" "RESISTOR-G155-14701-01,4.7KOHMA"
			(at -0.008382 1.210564 180)
			(unlocked yes)
			(layer "B.Fab")
			(hide yes)
			(effects
				(font
					(size 0.7874 0.5842)
					(thickness 0.1524)
				)
				(justify mirror)
			)
		)
		(duplicate_pad_numbers_are_jumpers no)
		(fp_line
			(start 1.143 0.5588)
			(end -1.143 0.5588)
			(stroke
				(width 0.1)
				(type default)
			)
			(layer "B.SilkS")
		)
		(fp_line
			(start 1.143 -0.5588)
			(end 1.143 0.5588)
			(stroke
				(width 0.1)
				(type default)
			)
			(layer "B.SilkS")
		)
		(fp_line
			(start -1.143 0.5588)
			(end -1.143 -0.5588)
			(stroke
				(width 0.1)
				(type default)
			)
			(layer "B.SilkS")
		)
		(fp_line
			(start -1.143 -0.5588)
			(end 1.143 -0.5588)
			(stroke
				(width 0.1)
				(type default)
			)
			(layer "B.SilkS")
		)
		(fp_rect
			(start 1.143 -0.5588)
			(end -1.143 0.5588)
			(stroke
				(width 0)
				(type default)
			)
			(fill no)
			(layer "B.CrtYd")
		)
		(fp_line
			(start 0.508 0.3048)
			(end -0.508 0.3048)
			(stroke
				(width 0.1)
				(type default)
			)
			(layer "B.Fab")
		)
		(fp_line
			(start 0.508 -0.3048)
			(end 0.508 0.3048)
			(stroke
				(width 0.1)
				(type default)
			)
			(layer "B.Fab")
		)
		(fp_line
			(start -0.508 0.3048)
			(end -0.508 -0.3048)
			(stroke
				(width 0.1)
				(type default)
			)
			(layer "B.Fab")
		)
		(fp_line
			(start -0.508 -0.3048)
			(end 0.508 -0.3048)
			(stroke
				(width 0.1)
				(type default)
			)
			(layer "B.Fab")
		)
		(pad "1" smd rect
			(at 0.5334 0)
			(size 0.7112 0.6096)
			(layers "B.Cu" "B.Mask" "B.Paste")
			(net "UNNAMED_127_MT25QL128ABA1ESESOP")
		)
		(pad "2" smd rect
			(at -0.5334 0)
			(size 0.7112 0.6096)
			(layers "B.Cu" "B.Mask" "B.Paste")
			(net "XP3R3V_FPGA")
		)
		(zone
			(layer "B.Cu")
			(hatch none 0.5)
			(connect_pads
				(clearance 0)
			)
			(min_thickness 0.25)
			(keepout
				(tracks allowed)
				(vias not_allowed)
				(pads allowed)
				(copperpour not_allowed)
				(footprints allowed)
			)
			(placement
				(enabled no)
				(sheetname "")
			)
			(fill
				(thermal_gap 0.5)
				(thermal_bridge_width 0.5)
				(island_removal_mode 0)
			)
			(polygon
				(pts
					(xy 88.4428 -85.2932) (xy 88.5952 -85.2932) (xy 88.5952 -85.9028) (xy 88.4428 -85.9028)
				)
			)
		)
	)
	(footprint ""
		(layer "B.Cu")
		(at 111.633 -61.976 90)
		(property "Reference" "R219"
			(at 3.302 -0.03937 270)
			(unlocked yes)
			(layer "B.SilkS")
			(effects
				(font
					(size 0.7874 0.5842)
					(thickness 0.1524)
				)
				(justify mirror)
			)
		)
		(property "Value" "VAL*"
			(at -0.02032 2.13233 90)
			(unlocked yes)
			(layer "B.Fab")
			(hide yes)
			(effects
				(font
					(size 0.7874 0.5842)
					(thickness 0.1524)
				)
				(justify mirror)
			)
		)
		(property "Device Type" "RESISTOR-G155-11002-01,10KOHM,A"
			(at -0.008382 1.210564 90)
			(unlocked yes)
			(layer "B.Fab")
			(hide yes)
			(effects
				(font
					(size 0.7874 0.5842)
					(thickness 0.1524)
				)
				(justify mirror)
			)
		)
		(property "User Part Number" "PARTNUM*"
			(at -0.02032 4.024884 90)
			(unlocked yes)
			(layer "Cmts.User")
			(hide yes)
			(effects
				(font
					(size 0.7874 0.5842)
					(thickness 0.1524)
				)
				(justify mirror)
			)
		)
		(property "Tolerance" "TOL*"
			(at -0.044704 3.05435 90)
			(unlocked yes)
			(layer "Cmts.User")
			(hide yes)
			(effects
				(font
					(size 0.7874 0.5842)
					(thickness 0.1524)
				)
				(justify mirror)
			)
		)
		(duplicate_pad_numbers_are_jumpers no)
		(fp_line
			(start 1.143 -0.5588)
			(end 1.143 0.5588)
			(stroke
				(width 0.1)
				(type default)
			)
			(layer "B.SilkS")
		)
		(fp_line
			(start -1.143 -0.5588)
			(end 1.143 -0.5588)
			(stroke
				(width 0.1)
				(type default)
			)
			(layer "B.SilkS")
		)
		(fp_line
			(start 1.143 0.5588)
			(end -1.143 0.5588)
			(stroke
				(width 0.1)
				(type default)
			)
			(layer "B.SilkS")
		)
		(fp_line
			(start -1.143 0.5588)
			(end -1.143 -0.5588)
			(stroke
				(width 0.1)
				(type default)
			)
			(layer "B.SilkS")
		)
		(fp_rect
			(start -1.143 0.5588)
			(end 1.143 -0.5588)
			(stroke
				(width 0)
				(type default)
			)
			(fill no)
			(layer "B.CrtYd")
		)
		(fp_line
			(start 0.508 -0.3048)
			(end 0.508 0.3048)
			(stroke
				(width 0.1)
				(type default)
			)
			(layer "B.Fab")
		)
		(fp_line
			(start -0.508 -0.3048)
			(end 0.508 -0.3048)
			(stroke
				(width 0.1)
				(type default)
			)
			(layer "B.Fab")
		)
		(fp_line
			(start 0.508 0.3048)
			(end -0.508 0.3048)
			(stroke
				(width 0.1)
				(type default)
			)
			(layer "B.Fab")
		)
		(fp_line
			(start -0.508 0.3048)
			(end -0.508 -0.3048)
			(stroke
				(width 0.1)
				(type default)
			)
			(layer "B.Fab")
		)
		(pad "1" smd rect
			(at 0.5334 0 270)
			(size 0.7112 0.6096)
			(layers "B.Cu" "B.Mask" "B.Paste")
			(net "XP3R3V_FPGA")
		)
		(pad "2" smd rect
			(at -0.5334 0 270)
			(size 0.7112 0.6096)
			(layers "B.Cu" "B.Mask" "B.Paste")
			(net "FPGA_BRD_REV0")
		)
		(zone
			(layer "B.Cu")
			(hatch none 0.5)
			(connect_pads
				(clearance 0)
			)
			(min_thickness 0.25)
			(keepout
				(tracks allowed)
				(vias not_allowed)
				(pads allowed)
				(copperpour not_allowed)
				(footprints allowed)
			)
			(placement
				(enabled no)
				(sheetname "")
			)
			(fill
				(thermal_gap 0.5)
				(thermal_bridge_width 0.5)
				(island_removal_mode 0)
			)
			(polygon
				(pts
					(xy 111.9378 -61.8998) (xy 111.9378 -62.0522) (xy 111.3282 -62.0522) (xy 111.3282 -61.8998)
				)
			)
		)
	)
	(footprint ""
		(layer "B.Cu")
		(at 26.797 -94.234 90)
		(property "Reference" "R18"
			(at 2.54 0.34163 270)
			(unlocked yes)
			(layer "B.SilkS")
			(effects
				(font
					(size 0.7874 0.5842)
					(thickness 0.1524)
				)
				(justify mirror)
			)
		)
		(property "Value" "VAL*"
			(at -0.02032 2.13233 90)
			(unlocked yes)
			(layer "B.Fab")
			(hide yes)
			(effects
				(font
					(size 0.7874 0.5842)
					(thickness 0.1524)
				)
				(justify mirror)
			)
		)
		(property "Device Type" "RESISTOR-G155-14701-01,4.7KOHMA"
			(at -0.008382 1.210564 90)
			(unlocked yes)
			(layer "B.Fab")
			(hide yes)
			(effects
				(font
					(size 0.7874 0.5842)
					(thickness 0.1524)
				)
				(justify mirror)
			)
		)
		(property "User Part Number" "PARTNUM*"
			(at -0.02032 4.024884 90)
			(unlocked yes)
			(layer "Cmts.User")
			(hide yes)
			(effects
				(font
					(size 0.7874 0.5842)
					(thickness 0.1524)
				)
				(justify mirror)
			)
		)
		(property "Tolerance" "TOL*"
			(at -0.044704 3.05435 90)
			(unlocked yes)
			(layer "Cmts.User")
			(hide yes)
			(effects
				(font
					(size 0.7874 0.5842)
					(thickness 0.1524)
				)
				(justify mirror)
			)
		)
		(duplicate_pad_numbers_are_jumpers no)
		(fp_line
			(start 1.143 -0.5588)
			(end 1.143 0.5588)
			(stroke
				(width 0.1)
				(type default)
			)
			(layer "B.SilkS")
		)
		(fp_line
			(start -1.143 -0.5588)
			(end 1.143 -0.5588)
			(stroke
				(width 0.1)
				(type default)
			)
			(layer "B.SilkS")
		)
		(fp_line
			(start 1.143 0.5588)
			(end -1.143 0.5588)
			(stroke
				(width 0.1)
				(type default)
			)
			(layer "B.SilkS")
		)
		(fp_line
			(start -1.143 0.5588)
			(end -1.143 -0.5588)
			(stroke
				(width 0.1)
				(type default)
			)
			(layer "B.SilkS")
		)
		(fp_rect
			(start -1.143 0.5588)
			(end 1.143 -0.5588)
			(stroke
				(width 0)
				(type default)
			)
			(fill no)
			(layer "B.CrtYd")
		)
		(fp_line
			(start 0.508 -0.3048)
			(end 0.508 0.3048)
			(stroke
				(width 0.1)
				(type default)
			)
			(layer "B.Fab")
		)
		(fp_line
			(start -0.508 -0.3048)
			(end 0.508 -0.3048)
			(stroke
				(width 0.1)
				(type default)
			)
			(layer "B.Fab")
		)
		(fp_line
			(start 0.508 0.3048)
			(end -0.508 0.3048)
			(stroke
				(width 0.1)
				(type default)
			)
			(layer "B.Fab")
		)
		(fp_line
			(start -0.508 0.3048)
			(end -0.508 -0.3048)
			(stroke
				(width 0.1)
				(type default)
			)
			(layer "B.Fab")
		)
		(pad "1" smd rect
			(at 0.5334 0 270)
			(size 0.7112 0.6096)
			(layers "B.Cu" "B.Mask" "B.Paste")
			(net "XP5R0V_FT4232")
		)
		(pad "2" smd rect
			(at -0.5334 0 270)
			(size 0.7112 0.6096)
			(layers "B.Cu" "B.Mask" "B.Paste")
			(net "FT_USB_DETECT")
		)
		(zone
			(layer "B.Cu")
			(hatch none 0.5)
			(connect_pads
				(clearance 0)
			)
			(min_thickness 0.25)
			(keepout
				(tracks allowed)
				(vias not_allowed)
				(pads allowed)
				(copperpour not_allowed)
				(footprints allowed)
			)
			(placement
				(enabled no)
				(sheetname "")
			)
			(fill
				(thermal_gap 0.5)
				(thermal_bridge_width 0.5)
				(island_removal_mode 0)
			)
			(polygon
				(pts
					(xy 27.1018 -94.1578) (xy 27.1018 -94.3102) (xy 26.4922 -94.3102) (xy 26.4922 -94.1578)
				)
			)
		)
	)
	(footprint ""
		(layer "B.Cu")
		(at 107.823 -103.251 180)
		(property "Reference" "R317"
			(at -0.127 3.13563 0)
			(unlocked yes)
			(layer "B.SilkS")
			(effects
				(font
					(size 0.7874 0.5842)
					(thickness 0.1524)
				)
				(justify mirror)
			)
		)
		(property "Value" "VAL*"
			(at -0.02032 2.13233 180)
			(unlocked yes)
			(layer "B.Fab")
			(hide yes)
			(effects
				(font
					(size 0.7874 0.5842)
					(thickness 0.1524)
				)
				(justify mirror)
			)
		)
		(property "Tolerance" "TOL*"
			(at -0.044704 3.05435 180)
			(unlocked yes)
			(layer "Cmts.User")
			(hide yes)
			(effects
				(font
					(size 0.7874 0.5842)
					(thickness 0.1524)
				)
				(justify mirror)
			)
		)
		(property "User Part Number" "PARTNUM*"
			(at -0.02032 4.024884 180)
			(unlocked yes)
			(layer "Cmts.User")
			(hide yes)
			(effects
				(font
					(size 0.7874 0.5842)
					(thickness 0.1524)
				)
				(justify mirror)
			)
		)
		(property "Device Type" "RESISTOR-G155-11002-01,10KOHM,A"
			(at -0.008382 1.210564 180)
			(unlocked yes)
			(layer "B.Fab")
			(hide yes)
			(effects
				(font
					(size 0.7874 0.5842)
					(thickness 0.1524)
				)
				(justify mirror)
			)
		)
		(duplicate_pad_numbers_are_jumpers no)
		(fp_line
			(start 1.143 0.5588)
			(end -1.143 0.5588)
			(stroke
				(width 0.1)
				(type default)
			)
			(layer "B.SilkS")
		)
		(fp_line
			(start 1.143 -0.5588)
			(end 1.143 0.5588)
			(stroke
				(width 0.1)
				(type default)
			)
			(layer "B.SilkS")
		)
		(fp_line
			(start -1.143 0.5588)
			(end -1.143 -0.5588)
			(stroke
				(width 0.1)
				(type default)
			)
			(layer "B.SilkS")
		)
		(fp_line
			(start -1.143 -0.5588)
			(end 1.143 -0.5588)
			(stroke
				(width 0.1)
				(type default)
			)
			(layer "B.SilkS")
		)
		(fp_poly
			(pts
				(xy 1.143 0.5588) (xy -1.143 0.5588) (xy -1.143 -0.5588) (xy 1.143 -0.5588)
			)
			(stroke
				(width 0)
				(type default)
			)
			(fill no)
			(layer "B.CrtYd")
		)
		(fp_line
			(start 0.508 0.3048)
			(end -0.508 0.3048)
			(stroke
				(width 0.1)
				(type default)
			)
			(layer "B.Fab")
		)
		(fp_line
			(start 0.508 -0.3048)
			(end 0.508 0.3048)
			(stroke
				(width 0.1)
				(type default)
			)
			(layer "B.Fab")
		)
		(fp_line
			(start -0.508 0.3048)
			(end -0.508 -0.3048)
			(stroke
				(width 0.1)
				(type default)
			)
			(layer "B.Fab")
		)
		(fp_line
			(start -0.508 -0.3048)
			(end 0.508 -0.3048)
			(stroke
				(width 0.1)
				(type default)
			)
			(layer "B.Fab")
		)
		(pad "1" smd rect
			(at 0.5334 0)
			(size 0.7112 0.6096)
			(layers "B.Cu" "B.Mask" "B.Paste")
			(net "XP3R3V_FPGA")
		)
		(pad "2" smd rect
			(at -0.5334 0)
			(size 0.7112 0.6096)
			(layers "B.Cu" "B.Mask" "B.Paste")
			(net "R_RGB_LED_I2C_SDA")
		)
		(zone
			(layer "B.Cu")
			(hatch none 0.5)
			(connect_pads
				(clearance 0)
			)
			(min_thickness 0.25)
			(keepout
				(tracks allowed)
				(vias not_allowed)
				(pads allowed)
				(copperpour not_allowed)
				(footprints allowed)
			)
			(placement
				(enabled no)
				(sheetname "")
			)
			(fill
				(thermal_gap 0.5)
				(thermal_bridge_width 0.5)
				(island_removal_mode 0)
			)
			(polygon
				(pts
					(xy 107.7468 -103.5558) (xy 107.7468 -102.9462) (xy 107.8992 -102.9462) (xy 107.8992 -103.5558)
				)
			)
		)
		(zone
			(layer "B.Cu")
			(hatch none 0.5)
			(connect_pads
				(clearance 0)
			)
			(min_thickness 0.25)
			(keepout
				(tracks not_allowed)
				(vias allowed)
				(pads allowed)
				(copperpour not_allowed)
				(footprints allowed)
			)
			(placement
				(enabled no)
				(sheetname "")
			)
			(fill
				(thermal_gap 0.5)
				(thermal_bridge_width 0.5)
				(island_removal_mode 0)
			)
			(polygon
				(pts
					(xy 107.7468 -103.5558) (xy 107.7468 -102.9462) (xy 107.8992 -102.9462) (xy 107.8992 -103.5558)
				)
			)
		)
	)
	(footprint ""
		(layer "B.Cu")
		(at 118.346982 -39.823136)
		(property "Reference" "C151"
			(at 2.303018 -0.404114 0)
			(unlocked yes)
			(layer "B.SilkS")
			(effects
				(font
					(size 0.635 0.4064)
					(thickness 0.1524)
				)
				(justify mirror)
			)
		)
		(property "Value" "VAL*"
			(at 0 3.718306 0)
			(unlocked yes)
			(layer "B.Fab")
			(hide yes)
			(effects
				(font
					(size 0.7874 0.5842)
					(thickness 0.127)
				)
				(justify mirror)
			)
		)
		(property "Tolerance" "TOL*"
			(at 0 4.861306 0)
			(unlocked yes)
			(layer "Cmts.User")
			(hide yes)
			(effects
				(font
					(size 0.7874 0.5842)
					(thickness 0.127)
				)
				(justify mirror)
			)
		)
		(property "User Part Number" "PARTNUM*"
			(at 0 2.575306 0)
			(unlocked yes)
			(layer "Cmts.User")
			(hide yes)
			(effects
				(font
					(size 0.7874 0.5842)
					(thickness 0.127)
				)
				(justify mirror)
			)
		)
		(property "Device Type" "CAPACITOR-G105-0B104-CK,0.1UF,A"
			(at 0 1.432306 0)
			(unlocked yes)
			(layer "B.Fab")
			(hide yes)
			(effects
				(font
					(size 0.7874 0.5842)
					(thickness 0.127)
				)
				(justify mirror)
			)
		)
		(duplicate_pad_numbers_are_jumpers no)
		(fp_line
			(start -0.970026 -0.4699)
			(end -0.970026 0.4699)
			(stroke
				(width 0.1)
				(type default)
			)
			(layer "B.SilkS")
		)
		(fp_line
			(start -0.970026 0.4699)
			(end 0.970026 0.4699)
			(stroke
				(width 0.1)
				(type default)
			)
			(layer "B.SilkS")
		)
		(fp_line
			(start 0.970026 -0.4699)
			(end -0.970026 -0.4699)
			(stroke
				(width 0.1)
				(type default)
			)
			(layer "B.SilkS")
		)
		(fp_line
			(start 0.970026 0.4699)
			(end 0.970026 -0.4699)
			(stroke
				(width 0.1)
				(type default)
			)
			(layer "B.SilkS")
		)
		(fp_poly
			(pts
				(xy 0.970026 0.4699) (xy -0.970026 0.4699) (xy -0.970026 -0.4699) (xy 0.970026 -0.4699)
			)
			(stroke
				(width 0)
				(type default)
			)
			(fill no)
			(layer "B.CrtYd")
		)
		(fp_line
			(start -0.508 -0.3048)
			(end -0.508 0.3048)
			(stroke
				(width 0.1)
				(type default)
			)
			(layer "B.Fab")
		)
		(fp_line
			(start -0.508 0.3048)
			(end 0.508 0.3048)
			(stroke
				(width 0.1)
				(type default)
			)
			(layer "B.Fab")
		)
		(fp_line
			(start 0.508 -0.3048)
			(end -0.508 -0.3048)
			(stroke
				(width 0.1)
				(type default)
			)
			(layer "B.Fab")
		)
		(fp_line
			(start 0.508 0.3048)
			(end 0.508 -0.3048)
			(stroke
				(width 0.1)
				(type default)
			)
			(layer "B.Fab")
		)
		(pad "1" smd circle
			(at 0.500126 0 180)
			(size 0.635 0.635)
			(layers "B.Cu" "B.Mask" "B.Paste")
			(net "XP2R5V_FPGA")
		)
		(pad "2" smd circle
			(at -0.500126 0 180)
			(size 0.635 0.635)
			(layers "B.Cu" "B.Mask" "B.Paste")
			(net "SG")
		)
	)
	(footprint ""
		(layer "B.Cu")
		(at 103.347012 -37.82314)
		(property "Reference" "R197"
			(at -41.879012 1.40589 0)
			(unlocked yes)
			(layer "B.SilkS")
			(effects
				(font
					(size 0.635 0.4064)
					(thickness 0.1524)
				)
				(justify mirror)
			)
		)
		(property "Value" "VAL*"
			(at 0 3.718306 0)
			(unlocked yes)
			(layer "B.Fab")
			(hide yes)
			(effects
				(font
					(size 0.7874 0.5842)
					(thickness 0.127)
				)
				(justify mirror)
			)
		)
		(property "Device Type" "RESISTOR-G155-11000-01,100OHM,A"
			(at 0 1.432306 0)
			(unlocked yes)
			(layer "B.Fab")
			(hide yes)
			(effects
				(font
					(size 0.7874 0.5842)
					(thickness 0.127)
				)
				(justify mirror)
			)
		)
		(property "User Part Number" "PARTNUM*"
			(at 0 2.575306 0)
			(unlocked yes)
			(layer "Cmts.User")
			(hide yes)
			(effects
				(font
					(size 0.7874 0.5842)
					(thickness 0.127)
				)
				(justify mirror)
			)
		)
		(property "Tolerance" "TOL*"
			(at 0 4.861306 0)
			(unlocked yes)
			(layer "Cmts.User")
			(hide yes)
			(effects
				(font
					(size 0.7874 0.5842)
					(thickness 0.127)
				)
				(justify mirror)
			)
		)
		(duplicate_pad_numbers_are_jumpers no)
		(fp_line
			(start -0.970026 -0.4699)
			(end -0.970026 0.4699)
			(stroke
				(width 0.1)
				(type default)
			)
			(layer "B.SilkS")
		)
		(fp_line
			(start -0.970026 0.4699)
			(end 0.970026 0.4699)
			(stroke
				(width 0.1)
				(type default)
			)
			(layer "B.SilkS")
		)
		(fp_line
			(start 0.970026 -0.4699)
			(end -0.970026 -0.4699)
			(stroke
				(width 0.1)
				(type default)
			)
			(layer "B.SilkS")
		)
		(fp_line
			(start 0.970026 0.4699)
			(end 0.970026 -0.4699)
			(stroke
				(width 0.1)
				(type default)
			)
			(layer "B.SilkS")
		)
		(fp_poly
			(pts
				(xy 0.970026 0.4699) (xy -0.970026 0.4699) (xy -0.970026 -0.4699) (xy 0.970026 -0.4699)
			)
			(stroke
				(width 0)
				(type default)
			)
			(fill no)
			(layer "B.CrtYd")
		)
		(fp_line
			(start -0.508 -0.3048)
			(end -0.508 0.3048)
			(stroke
				(width 0.1)
				(type default)
			)
			(layer "B.Fab")
		)
		(fp_line
			(start -0.508 0.3048)
			(end 0.508 0.3048)
			(stroke
				(width 0.1)
				(type default)
			)
			(layer "B.Fab")
		)
		(fp_line
			(start 0.508 -0.3048)
			(end -0.508 -0.3048)
			(stroke
				(width 0.1)
				(type default)
			)
			(layer "B.Fab")
		)
		(fp_line
			(start 0.508 0.3048)
			(end 0.508 -0.3048)
			(stroke
				(width 0.1)
				(type default)
			)
			(layer "B.Fab")
		)
		(pad "1" smd circle
			(at 0.500126 0 180)
			(size 0.635 0.635)
			(layers "B.Cu" "B.Mask" "B.Paste")
			(net "MHZ125CLKP_CLKIN")
		)
		(pad "2" smd circle
			(at -0.500126 0 180)
			(size 0.635 0.635)
			(layers "B.Cu" "B.Mask" "B.Paste")
			(net "MHZ125CLKN_CLKIN")
		)
	)
	(footprint ""
		(layer "B.Cu")
		(at 83.2358 -85.979 180)
		(property "Reference" "R146"
			(at 0.6858 5.54863 0)
			(unlocked yes)
			(layer "B.SilkS")
			(effects
				(font
					(size 0.7874 0.5842)
					(thickness 0.1524)
				)
				(justify mirror)
			)
		)
		(property "Value" "VAL*"
			(at -0.02032 2.13233 180)
			(unlocked yes)
			(layer "B.Fab")
			(hide yes)
			(effects
				(font
					(size 0.7874 0.5842)
					(thickness 0.1524)
				)
				(justify mirror)
			)
		)
		(property "Tolerance" "TOL*"
			(at -0.044704 3.05435 180)
			(unlocked yes)
			(layer "Cmts.User")
			(hide yes)
			(effects
				(font
					(size 0.7874 0.5842)
					(thickness 0.1524)
				)
				(justify mirror)
			)
		)
		(property "User Part Number" "PARTNUM*"
			(at -0.02032 4.024884 180)
			(unlocked yes)
			(layer "Cmts.User")
			(hide yes)
			(effects
				(font
					(size 0.7874 0.5842)
					(thickness 0.1524)
				)
				(justify mirror)
			)
		)
		(property "Device Type" "RESISTOR-G155-11002-01,10KOHM,A"
			(at -0.008382 1.210564 180)
			(unlocked yes)
			(layer "B.Fab")
			(hide yes)
			(effects
				(font
					(size 0.7874 0.5842)
					(thickness 0.1524)
				)
				(justify mirror)
			)
		)
		(duplicate_pad_numbers_are_jumpers no)
		(fp_line
			(start 1.143 0.5588)
			(end -1.143 0.5588)
			(stroke
				(width 0.1)
				(type default)
			)
			(layer "B.SilkS")
		)
		(fp_line
			(start 1.143 -0.5588)
			(end 1.143 0.5588)
			(stroke
				(width 0.1)
				(type default)
			)
			(layer "B.SilkS")
		)
		(fp_line
			(start -1.143 0.5588)
			(end -1.143 -0.5588)
			(stroke
				(width 0.1)
				(type default)
			)
			(layer "B.SilkS")
		)
		(fp_line
			(start -1.143 -0.5588)
			(end 1.143 -0.5588)
			(stroke
				(width 0.1)
				(type default)
			)
			(layer "B.SilkS")
		)
		(fp_rect
			(start -1.143 0.5588)
			(end 1.143 -0.5588)
			(stroke
				(width 0)
				(type default)
			)
			(fill no)
			(layer "B.CrtYd")
		)
		(fp_line
			(start 0.508 0.3048)
			(end -0.508 0.3048)
			(stroke
				(width 0.1)
				(type default)
			)
			(layer "B.Fab")
		)
		(fp_line
			(start 0.508 -0.3048)
			(end 0.508 0.3048)
			(stroke
				(width 0.1)
				(type default)
			)
			(layer "B.Fab")
		)
		(fp_line
			(start -0.508 0.3048)
			(end -0.508 -0.3048)
			(stroke
				(width 0.1)
				(type default)
			)
			(layer "B.Fab")
		)
		(fp_line
			(start -0.508 -0.3048)
			(end 0.508 -0.3048)
			(stroke
				(width 0.1)
				(type default)
			)
			(layer "B.Fab")
		)
		(pad "1" smd rect
			(at 0.5334 0)
			(size 0.7112 0.6096)
			(layers "B.Cu" "B.Mask" "B.Paste")
			(net "XP3R3V_FPGA")
		)
		(pad "2" smd rect
			(at -0.5334 0)
			(size 0.7112 0.6096)
			(layers "B.Cu" "B.Mask" "B.Paste")
			(net "PCA9546_RST_N")
		)
		(zone
			(layer "B.Cu")
			(hatch none 0.5)
			(connect_pads
				(clearance 0)
			)
			(min_thickness 0.25)
			(keepout
				(tracks allowed)
				(vias not_allowed)
				(pads allowed)
				(copperpour not_allowed)
				(footprints allowed)
			)
			(placement
				(enabled no)
				(sheetname "")
			)
			(fill
				(thermal_gap 0.5)
				(thermal_bridge_width 0.5)
				(island_removal_mode 0)
			)
			(polygon
				(pts
					(xy 83.312 -86.2838) (xy 83.1596 -86.2838) (xy 83.1596 -85.6742) (xy 83.312 -85.6742)
				)
			)
		)
	)
	(footprint ""
		(layer "B.Cu")
		(at 156.337 -45.466 90)
		(property "Reference" "R430"
			(at -10.70737 -0.254 0)
			(unlocked yes)
			(layer "B.SilkS")
			(effects
				(font
					(size 0.7874 0.5842)
					(thickness 0.1524)
				)
				(justify mirror)
			)
		)
		(property "Value" "VAL*"
			(at -0.02032 2.13233 90)
			(unlocked yes)
			(layer "B.Fab")
			(hide yes)
			(effects
				(font
					(size 0.7874 0.5842)
					(thickness 0.1524)
				)
				(justify mirror)
			)
		)
		(property "Tolerance" "TOL*"
			(at -0.044704 3.05435 90)
			(unlocked yes)
			(layer "Cmts.User")
			(hide yes)
			(effects
				(font
					(size 0.7874 0.5842)
					(thickness 0.1524)
				)
				(justify mirror)
			)
		)
		(property "User Part Number" "PARTNUM*"
			(at -0.02032 4.024884 90)
			(unlocked yes)
			(layer "Cmts.User")
			(hide yes)
			(effects
				(font
					(size 0.7874 0.5842)
					(thickness 0.1524)
				)
				(justify mirror)
			)
		)
		(property "Device Type" "RESISTOR-G155-133R0-01,33OHM,1%"
			(at -0.008382 1.210564 90)
			(unlocked yes)
			(layer "B.Fab")
			(hide yes)
			(effects
				(font
					(size 0.7874 0.5842)
					(thickness 0.1524)
				)
				(justify mirror)
			)
		)
		(duplicate_pad_numbers_are_jumpers no)
		(fp_line
			(start 1.143 -0.5588)
			(end 1.143 0.5588)
			(stroke
				(width 0.1)
				(type default)
			)
			(layer "B.SilkS")
		)
		(fp_line
			(start -1.143 -0.5588)
			(end 1.143 -0.5588)
			(stroke
				(width 0.1)
				(type default)
			)
			(layer "B.SilkS")
		)
		(fp_line
			(start 1.143 0.5588)
			(end -1.143 0.5588)
			(stroke
				(width 0.1)
				(type default)
			)
			(layer "B.SilkS")
		)
		(fp_line
			(start -1.143 0.5588)
			(end -1.143 -0.5588)
			(stroke
				(width 0.1)
				(type default)
			)
			(layer "B.SilkS")
		)
		(fp_poly
			(pts
				(xy 1.143 0.5588) (xy -1.143 0.5588) (xy -1.143 -0.5588) (xy 1.143 -0.5588)
			)
			(stroke
				(width 0)
				(type default)
			)
			(fill no)
			(layer "B.CrtYd")
		)
		(fp_line
			(start 0.508 -0.3048)
			(end 0.508 0.3048)
			(stroke
				(width 0.1)
				(type default)
			)
			(layer "B.Fab")
		)
		(fp_line
			(start -0.508 -0.3048)
			(end 0.508 -0.3048)
			(stroke
				(width 0.1)
				(type default)
			)
			(layer "B.Fab")
		)
		(fp_line
			(start 0.508 0.3048)
			(end -0.508 0.3048)
			(stroke
				(width 0.1)
				(type default)
			)
			(layer "B.Fab")
		)
		(fp_line
			(start -0.508 0.3048)
			(end -0.508 -0.3048)
			(stroke
				(width 0.1)
				(type default)
			)
			(layer "B.Fab")
		)
		(pad "1" smd rect
			(at 0.5334 0 270)
			(size 0.7112 0.6096)
			(layers "B.Cu" "B.Mask" "B.Paste")
			(net "FPGA_IO_4")
		)
		(pad "2" smd rect
			(at -0.5334 0 270)
			(size 0.7112 0.6096)
			(layers "B.Cu" "B.Mask" "B.Paste")
			(net "UNNAMED_16_CONNHDR2X6FSSMT_I161")
		)
		(zone
			(layer "B.Cu")
			(hatch none 0.5)
			(connect_pads
				(clearance 0)
			)
			(min_thickness 0.25)
			(keepout
				(tracks not_allowed)
				(vias allowed)
				(pads allowed)
				(copperpour not_allowed)
				(footprints allowed)
			)
			(placement
				(enabled no)
				(sheetname "")
			)
			(fill
				(thermal_gap 0.5)
				(thermal_bridge_width 0.5)
				(island_removal_mode 0)
			)
			(polygon
				(pts
					(xy 156.6418 -45.5422) (xy 156.0322 -45.5422) (xy 156.0322 -45.3898) (xy 156.6418 -45.3898)
				)
			)
		)
		(zone
			(layer "B.Cu")
			(hatch none 0.5)
			(connect_pads
				(clearance 0)
			)
			(min_thickness 0.25)
			(keepout
				(tracks allowed)
				(vias not_allowed)
				(pads allowed)
				(copperpour not_allowed)
				(footprints allowed)
			)
			(placement
				(enabled no)
				(sheetname "")
			)
			(fill
				(thermal_gap 0.5)
				(thermal_bridge_width 0.5)
				(island_removal_mode 0)
			)
			(polygon
				(pts
					(xy 156.6418 -45.5422) (xy 156.0322 -45.5422) (xy 156.0322 -45.3898) (xy 156.6418 -45.3898)
				)
			)
		)
	)
	(footprint ""
		(layer "B.Cu")
		(at 110.3376 -44.2214)
		(property "Reference" "C212"
			(at -43.4086 1.45415 0)
			(unlocked yes)
			(layer "B.SilkS")
			(effects
				(font
					(size 0.635 0.4064)
					(thickness 0.1524)
				)
				(justify mirror)
			)
		)
		(property "Value" "VAL*"
			(at -0.0762 2.067306 0)
			(unlocked yes)
			(layer "B.Fab")
			(hide yes)
			(effects
				(font
					(size 0.7874 0.5842)
					(thickness 0.1524)
				)
				(justify mirror)
			)
		)
		(property "Device Type" "CAPACITOR-G105-0B104-CK,0.1UF,A"
			(at -0.0508 1.127506 0)
			(unlocked yes)
			(layer "B.Fab")
			(hide yes)
			(effects
				(font
					(size 0.7874 0.5842)
					(thickness 0.1524)
				)
				(justify mirror)
			)
		)
		(property "User Part Number" "PARTNUM*"
			(at -0.1016 4.023106 0)
			(unlocked yes)
			(layer "Cmts.User")
			(hide yes)
			(effects
				(font
					(size 0.7874 0.5842)
					(thickness 0.1524)
				)
				(justify mirror)
			)
		)
		(property "Tolerance" "TOL*"
			(at -0.0762 3.032506 0)
			(unlocked yes)
			(layer "Cmts.User")
			(hide yes)
			(effects
				(font
					(size 0.7874 0.5842)
					(thickness 0.1524)
				)
				(justify mirror)
			)
		)
		(duplicate_pad_numbers_are_jumpers no)
		(fp_line
			(start -1.143 -0.5588)
			(end 1.143 -0.5588)
			(stroke
				(width 0.1)
				(type default)
			)
			(layer "B.SilkS")
		)
		(fp_line
			(start -1.143 0.5588)
			(end -1.143 -0.5588)
			(stroke
				(width 0.1)
				(type default)
			)
			(layer "B.SilkS")
		)
		(fp_line
			(start 1.143 -0.5588)
			(end 1.143 0.5588)
			(stroke
				(width 0.1)
				(type default)
			)
			(layer "B.SilkS")
		)
		(fp_line
			(start 1.143 0.5588)
			(end -1.143 0.5588)
			(stroke
				(width 0.1)
				(type default)
			)
			(layer "B.SilkS")
		)
		(fp_poly
			(pts
				(xy 1.143 0.5588) (xy -1.143 0.5588) (xy -1.143 -0.5588) (xy 1.143 -0.5588)
			)
			(stroke
				(width 0)
				(type default)
			)
			(fill no)
			(layer "B.CrtYd")
		)
		(fp_line
			(start -0.508 -0.3048)
			(end 0.508 -0.3048)
			(stroke
				(width 0.1)
				(type default)
			)
			(layer "B.Fab")
		)
		(fp_line
			(start -0.508 0.3048)
			(end -0.508 -0.3048)
			(stroke
				(width 0.1)
				(type default)
			)
			(layer "B.Fab")
		)
		(fp_line
			(start 0.508 -0.3048)
			(end 0.508 0.3048)
			(stroke
				(width 0.1)
				(type default)
			)
			(layer "B.Fab")
		)
		(fp_line
			(start 0.508 0.3048)
			(end -0.508 0.3048)
			(stroke
				(width 0.1)
				(type default)
			)
			(layer "B.Fab")
		)
		(pad "1" smd rect
			(at 0.5334 0 180)
			(size 0.7112 0.6096)
			(layers "B.Cu" "B.Mask" "B.Paste")
			(net "XP1R8V_FPGA_VCCAUX")
		)
		(pad "2" smd rect
			(at -0.5334 0 180)
			(size 0.7112 0.6096)
			(layers "B.Cu" "B.Mask" "B.Paste")
			(net "SG")
		)
		(zone
			(layer "B.Cu")
			(hatch none 0.5)
			(connect_pads
				(clearance 0)
			)
			(min_thickness 0.25)
			(keepout
				(tracks not_allowed)
				(vias allowed)
				(pads allowed)
				(copperpour not_allowed)
				(footprints allowed)
			)
			(placement
				(enabled no)
				(sheetname "")
			)
			(fill
				(thermal_gap 0.5)
				(thermal_bridge_width 0.5)
				(island_removal_mode 0)
			)
			(polygon
				(pts
					(xy 110.4138 -43.9166) (xy 110.4138 -44.5262) (xy 110.2614 -44.5262) (xy 110.2614 -43.9166)
				)
			)
		)
		(zone
			(layer "B.Cu")
			(hatch none 0.5)
			(connect_pads
				(clearance 0)
			)
			(min_thickness 0.25)
			(keepout
				(tracks allowed)
				(vias not_allowed)
				(pads allowed)
				(copperpour not_allowed)
				(footprints allowed)
			)
			(placement
				(enabled no)
				(sheetname "")
			)
			(fill
				(thermal_gap 0.5)
				(thermal_bridge_width 0.5)
				(island_removal_mode 0)
			)
			(polygon
				(pts
					(xy 110.4138 -43.9166) (xy 110.4138 -44.5262) (xy 110.2614 -44.5262) (xy 110.2614 -43.9166)
				)
			)
		)
	)
	(footprint ""
		(layer "B.Cu")
		(at 113.847118 -46.322996 -90)
		(property "Reference" "R437"
			(at 1.999996 43.139868 270)
			(unlocked yes)
			(layer "B.SilkS")
			(effects
				(font
					(size 0.635 0.4064)
					(thickness 0.1524)
				)
				(justify mirror)
			)
		)
		(property "Value" "VAL*"
			(at 0 3.718306 270)
			(unlocked yes)
			(layer "B.Fab")
			(hide yes)
			(effects
				(font
					(size 0.7874 0.5842)
					(thickness 0.127)
				)
				(justify mirror)
			)
		)
		(property "Tolerance" "TOL*"
			(at 0 4.861306 270)
			(unlocked yes)
			(layer "Cmts.User")
			(hide yes)
			(effects
				(font
					(size 0.7874 0.5842)
					(thickness 0.127)
				)
				(justify mirror)
			)
		)
		(property "User Part Number" "PARTNUM*"
			(at 0 2.575306 270)
			(unlocked yes)
			(layer "Cmts.User")
			(hide yes)
			(effects
				(font
					(size 0.7874 0.5842)
					(thickness 0.127)
				)
				(justify mirror)
			)
		)
		(property "Device Type" "RESISTOR-G155-11502-01,15KOHM,A"
			(at 0 1.432306 270)
			(unlocked yes)
			(layer "B.Fab")
			(hide yes)
			(effects
				(font
					(size 0.7874 0.5842)
					(thickness 0.127)
				)
				(justify mirror)
			)
		)
		(duplicate_pad_numbers_are_jumpers no)
		(fp_line
			(start -0.970026 0.4699)
			(end 0.970026 0.4699)
			(stroke
				(width 0.1)
				(type default)
			)
			(layer "B.SilkS")
		)
		(fp_line
			(start 0.970026 0.4699)
			(end 0.970026 -0.4699)
			(stroke
				(width 0.1)
				(type default)
			)
			(layer "B.SilkS")
		)
		(fp_line
			(start -0.970026 -0.4699)
			(end -0.970026 0.4699)
			(stroke
				(width 0.1)
				(type default)
			)
			(layer "B.SilkS")
		)
		(fp_line
			(start 0.970026 -0.4699)
			(end -0.970026 -0.4699)
			(stroke
				(width 0.1)
				(type default)
			)
			(layer "B.SilkS")
		)
		(fp_poly
			(pts
				(xy 0.970026 0.4699) (xy -0.970026 0.4699) (xy -0.970026 -0.4699) (xy 0.970026 -0.4699)
			)
			(stroke
				(width 0)
				(type default)
			)
			(fill no)
			(layer "B.CrtYd")
		)
		(fp_line
			(start -0.508 0.3048)
			(end 0.508 0.3048)
			(stroke
				(width 0.1)
				(type default)
			)
			(layer "B.Fab")
		)
		(fp_line
			(start 0.508 0.3048)
			(end 0.508 -0.3048)
			(stroke
				(width 0.1)
				(type default)
			)
			(layer "B.Fab")
		)
		(fp_line
			(start -0.508 -0.3048)
			(end -0.508 0.3048)
			(stroke
				(width 0.1)
				(type default)
			)
			(layer "B.Fab")
		)
		(fp_line
			(start 0.508 -0.3048)
			(end -0.508 -0.3048)
			(stroke
				(width 0.1)
				(type default)
			)
			(layer "B.Fab")
		)
		(pad "1" smd circle
			(at 0.500126 0 90)
			(size 0.635 0.635)
			(layers "B.Cu" "B.Mask" "B.Paste")
			(net "SG")
		)
		(pad "2" smd circle
			(at -0.500126 0 90)
			(size 0.635 0.635)
			(layers "B.Cu" "B.Mask" "B.Paste")
			(net "MAC_USB_DM")
		)
	)
	(footprint ""
		(layer "B.Cu")
		(at 13.462 -66.167 90)
		(property "Reference" "R494"
			(at 0 1.23063 270)
			(unlocked yes)
			(layer "B.SilkS")
			(effects
				(font
					(size 0.7874 0.5842)
					(thickness 0.1524)
				)
				(justify mirror)
			)
		)
		(property "Value" "VAL*"
			(at -0.02032 2.13233 90)
			(unlocked yes)
			(layer "B.Fab")
			(hide yes)
			(effects
				(font
					(size 0.7874 0.5842)
					(thickness 0.1524)
				)
				(justify mirror)
			)
		)
		(property "Tolerance" "TOL*"
			(at -0.044704 3.05435 90)
			(unlocked yes)
			(layer "Cmts.User")
			(hide yes)
			(effects
				(font
					(size 0.7874 0.5842)
					(thickness 0.1524)
				)
				(justify mirror)
			)
		)
		(property "User Part Number" "PARTNUM*"
			(at -0.02032 4.024884 90)
			(unlocked yes)
			(layer "Cmts.User")
			(hide yes)
			(effects
				(font
					(size 0.7874 0.5842)
					(thickness 0.1524)
				)
				(justify mirror)
			)
		)
		(property "Device Type" "RESISTOR-G155-100R0-J0,0OHM,-"
			(at -0.008382 1.210564 90)
			(unlocked yes)
			(layer "B.Fab")
			(hide yes)
			(effects
				(font
					(size 0.7874 0.5842)
					(thickness 0.1524)
				)
				(justify mirror)
			)
		)
		(duplicate_pad_numbers_are_jumpers no)
		(fp_line
			(start 1.143 -0.5588)
			(end 1.143 0.5588)
			(stroke
				(width 0.1)
				(type default)
			)
			(layer "B.SilkS")
		)
		(fp_line
			(start -1.143 -0.5588)
			(end 1.143 -0.5588)
			(stroke
				(width 0.1)
				(type default)
			)
			(layer "B.SilkS")
		)
		(fp_line
			(start 1.143 0.5588)
			(end -1.143 0.5588)
			(stroke
				(width 0.1)
				(type default)
			)
			(layer "B.SilkS")
		)
		(fp_line
			(start -1.143 0.5588)
			(end -1.143 -0.5588)
			(stroke
				(width 0.1)
				(type default)
			)
			(layer "B.SilkS")
		)
		(fp_poly
			(pts
				(xy 1.143 0.5588) (xy -1.143 0.5588) (xy -1.143 -0.5588) (xy 1.143 -0.5588)
			)
			(stroke
				(width 0)
				(type default)
			)
			(fill no)
			(layer "B.CrtYd")
		)
		(fp_line
			(start 0.508 -0.3048)
			(end 0.508 0.3048)
			(stroke
				(width 0.1)
				(type default)
			)
			(layer "B.Fab")
		)
		(fp_line
			(start -0.508 -0.3048)
			(end 0.508 -0.3048)
			(stroke
				(width 0.1)
				(type default)
			)
			(layer "B.Fab")
		)
		(fp_line
			(start 0.508 0.3048)
			(end -0.508 0.3048)
			(stroke
				(width 0.1)
				(type default)
			)
			(layer "B.Fab")
		)
		(fp_line
			(start -0.508 0.3048)
			(end -0.508 -0.3048)
			(stroke
				(width 0.1)
				(type default)
			)
			(layer "B.Fab")
		)
		(pad "1" smd rect
			(at 0.5334 0 270)
			(size 0.7112 0.6096)
			(layers "B.Cu" "B.Mask" "B.Paste")
			(net "UNNAMED_12_CAPACITOR_I328_2")
		)
		(pad "2" smd rect
			(at -0.5334 0 270)
			(size 0.7112 0.6096)
			(layers "B.Cu" "B.Mask" "B.Paste")
			(net "UNNAMED_12_74HCT2G125DPTSSOP8_6")
		)
		(zone
			(layer "B.Cu")
			(hatch none 0.5)
			(connect_pads
				(clearance 0)
			)
			(min_thickness 0.25)
			(keepout
				(tracks allowed)
				(vias not_allowed)
				(pads allowed)
				(copperpour not_allowed)
				(footprints allowed)
			)
			(placement
				(enabled no)
				(sheetname "")
			)
			(fill
				(thermal_gap 0.5)
				(thermal_bridge_width 0.5)
				(island_removal_mode 0)
			)
			(polygon
				(pts
					(xy 13.7668 -66.2432) (xy 13.1572 -66.2432) (xy 13.1572 -66.0908) (xy 13.7668 -66.0908)
				)
			)
		)
		(zone
			(layer "B.Cu")
			(hatch none 0.5)
			(connect_pads
				(clearance 0)
			)
			(min_thickness 0.25)
			(keepout
				(tracks not_allowed)
				(vias allowed)
				(pads allowed)
				(copperpour not_allowed)
				(footprints allowed)
			)
			(placement
				(enabled no)
				(sheetname "")
			)
			(fill
				(thermal_gap 0.5)
				(thermal_bridge_width 0.5)
				(island_removal_mode 0)
			)
			(polygon
				(pts
					(xy 13.7668 -66.2432) (xy 13.1572 -66.2432) (xy 13.1572 -66.0908) (xy 13.7668 -66.0908)
				)
			)
		)
	)
	(footprint ""
		(layer "B.Cu")
		(at 107.84713 -54.323234 -90)
		(property "Reference" "C162"
			(at -0.286766 -1.34112 270)
			(unlocked yes)
			(layer "B.SilkS")
			(effects
				(font
					(size 0.635 0.4064)
					(thickness 0.1524)
				)
				(justify mirror)
			)
		)
		(property "Value" "VAL*"
			(at 0 3.718306 270)
			(unlocked yes)
			(layer "B.Fab")
			(hide yes)
			(effects
				(font
					(size 0.7874 0.5842)
					(thickness 0.127)
				)
				(justify mirror)
			)
		)
		(property "Tolerance" "TOL*"
			(at 0 4.861306 270)
			(unlocked yes)
			(layer "Cmts.User")
			(hide yes)
			(effects
				(font
					(size 0.7874 0.5842)
					(thickness 0.127)
				)
				(justify mirror)
			)
		)
		(property "User Part Number" "PARTNUM*"
			(at 0 2.575306 270)
			(unlocked yes)
			(layer "Cmts.User")
			(hide yes)
			(effects
				(font
					(size 0.7874 0.5842)
					(thickness 0.127)
				)
				(justify mirror)
			)
		)
		(property "Device Type" "CAPACITOR-G105-0B104-CK,0.1UF,A"
			(at 0 1.432306 270)
			(unlocked yes)
			(layer "B.Fab")
			(hide yes)
			(effects
				(font
					(size 0.7874 0.5842)
					(thickness 0.127)
				)
				(justify mirror)
			)
		)
		(duplicate_pad_numbers_are_jumpers no)
		(fp_line
			(start -0.970026 0.4699)
			(end 0.970026 0.4699)
			(stroke
				(width 0.1)
				(type default)
			)
			(layer "B.SilkS")
		)
		(fp_line
			(start 0.970026 0.4699)
			(end 0.970026 -0.4699)
			(stroke
				(width 0.1)
				(type default)
			)
			(layer "B.SilkS")
		)
		(fp_line
			(start -0.970026 -0.4699)
			(end -0.970026 0.4699)
			(stroke
				(width 0.1)
				(type default)
			)
			(layer "B.SilkS")
		)
		(fp_line
			(start 0.970026 -0.4699)
			(end -0.970026 -0.4699)
			(stroke
				(width 0.1)
				(type default)
			)
			(layer "B.SilkS")
		)
		(fp_poly
			(pts
				(xy 0.970026 0.4699) (xy -0.970026 0.4699) (xy -0.970026 -0.4699) (xy 0.970026 -0.4699)
			)
			(stroke
				(width 0)
				(type default)
			)
			(fill no)
			(layer "B.CrtYd")
		)
		(fp_line
			(start -0.508 0.3048)
			(end 0.508 0.3048)
			(stroke
				(width 0.1)
				(type default)
			)
			(layer "B.Fab")
		)
		(fp_line
			(start 0.508 0.3048)
			(end 0.508 -0.3048)
			(stroke
				(width 0.1)
				(type default)
			)
			(layer "B.Fab")
		)
		(fp_line
			(start -0.508 -0.3048)
			(end -0.508 0.3048)
			(stroke
				(width 0.1)
				(type default)
			)
			(layer "B.Fab")
		)
		(fp_line
			(start 0.508 -0.3048)
			(end -0.508 -0.3048)
			(stroke
				(width 0.1)
				(type default)
			)
			(layer "B.Fab")
		)
		(pad "1" smd circle
			(at 0.500126 0 90)
			(size 0.635 0.635)
			(layers "B.Cu" "B.Mask" "B.Paste")
			(net "XP3R3V_FPGA")
		)
		(pad "2" smd circle
			(at -0.500126 0 90)
			(size 0.635 0.635)
			(layers "B.Cu" "B.Mask" "B.Paste")
			(net "SG")
		)
	)
	(footprint ""
		(layer "B.Cu")
		(at 89.9922 -100.1268)
		(property "Reference" "C54"
			(at 3.683 0.03937 0)
			(unlocked yes)
			(layer "B.SilkS")
			(effects
				(font
					(size 0.7874 0.5842)
					(thickness 0.1524)
				)
				(justify mirror)
			)
		)
		(property "Value" "VAL*"
			(at -0.0762 2.067306 0)
			(unlocked yes)
			(layer "B.Fab")
			(hide yes)
			(effects
				(font
					(size 0.7874 0.5842)
					(thickness 0.1524)
				)
				(justify mirror)
			)
		)
		(property "Tolerance" "TOL*"
			(at -0.0762 3.032506 0)
			(unlocked yes)
			(layer "Cmts.User")
			(hide yes)
			(effects
				(font
					(size 0.7874 0.5842)
					(thickness 0.1524)
				)
				(justify mirror)
			)
		)
		(property "User Part Number" "PARTNUM*"
			(at -0.1016 4.023106 0)
			(unlocked yes)
			(layer "Cmts.User")
			(hide yes)
			(effects
				(font
					(size 0.7874 0.5842)
					(thickness 0.1524)
				)
				(justify mirror)
			)
		)
		(property "Device Type" "CAPACITOR-G105-0B222-FK,2200PFA"
			(at -0.0508 1.127506 0)
			(unlocked yes)
			(layer "B.Fab")
			(hide yes)
			(effects
				(font
					(size 0.7874 0.5842)
					(thickness 0.1524)
				)
				(justify mirror)
			)
		)
		(duplicate_pad_numbers_are_jumpers no)
		(fp_line
			(start -1.143 -0.5588)
			(end 1.143 -0.5588)
			(stroke
				(width 0.1)
				(type default)
			)
			(layer "B.SilkS")
		)
		(fp_line
			(start -1.143 0.5588)
			(end -1.143 -0.5588)
			(stroke
				(width 0.1)
				(type default)
			)
			(layer "B.SilkS")
		)
		(fp_line
			(start 1.143 -0.5588)
			(end 1.143 0.5588)
			(stroke
				(width 0.1)
				(type default)
			)
			(layer "B.SilkS")
		)
		(fp_line
			(start 1.143 0.5588)
			(end -1.143 0.5588)
			(stroke
				(width 0.1)
				(type default)
			)
			(layer "B.SilkS")
		)
		(fp_rect
			(start -1.143 0.5588)
			(end 1.143 -0.5588)
			(stroke
				(width 0)
				(type default)
			)
			(fill no)
			(layer "B.CrtYd")
		)
		(fp_line
			(start -0.508 -0.3048)
			(end 0.508 -0.3048)
			(stroke
				(width 0.1)
				(type default)
			)
			(layer "B.Fab")
		)
		(fp_line
			(start -0.508 0.3048)
			(end -0.508 -0.3048)
			(stroke
				(width 0.1)
				(type default)
			)
			(layer "B.Fab")
		)
		(fp_line
			(start 0.508 -0.3048)
			(end 0.508 0.3048)
			(stroke
				(width 0.1)
				(type default)
			)
			(layer "B.Fab")
		)
		(fp_line
			(start 0.508 0.3048)
			(end -0.508 0.3048)
			(stroke
				(width 0.1)
				(type default)
			)
			(layer "B.Fab")
		)
		(pad "1" smd rect
			(at 0.5334 0 180)
			(size 0.7112 0.6096)
			(layers "B.Cu" "B.Mask" "B.Paste")
			(net "UNNAMED_517_CAPACITOR_I17_1")
		)
		(pad "2" smd rect
			(at -0.5334 0 180)
			(size 0.7112 0.6096)
			(layers "B.Cu" "B.Mask" "B.Paste")
			(net "XP3R3V_AGND")
		)
		(zone
			(layer "B.Cu")
			(hatch none 0.5)
			(connect_pads
				(clearance 0)
			)
			(min_thickness 0.25)
			(keepout
				(tracks allowed)
				(vias not_allowed)
				(pads allowed)
				(copperpour not_allowed)
				(footprints allowed)
			)
			(placement
				(enabled no)
				(sheetname "")
			)
			(fill
				(thermal_gap 0.5)
				(thermal_bridge_width 0.5)
				(island_removal_mode 0)
			)
			(polygon
				(pts
					(xy 89.916 -99.822) (xy 90.0684 -99.822) (xy 90.0684 -100.4316) (xy 89.916 -100.4316)
				)
			)
		)
	)
	(footprint ""
		(layer "B.Cu")
		(at 95.758 -22.606 90)
		(property "Reference" "L10"
			(at 0 2.25425 270)
			(unlocked yes)
			(layer "B.SilkS")
			(effects
				(font
					(size 0.635 0.4064)
					(thickness 0.1524)
				)
				(justify mirror)
			)
		)
		(property "Value" "VAL*"
			(at -0.014732 2.526538 90)
			(unlocked yes)
			(layer "B.Fab")
			(hide yes)
			(effects
				(font
					(size 0.7874 0.5842)
					(thickness 0.000001)
				)
				(justify mirror)
			)
		)
		(property "Device Type" "FERRITEBEAD-G191-10097-01,600OA"
			(at -0.014732 1.600708 90)
			(unlocked yes)
			(layer "B.Fab")
			(hide yes)
			(effects
				(font
					(size 0.7874 0.5842)
					(thickness 0.000001)
				)
				(justify mirror)
			)
		)
		(property "User Part Number" "PARTNUM*"
			(at -0.02794 4.480814 90)
			(unlocked yes)
			(layer "Cmts.User")
			(hide yes)
			(effects
				(font
					(size 0.7874 0.5842)
					(thickness 0.000001)
				)
				(justify mirror)
			)
		)
		(property "Tolerance" "TOL*"
			(at -0.014732 3.503676 90)
			(unlocked yes)
			(layer "Cmts.User")
			(hide yes)
			(effects
				(font
					(size 0.7874 0.5842)
					(thickness 0.000001)
				)
				(justify mirror)
			)
		)
		(duplicate_pad_numbers_are_jumpers no)
		(fp_line
			(start 1.3208 -0.7112)
			(end -1.3208 -0.7112)
			(stroke
				(width 0.1)
				(type default)
			)
			(layer "B.SilkS")
		)
		(fp_line
			(start -1.3208 -0.7112)
			(end -1.3208 0.7112)
			(stroke
				(width 0.1)
				(type default)
			)
			(layer "B.SilkS")
		)
		(fp_line
			(start 1.3208 0.7112)
			(end 1.3208 -0.7112)
			(stroke
				(width 0.1)
				(type default)
			)
			(layer "B.SilkS")
		)
		(fp_line
			(start -1.3208 0.7112)
			(end 1.3208 0.7112)
			(stroke
				(width 0.1)
				(type default)
			)
			(layer "B.SilkS")
		)
		(fp_rect
			(start 1.3208 0.7112)
			(end -1.3208 -0.7112)
			(stroke
				(width 0)
				(type default)
			)
			(fill no)
			(layer "B.CrtYd")
		)
		(fp_line
			(start 0.8128 -0.4572)
			(end -0.8128 -0.4572)
			(stroke
				(width 0.1)
				(type default)
			)
			(layer "B.Fab")
		)
		(fp_line
			(start -0.8128 -0.4572)
			(end -0.8128 0.4572)
			(stroke
				(width 0.1)
				(type default)
			)
			(layer "B.Fab")
		)
		(fp_line
			(start 0.8128 0.4572)
			(end 0.8128 -0.4572)
			(stroke
				(width 0.1)
				(type default)
			)
			(layer "B.Fab")
		)
		(fp_line
			(start -0.8128 0.4572)
			(end 0.8128 0.4572)
			(stroke
				(width 0.1)
				(type default)
			)
			(layer "B.Fab")
		)
		(pad "1" smd rect
			(at 0.6858 0 270)
			(size 0.762 0.8636)
			(layers "B.Cu" "B.Mask" "B.Paste")
			(net "VDD3V3_OSC_125M")
		)
		(pad "2" smd rect
			(at -0.6858 0 270)
			(size 0.762 0.8636)
			(layers "B.Cu" "B.Mask" "B.Paste")
			(net "XP3R3V")
		)
		(zone
			(layer "B.Cu")
			(hatch none 0.5)
			(connect_pads
				(clearance 0)
			)
			(min_thickness 0.25)
			(keepout
				(tracks not_allowed)
				(vias allowed)
				(pads allowed)
				(copperpour not_allowed)
				(footprints allowed)
			)
			(placement
				(enabled no)
				(sheetname "")
			)
			(fill
				(thermal_gap 0.5)
				(thermal_bridge_width 0.5)
				(island_removal_mode 0)
			)
			(polygon
				(pts
					(xy 96.2152 -22.7584) (xy 95.3008 -22.7584) (xy 95.3008 -22.4536) (xy 96.2152 -22.4536)
				)
			)
		)
		(zone
			(layer "B.Cu")
			(hatch none 0.5)
			(connect_pads
				(clearance 0)
			)
			(min_thickness 0.25)
			(keepout
				(tracks allowed)
				(vias not_allowed)
				(pads allowed)
				(copperpour not_allowed)
				(footprints allowed)
			)
			(placement
				(enabled no)
				(sheetname "")
			)
			(fill
				(thermal_gap 0.5)
				(thermal_bridge_width 0.5)
				(island_removal_mode 0)
			)
			(polygon
				(pts
					(xy 96.2152 -22.7584) (xy 95.3008 -22.7584) (xy 95.3008 -22.4536) (xy 96.2152 -22.4536)
				)
			)
		)
	)
	(footprint ""
		(layer "B.Cu")
		(at 95.631 -82.169 180)
		(property "Reference" "R191"
			(at 0.254 5.67563 0)
			(unlocked yes)
			(layer "B.SilkS")
			(effects
				(font
					(size 0.7874 0.5842)
					(thickness 0.1524)
				)
				(justify mirror)
			)
		)
		(property "Value" "VAL*"
			(at -0.02032 2.13233 180)
			(unlocked yes)
			(layer "B.Fab")
			(hide yes)
			(effects
				(font
					(size 0.7874 0.5842)
					(thickness 0.1524)
				)
				(justify mirror)
			)
		)
		(property "Device Type" "RESISTOR-G155-14701-01,4.7KOHMA"
			(at -0.008382 1.210564 180)
			(unlocked yes)
			(layer "B.Fab")
			(hide yes)
			(effects
				(font
					(size 0.7874 0.5842)
					(thickness 0.1524)
				)
				(justify mirror)
			)
		)
		(property "User Part Number" "PARTNUM*"
			(at -0.02032 4.024884 180)
			(unlocked yes)
			(layer "Cmts.User")
			(hide yes)
			(effects
				(font
					(size 0.7874 0.5842)
					(thickness 0.1524)
				)
				(justify mirror)
			)
		)
		(property "Tolerance" "TOL*"
			(at -0.044704 3.05435 180)
			(unlocked yes)
			(layer "Cmts.User")
			(hide yes)
			(effects
				(font
					(size 0.7874 0.5842)
					(thickness 0.1524)
				)
				(justify mirror)
			)
		)
		(duplicate_pad_numbers_are_jumpers no)
		(fp_line
			(start 1.143 0.5588)
			(end -1.143 0.5588)
			(stroke
				(width 0.1)
				(type default)
			)
			(layer "B.SilkS")
		)
		(fp_line
			(start 1.143 -0.5588)
			(end 1.143 0.5588)
			(stroke
				(width 0.1)
				(type default)
			)
			(layer "B.SilkS")
		)
		(fp_line
			(start -1.143 0.5588)
			(end -1.143 -0.5588)
			(stroke
				(width 0.1)
				(type default)
			)
			(layer "B.SilkS")
		)
		(fp_line
			(start -1.143 -0.5588)
			(end 1.143 -0.5588)
			(stroke
				(width 0.1)
				(type default)
			)
			(layer "B.SilkS")
		)
		(fp_rect
			(start 1.143 -0.5588)
			(end -1.143 0.5588)
			(stroke
				(width 0)
				(type default)
			)
			(fill no)
			(layer "B.CrtYd")
		)
		(fp_line
			(start 0.508 0.3048)
			(end -0.508 0.3048)
			(stroke
				(width 0.1)
				(type default)
			)
			(layer "B.Fab")
		)
		(fp_line
			(start 0.508 -0.3048)
			(end 0.508 0.3048)
			(stroke
				(width 0.1)
				(type default)
			)
			(layer "B.Fab")
		)
		(fp_line
			(start -0.508 0.3048)
			(end -0.508 -0.3048)
			(stroke
				(width 0.1)
				(type default)
			)
			(layer "B.Fab")
		)
		(fp_line
			(start -0.508 -0.3048)
			(end 0.508 -0.3048)
			(stroke
				(width 0.1)
				(type default)
			)
			(layer "B.Fab")
		)
		(pad "1" smd rect
			(at 0.5334 0)
			(size 0.7112 0.6096)
			(layers "B.Cu" "B.Mask" "B.Paste")
			(net "XP3R3V_FPGA")
		)
		(pad "2" smd rect
			(at -0.5334 0)
			(size 0.7112 0.6096)
			(layers "B.Cu" "B.Mask" "B.Paste")
			(net "FLASH_CS_N")
		)
		(zone
			(layer "B.Cu")
			(hatch none 0.5)
			(connect_pads
				(clearance 0)
			)
			(min_thickness 0.25)
			(keepout
				(tracks allowed)
				(vias not_allowed)
				(pads allowed)
				(copperpour not_allowed)
				(footprints allowed)
			)
			(placement
				(enabled no)
				(sheetname "")
			)
			(fill
				(thermal_gap 0.5)
				(thermal_bridge_width 0.5)
				(island_removal_mode 0)
			)
			(polygon
				(pts
					(xy 95.5548 -81.8642) (xy 95.7072 -81.8642) (xy 95.7072 -82.4738) (xy 95.5548 -82.4738)
				)
			)
		)
	)
	(footprint ""
		(layer "B.Cu")
		(at 20.955 -38.1)
		(property "Reference" "R27"
			(at 0.127 4.48437 0)
			(unlocked yes)
			(layer "B.SilkS")
			(effects
				(font
					(size 0.7874 0.5842)
					(thickness 0.1524)
				)
				(justify mirror)
			)
		)
		(property "Value" "VAL*"
			(at -0.02032 2.13233 0)
			(unlocked yes)
			(layer "B.Fab")
			(hide yes)
			(effects
				(font
					(size 0.7874 0.5842)
					(thickness 0.1524)
				)
				(justify mirror)
			)
		)
		(property "Device Type" "RESISTOR-G155-133R0-01,33OHM,1%"
			(at -0.008382 1.210564 0)
			(unlocked yes)
			(layer "B.Fab")
			(hide yes)
			(effects
				(font
					(size 0.7874 0.5842)
					(thickness 0.1524)
				)
				(justify mirror)
			)
		)
		(property "User Part Number" "PARTNUM*"
			(at -0.02032 4.024884 0)
			(unlocked yes)
			(layer "Cmts.User")
			(hide yes)
			(effects
				(font
					(size 0.7874 0.5842)
					(thickness 0.1524)
				)
				(justify mirror)
			)
		)
		(property "Tolerance" "TOL*"
			(at -0.044704 3.05435 0)
			(unlocked yes)
			(layer "Cmts.User")
			(hide yes)
			(effects
				(font
					(size 0.7874 0.5842)
					(thickness 0.1524)
				)
				(justify mirror)
			)
		)
		(duplicate_pad_numbers_are_jumpers no)
		(fp_line
			(start -1.143 -0.5588)
			(end 1.143 -0.5588)
			(stroke
				(width 0.1)
				(type default)
			)
			(layer "B.SilkS")
		)
		(fp_line
			(start -1.143 0.5588)
			(end -1.143 -0.5588)
			(stroke
				(width 0.1)
				(type default)
			)
			(layer "B.SilkS")
		)
		(fp_line
			(start 1.143 -0.5588)
			(end 1.143 0.5588)
			(stroke
				(width 0.1)
				(type default)
			)
			(layer "B.SilkS")
		)
		(fp_line
			(start 1.143 0.5588)
			(end -1.143 0.5588)
			(stroke
				(width 0.1)
				(type default)
			)
			(layer "B.SilkS")
		)
		(fp_rect
			(start 1.143 0.5588)
			(end -1.143 -0.5588)
			(stroke
				(width 0)
				(type default)
			)
			(fill no)
			(layer "B.CrtYd")
		)
		(fp_line
			(start -0.508 -0.3048)
			(end 0.508 -0.3048)
			(stroke
				(width 0.1)
				(type default)
			)
			(layer "B.Fab")
		)
		(fp_line
			(start -0.508 0.3048)
			(end -0.508 -0.3048)
			(stroke
				(width 0.1)
				(type default)
			)
			(layer "B.Fab")
		)
		(fp_line
			(start 0.508 -0.3048)
			(end 0.508 0.3048)
			(stroke
				(width 0.1)
				(type default)
			)
			(layer "B.Fab")
		)
		(fp_line
			(start 0.508 0.3048)
			(end -0.508 0.3048)
			(stroke
				(width 0.1)
				(type default)
			)
			(layer "B.Fab")
		)
		(pad "1" smd rect
			(at 0.5334 0 180)
			(size 0.7112 0.6096)
			(layers "B.Cu" "B.Mask" "B.Paste")
			(net "PCIE_SMCLK")
		)
		(pad "2" smd rect
			(at -0.5334 0 180)
			(size 0.7112 0.6096)
			(layers "B.Cu" "B.Mask" "B.Paste")
			(net "R_PCA9546_I2C_SCL")
		)
		(zone
			(layer "B.Cu")
			(hatch none 0.5)
			(connect_pads
				(clearance 0)
			)
			(min_thickness 0.25)
			(keepout
				(tracks allowed)
				(vias not_allowed)
				(pads allowed)
				(copperpour not_allowed)
				(footprints allowed)
			)
			(placement
				(enabled no)
				(sheetname "")
			)
			(fill
				(thermal_gap 0.5)
				(thermal_bridge_width 0.5)
				(island_removal_mode 0)
			)
			(polygon
				(pts
					(xy 21.0312 -37.7952) (xy 21.0312 -38.4048) (xy 20.8788 -38.4048) (xy 20.8788 -37.7952)
				)
			)
		)
	)
	(footprint ""
		(layer "B.Cu")
		(at 134.0612 -66.8528 -90)
		(property "Reference" "R188"
			(at 0.0508 1.89357 270)
			(unlocked yes)
			(layer "B.SilkS")
			(effects
				(font
					(size 0.7874 0.5842)
					(thickness 0.1524)
				)
				(justify mirror)
			)
		)
		(property "Value" "VAL*"
			(at -0.02032 2.13233 270)
			(unlocked yes)
			(layer "B.Fab")
			(hide yes)
			(effects
				(font
					(size 0.7874 0.5842)
					(thickness 0.1524)
				)
				(justify mirror)
			)
		)
		(property "Tolerance" "TOL*"
			(at -0.044704 3.05435 270)
			(unlocked yes)
			(layer "Cmts.User")
			(hide yes)
			(effects
				(font
					(size 0.7874 0.5842)
					(thickness 0.1524)
				)
				(justify mirror)
			)
		)
		(property "User Part Number" "PARTNUM*"
			(at -0.02032 4.024884 270)
			(unlocked yes)
			(layer "Cmts.User")
			(hide yes)
			(effects
				(font
					(size 0.7874 0.5842)
					(thickness 0.1524)
				)
				(justify mirror)
			)
		)
		(property "Device Type" "RESISTOR-G155-03241-01,3.24KOHA"
			(at -0.008382 1.210564 270)
			(unlocked yes)
			(layer "B.Fab")
			(hide yes)
			(effects
				(font
					(size 0.7874 0.5842)
					(thickness 0.1524)
				)
				(justify mirror)
			)
		)
		(duplicate_pad_numbers_are_jumpers no)
		(fp_line
			(start -1.143 0.5588)
			(end -1.143 -0.5588)
			(stroke
				(width 0.1)
				(type default)
			)
			(layer "B.SilkS")
		)
		(fp_line
			(start 1.143 0.5588)
			(end -1.143 0.5588)
			(stroke
				(width 0.1)
				(type default)
			)
			(layer "B.SilkS")
		)
		(fp_line
			(start -1.143 -0.5588)
			(end 1.143 -0.5588)
			(stroke
				(width 0.1)
				(type default)
			)
			(layer "B.SilkS")
		)
		(fp_line
			(start 1.143 -0.5588)
			(end 1.143 0.5588)
			(stroke
				(width 0.1)
				(type default)
			)
			(layer "B.SilkS")
		)
		(fp_rect
			(start -1.143 -0.5588)
			(end 1.143 0.5588)
			(stroke
				(width 0)
				(type default)
			)
			(fill no)
			(layer "B.CrtYd")
		)
		(fp_line
			(start -0.508 0.3048)
			(end -0.508 -0.3048)
			(stroke
				(width 0.1)
				(type default)
			)
			(layer "B.Fab")
		)
		(fp_line
			(start 0.508 0.3048)
			(end -0.508 0.3048)
			(stroke
				(width 0.1)
				(type default)
			)
			(layer "B.Fab")
		)
		(fp_line
			(start -0.508 -0.3048)
			(end 0.508 -0.3048)
			(stroke
				(width 0.1)
				(type default)
			)
			(layer "B.Fab")
		)
		(fp_line
			(start 0.508 -0.3048)
			(end 0.508 0.3048)
			(stroke
				(width 0.1)
				(type default)
			)
			(layer "B.Fab")
		)
		(pad "1" smd rect
			(at 0.5334 0 90)
			(size 0.7112 0.6096)
			(layers "B.Cu" "B.Mask" "B.Paste")
			(net "SG")
		)
		(pad "2" smd rect
			(at -0.5334 0 90)
			(size 0.7112 0.6096)
			(layers "B.Cu" "B.Mask" "B.Paste")
			(net "XP1R8V_FB")
		)
		(zone
			(layer "B.Cu")
			(hatch none 0.5)
			(connect_pads
				(clearance 0)
			)
			(min_thickness 0.25)
			(keepout
				(tracks allowed)
				(vias not_allowed)
				(pads allowed)
				(copperpour not_allowed)
				(footprints allowed)
			)
			(placement
				(enabled no)
				(sheetname "")
			)
			(fill
				(thermal_gap 0.5)
				(thermal_bridge_width 0.5)
				(island_removal_mode 0)
			)
			(polygon
				(pts
					(xy 134.366 -66.929) (xy 133.7564 -66.929) (xy 133.7564 -66.7766) (xy 134.366 -66.7766)
				)
			)
		)
	)
	(footprint ""
		(layer "B.Cu")
		(at 139.5476 -81.4324)
		(property "Reference" "C303"
			(at 0.6604 -7.68223 0)
			(unlocked yes)
			(layer "B.SilkS")
			(effects
				(font
					(size 0.7874 0.5842)
					(thickness 0.1524)
				)
				(justify mirror)
			)
		)
		(property "Value" "VAL*"
			(at -0.0762 3.134106 0)
			(unlocked yes)
			(layer "B.Fab")
			(hide yes)
			(effects
				(font
					(size 0.7874 0.5842)
					(thickness 0.1524)
				)
				(justify mirror)
			)
		)
		(property "Device Type" "CAPACITOR-G107-0F106-EM,10UF,2A"
			(at -0.0508 2.194306 0)
			(unlocked yes)
			(layer "B.Fab")
			(hide yes)
			(effects
				(font
					(size 0.7874 0.5842)
					(thickness 0.1524)
				)
				(justify mirror)
			)
		)
		(property "User Part Number" "PARTNUM*"
			(at -0.1016 5.013706 0)
			(unlocked yes)
			(layer "Cmts.User")
			(hide yes)
			(effects
				(font
					(size 0.7874 0.5842)
					(thickness 0.1524)
				)
				(justify mirror)
			)
		)
		(property "Tolerance" "TOL*"
			(at -0.0762 4.048506 0)
			(unlocked yes)
			(layer "Cmts.User")
			(hide yes)
			(effects
				(font
					(size 0.7874 0.5842)
					(thickness 0.1524)
				)
				(justify mirror)
			)
		)
		(duplicate_pad_numbers_are_jumpers no)
		(fp_line
			(start -1.5748 -0.9398)
			(end 1.5748 -0.9398)
			(stroke
				(width 0.1)
				(type default)
			)
			(layer "B.SilkS")
		)
		(fp_line
			(start -1.5748 0.9398)
			(end -1.5748 -0.9398)
			(stroke
				(width 0.1)
				(type default)
			)
			(layer "B.SilkS")
		)
		(fp_line
			(start 1.5748 -0.9398)
			(end 1.5748 0.9398)
			(stroke
				(width 0.1)
				(type default)
			)
			(layer "B.SilkS")
		)
		(fp_line
			(start 1.5748 0.9398)
			(end -1.5748 0.9398)
			(stroke
				(width 0.1)
				(type default)
			)
			(layer "B.SilkS")
		)
		(fp_rect
			(start 1.5748 0.9398)
			(end -1.5748 -0.9398)
			(stroke
				(width 0)
				(type default)
			)
			(fill no)
			(layer "B.CrtYd")
		)
		(fp_line
			(start -1.016 -0.635)
			(end 1.016 -0.635)
			(stroke
				(width 0.1)
				(type default)
			)
			(layer "B.Fab")
		)
		(fp_line
			(start -1.016 0.635)
			(end -1.016 -0.635)
			(stroke
				(width 0.1)
				(type default)
			)
			(layer "B.Fab")
		)
		(fp_line
			(start 1.016 -0.635)
			(end 1.016 0.635)
			(stroke
				(width 0.1)
				(type default)
			)
			(layer "B.Fab")
		)
		(fp_line
			(start 1.016 0.635)
			(end -1.016 0.635)
			(stroke
				(width 0.1)
				(type default)
			)
			(layer "B.Fab")
		)
		(pad "1" smd rect
			(at 0.8382 0 180)
			(size 0.9652 1.3716)
			(layers "B.Cu" "B.Mask" "B.Paste")
			(net "XP12R0V_IN")
		)
		(pad "2" smd rect
			(at -0.8382 0 180)
			(size 0.9652 1.3716)
			(layers "B.Cu" "B.Mask" "B.Paste")
			(net "SG")
		)
		(zone
			(layer "B.Cu")
			(hatch none 0.5)
			(connect_pads
				(clearance 0)
			)
			(min_thickness 0.25)
			(keepout
				(tracks allowed)
				(vias not_allowed)
				(pads allowed)
				(copperpour not_allowed)
				(footprints allowed)
			)
			(placement
				(enabled no)
				(sheetname "")
			)
			(fill
				(thermal_gap 0.5)
				(thermal_bridge_width 0.5)
				(island_removal_mode 0)
			)
			(polygon
				(pts
					(xy 139.7762 -80.7974) (xy 139.7762 -82.0674) (xy 139.319 -82.0674) (xy 139.319 -80.7974)
				)
			)
		)
		(zone
			(layer "B.Cu")
			(hatch none 0.5)
			(connect_pads
				(clearance 0)
			)
			(min_thickness 0.25)
			(keepout
				(tracks not_allowed)
				(vias allowed)
				(pads allowed)
				(copperpour not_allowed)
				(footprints allowed)
			)
			(placement
				(enabled no)
				(sheetname "")
			)
			(fill
				(thermal_gap 0.5)
				(thermal_bridge_width 0.5)
				(island_removal_mode 0)
			)
			(polygon
				(pts
					(xy 139.7762 -80.7974) (xy 139.7762 -82.0674) (xy 139.319 -82.0674) (xy 139.319 -80.7974)
				)
			)
		)
	)
	(footprint ""
		(layer "B.Cu")
		(at 113.347246 -41.823132 180)
		(property "Reference" "C147"
			(at 41.909746 -1.250442 0)
			(unlocked yes)
			(layer "B.SilkS")
			(effects
				(font
					(size 0.635 0.4064)
					(thickness 0.1524)
				)
				(justify mirror)
			)
		)
		(property "Value" "VAL*"
			(at 0 3.718306 180)
			(unlocked yes)
			(layer "B.Fab")
			(hide yes)
			(effects
				(font
					(size 0.7874 0.5842)
					(thickness 0.127)
				)
				(justify mirror)
			)
		)
		(property "Device Type" "CAPACITOR-G105-0B104-CK,0.1UF,A"
			(at 0 1.432306 180)
			(unlocked yes)
			(layer "B.Fab")
			(hide yes)
			(effects
				(font
					(size 0.7874 0.5842)
					(thickness 0.127)
				)
				(justify mirror)
			)
		)
		(property "User Part Number" "PARTNUM*"
			(at 0 2.575306 180)
			(unlocked yes)
			(layer "Cmts.User")
			(hide yes)
			(effects
				(font
					(size 0.7874 0.5842)
					(thickness 0.127)
				)
				(justify mirror)
			)
		)
		(property "Tolerance" "TOL*"
			(at 0 4.861306 180)
			(unlocked yes)
			(layer "Cmts.User")
			(hide yes)
			(effects
				(font
					(size 0.7874 0.5842)
					(thickness 0.127)
				)
				(justify mirror)
			)
		)
		(duplicate_pad_numbers_are_jumpers no)
		(fp_line
			(start 0.970026 0.4699)
			(end 0.970026 -0.4699)
			(stroke
				(width 0.1)
				(type default)
			)
			(layer "B.SilkS")
		)
		(fp_line
			(start 0.970026 -0.4699)
			(end -0.970026 -0.4699)
			(stroke
				(width 0.1)
				(type default)
			)
			(layer "B.SilkS")
		)
		(fp_line
			(start -0.970026 0.4699)
			(end 0.970026 0.4699)
			(stroke
				(width 0.1)
				(type default)
			)
			(layer "B.SilkS")
		)
		(fp_line
			(start -0.970026 -0.4699)
			(end -0.970026 0.4699)
			(stroke
				(width 0.1)
				(type default)
			)
			(layer "B.SilkS")
		)
		(fp_poly
			(pts
				(xy 0.970026 0.4699) (xy -0.970026 0.4699) (xy -0.970026 -0.4699) (xy 0.970026 -0.4699)
			)
			(stroke
				(width 0)
				(type default)
			)
			(fill no)
			(layer "B.CrtYd")
		)
		(fp_line
			(start 0.508 0.3048)
			(end 0.508 -0.3048)
			(stroke
				(width 0.1)
				(type default)
			)
			(layer "B.Fab")
		)
		(fp_line
			(start 0.508 -0.3048)
			(end -0.508 -0.3048)
			(stroke
				(width 0.1)
				(type default)
			)
			(layer "B.Fab")
		)
		(fp_line
			(start -0.508 0.3048)
			(end 0.508 0.3048)
			(stroke
				(width 0.1)
				(type default)
			)
			(layer "B.Fab")
		)
		(fp_line
			(start -0.508 -0.3048)
			(end -0.508 0.3048)
			(stroke
				(width 0.1)
				(type default)
			)
			(layer "B.Fab")
		)
		(pad "1" smd circle
			(at 0.500126 0)
			(size 0.635 0.635)
			(layers "B.Cu" "B.Mask" "B.Paste")
			(net "XP1R0V_FPGA_VCCINT")
		)
		(pad "2" smd circle
			(at -0.500126 0)
			(size 0.635 0.635)
			(layers "B.Cu" "B.Mask" "B.Paste")
			(net "SG")
		)
	)
	(footprint ""
		(layer "B.Cu")
		(at 26.289 -79.121 90)
		(property "Reference" "C90"
			(at 0 -1.18237 270)
			(unlocked yes)
			(layer "B.SilkS")
			(effects
				(font
					(size 0.7874 0.5842)
					(thickness 0.1524)
				)
				(justify mirror)
			)
		)
		(property "Value" "VAL*"
			(at -0.02032 2.13233 90)
			(unlocked yes)
			(layer "B.Fab")
			(hide yes)
			(effects
				(font
					(size 0.7874 0.5842)
					(thickness 0.1524)
				)
				(justify mirror)
			)
		)
		(property "Tolerance" "TOL*"
			(at -0.044704 3.05435 90)
			(unlocked yes)
			(layer "Cmts.User")
			(hide yes)
			(effects
				(font
					(size 0.7874 0.5842)
					(thickness 0.1524)
				)
				(justify mirror)
			)
		)
		(property "User Part Number" "PARTNUM*"
			(at -0.02032 4.024884 90)
			(unlocked yes)
			(layer "Cmts.User")
			(hide yes)
			(effects
				(font
					(size 0.7874 0.5842)
					(thickness 0.1524)
				)
				(justify mirror)
			)
		)
		(property "Device Type" "CAPACITOR-G105-0F475-BM,4.7UF,A"
			(at -0.008382 1.210564 90)
			(unlocked yes)
			(layer "B.Fab")
			(hide yes)
			(effects
				(font
					(size 0.7874 0.5842)
					(thickness 0.1524)
				)
				(justify mirror)
			)
		)
		(duplicate_pad_numbers_are_jumpers no)
		(fp_line
			(start 1.143 -0.5588)
			(end 1.143 0.5588)
			(stroke
				(width 0.1)
				(type default)
			)
			(layer "B.SilkS")
		)
		(fp_line
			(start -1.143 -0.5588)
			(end 1.143 -0.5588)
			(stroke
				(width 0.1)
				(type default)
			)
			(layer "B.SilkS")
		)
		(fp_line
			(start 1.143 0.5588)
			(end -1.143 0.5588)
			(stroke
				(width 0.1)
				(type default)
			)
			(layer "B.SilkS")
		)
		(fp_line
			(start -1.143 0.5588)
			(end -1.143 -0.5588)
			(stroke
				(width 0.1)
				(type default)
			)
			(layer "B.SilkS")
		)
		(fp_poly
			(pts
				(xy 1.143 0.5588) (xy -1.143 0.5588) (xy -1.143 -0.5588) (xy 1.143 -0.5588)
			)
			(stroke
				(width 0)
				(type default)
			)
			(fill no)
			(layer "B.CrtYd")
		)
		(fp_line
			(start 0.508 -0.3048)
			(end 0.508 0.3048)
			(stroke
				(width 0.1)
				(type default)
			)
			(layer "B.Fab")
		)
		(fp_line
			(start -0.508 -0.3048)
			(end 0.508 -0.3048)
			(stroke
				(width 0.1)
				(type default)
			)
			(layer "B.Fab")
		)
		(fp_line
			(start 0.508 0.3048)
			(end -0.508 0.3048)
			(stroke
				(width 0.1)
				(type default)
			)
			(layer "B.Fab")
		)
		(fp_line
			(start -0.508 0.3048)
			(end -0.508 -0.3048)
			(stroke
				(width 0.1)
				(type default)
			)
			(layer "B.Fab")
		)
		(pad "1" smd rect
			(at 0.5334 0 270)
			(size 0.7112 0.6096)
			(layers "B.Cu" "B.Mask" "B.Paste")
			(net "FT4232_VREGOUT")
		)
		(pad "2" smd rect
			(at -0.5334 0 270)
			(size 0.7112 0.6096)
			(layers "B.Cu" "B.Mask" "B.Paste")
			(net "SG")
		)
		(zone
			(layer "B.Cu")
			(hatch none 0.5)
			(connect_pads
				(clearance 0)
			)
			(min_thickness 0.25)
			(keepout
				(tracks allowed)
				(vias not_allowed)
				(pads allowed)
				(copperpour not_allowed)
				(footprints allowed)
			)
			(placement
				(enabled no)
				(sheetname "")
			)
			(fill
				(thermal_gap 0.5)
				(thermal_bridge_width 0.5)
				(island_removal_mode 0)
			)
			(polygon
				(pts
					(xy 26.5938 -79.1972) (xy 25.9842 -79.1972) (xy 25.9842 -79.0448) (xy 26.5938 -79.0448)
				)
			)
		)
		(zone
			(layer "B.Cu")
			(hatch none 0.5)
			(connect_pads
				(clearance 0)
			)
			(min_thickness 0.25)
			(keepout
				(tracks not_allowed)
				(vias allowed)
				(pads allowed)
				(copperpour not_allowed)
				(footprints allowed)
			)
			(placement
				(enabled no)
				(sheetname "")
			)
			(fill
				(thermal_gap 0.5)
				(thermal_bridge_width 0.5)
				(island_removal_mode 0)
			)
			(polygon
				(pts
					(xy 26.5938 -79.1972) (xy 25.9842 -79.1972) (xy 25.9842 -79.0448) (xy 26.5938 -79.0448)
				)
			)
		)
	)
	(footprint ""
		(layer "B.Cu")
		(at 104.347264 -40.823134 180)
		(property "Reference" "C111"
			(at 41.400984 -1.251204 0)
			(unlocked yes)
			(layer "B.SilkS")
			(effects
				(font
					(size 0.635 0.4064)
					(thickness 0.1524)
				)
				(justify mirror)
			)
		)
		(property "Value" "VAL*"
			(at 0 3.718306 180)
			(unlocked yes)
			(layer "B.Fab")
			(hide yes)
			(effects
				(font
					(size 0.7874 0.5842)
					(thickness 0.127)
				)
				(justify mirror)
			)
		)
		(property "Tolerance" "TOL*"
			(at 0 4.861306 180)
			(unlocked yes)
			(layer "Cmts.User")
			(hide yes)
			(effects
				(font
					(size 0.7874 0.5842)
					(thickness 0.127)
				)
				(justify mirror)
			)
		)
		(property "User Part Number" "PARTNUM*"
			(at 0 2.575306 180)
			(unlocked yes)
			(layer "Cmts.User")
			(hide yes)
			(effects
				(font
					(size 0.7874 0.5842)
					(thickness 0.127)
				)
				(justify mirror)
			)
		)
		(property "Device Type" "CAPACITOR-G105-0B104-CK,0.1UF,A"
			(at 0 1.432306 180)
			(unlocked yes)
			(layer "B.Fab")
			(hide yes)
			(effects
				(font
					(size 0.7874 0.5842)
					(thickness 0.127)
				)
				(justify mirror)
			)
		)
		(duplicate_pad_numbers_are_jumpers no)
		(fp_line
			(start 0.970026 0.4699)
			(end 0.970026 -0.4699)
			(stroke
				(width 0.1)
				(type default)
			)
			(layer "B.SilkS")
		)
		(fp_line
			(start 0.970026 -0.4699)
			(end -0.970026 -0.4699)
			(stroke
				(width 0.1)
				(type default)
			)
			(layer "B.SilkS")
		)
		(fp_line
			(start -0.970026 0.4699)
			(end 0.970026 0.4699)
			(stroke
				(width 0.1)
				(type default)
			)
			(layer "B.SilkS")
		)
		(fp_line
			(start -0.970026 -0.4699)
			(end -0.970026 0.4699)
			(stroke
				(width 0.1)
				(type default)
			)
			(layer "B.SilkS")
		)
		(fp_poly
			(pts
				(xy 0.970026 0.4699) (xy -0.970026 0.4699) (xy -0.970026 -0.4699) (xy 0.970026 -0.4699)
			)
			(stroke
				(width 0)
				(type default)
			)
			(fill no)
			(layer "B.CrtYd")
		)
		(fp_line
			(start 0.508 0.3048)
			(end 0.508 -0.3048)
			(stroke
				(width 0.1)
				(type default)
			)
			(layer "B.Fab")
		)
		(fp_line
			(start 0.508 -0.3048)
			(end -0.508 -0.3048)
			(stroke
				(width 0.1)
				(type default)
			)
			(layer "B.Fab")
		)
		(fp_line
			(start -0.508 0.3048)
			(end 0.508 0.3048)
			(stroke
				(width 0.1)
				(type default)
			)
			(layer "B.Fab")
		)
		(fp_line
			(start -0.508 -0.3048)
			(end -0.508 0.3048)
			(stroke
				(width 0.1)
				(type default)
			)
			(layer "B.Fab")
		)
		(pad "1" smd circle
			(at 0.500126 0)
			(size 0.635 0.635)
			(layers "B.Cu" "B.Mask" "B.Paste")
			(net "XP1R0V_FPGA_MGTAVCC")
		)
		(pad "2" smd circle
			(at -0.500126 0)
			(size 0.635 0.635)
			(layers "B.Cu" "B.Mask" "B.Paste")
			(net "SG")
		)
	)
	(footprint ""
		(layer "B.Cu")
		(at 36.703 -103.886 180)
		(property "Reference" "R50"
			(at 4.064 -0.16637 0)
			(unlocked yes)
			(layer "B.SilkS")
			(effects
				(font
					(size 0.7874 0.5842)
					(thickness 0.1524)
				)
				(justify mirror)
			)
		)
		(property "Value" "VAL*"
			(at 0.0254 2.524506 180)
			(unlocked yes)
			(layer "B.Fab")
			(hide yes)
			(effects
				(font
					(size 0.7874 0.5842)
					(thickness 0.1524)
				)
				(justify mirror)
			)
		)
		(property "Device Type" "RESISTOR-G156-100R0-J0,0OHM,-"
			(at 0 1.610106 180)
			(unlocked yes)
			(layer "B.Fab")
			(hide yes)
			(effects
				(font
					(size 0.7874 0.5842)
					(thickness 0.1524)
				)
				(justify mirror)
			)
		)
		(property "User Part Number" "PARTNUM*"
			(at 0.0254 4.505706 180)
			(unlocked yes)
			(layer "Cmts.User")
			(hide yes)
			(effects
				(font
					(size 0.7874 0.5842)
					(thickness 0.1524)
				)
				(justify mirror)
			)
		)
		(property "Tolerance" "TOL*"
			(at 0.0254 3.464306 180)
			(unlocked yes)
			(layer "Cmts.User")
			(hide yes)
			(effects
				(font
					(size 0.7874 0.5842)
					(thickness 0.1524)
				)
				(justify mirror)
			)
		)
		(duplicate_pad_numbers_are_jumpers no)
		(fp_line
			(start 1.3208 0.7112)
			(end 1.3208 -0.7112)
			(stroke
				(width 0.1)
				(type default)
			)
			(layer "B.SilkS")
		)
		(fp_line
			(start 1.3208 -0.7112)
			(end -1.3208 -0.7112)
			(stroke
				(width 0.1)
				(type default)
			)
			(layer "B.SilkS")
		)
		(fp_line
			(start -1.3208 0.7112)
			(end 1.3208 0.7112)
			(stroke
				(width 0.1)
				(type default)
			)
			(layer "B.SilkS")
		)
		(fp_line
			(start -1.3208 -0.7112)
			(end -1.3208 0.7112)
			(stroke
				(width 0.1)
				(type default)
			)
			(layer "B.SilkS")
		)
		(fp_rect
			(start -1.3208 0.7112)
			(end 1.3208 -0.7112)
			(stroke
				(width 0)
				(type default)
			)
			(fill no)
			(layer "B.CrtYd")
		)
		(fp_line
			(start 0.8128 0.4572)
			(end 0.8128 -0.4572)
			(stroke
				(width 0.1)
				(type default)
			)
			(layer "B.Fab")
		)
		(fp_line
			(start 0.8128 -0.4572)
			(end -0.8128 -0.4572)
			(stroke
				(width 0.1)
				(type default)
			)
			(layer "B.Fab")
		)
		(fp_line
			(start -0.8128 0.4572)
			(end 0.8128 0.4572)
			(stroke
				(width 0.1)
				(type default)
			)
			(layer "B.Fab")
		)
		(fp_line
			(start -0.8128 -0.4572)
			(end -0.8128 0.4572)
			(stroke
				(width 0.1)
				(type default)
			)
			(layer "B.Fab")
		)
		(pad "1" smd rect
			(at 0.6858 0)
			(size 0.762 0.8636)
			(layers "B.Cu" "B.Mask" "B.Paste")
			(net "XP5R0V_AGND")
		)
		(pad "2" smd rect
			(at -0.6858 0)
			(size 0.762 0.8636)
			(layers "B.Cu" "B.Mask" "B.Paste")
			(net "XP5R0V_FB_R_TO_AGND")
		)
		(zone
			(layer "B.Cu")
			(hatch none 0.5)
			(connect_pads
				(clearance 0)
			)
			(min_thickness 0.25)
			(keepout
				(tracks allowed)
				(vias not_allowed)
				(pads allowed)
				(copperpour not_allowed)
				(footprints allowed)
			)
			(placement
				(enabled no)
				(sheetname "")
			)
			(fill
				(thermal_gap 0.5)
				(thermal_bridge_width 0.5)
				(island_removal_mode 0)
			)
			(polygon
				(pts
					(xy 36.8554 -104.3432) (xy 36.5506 -104.3432) (xy 36.5506 -103.4288) (xy 36.8554 -103.4288)
				)
			)
		)
	)
	(footprint ""
		(layer "B.Cu")
		(at 115.062 -29.464 90)
		(property "Reference" "R440"
			(at -3.556 0.08763 270)
			(unlocked yes)
			(layer "B.SilkS")
			(effects
				(font
					(size 0.7874 0.5842)
					(thickness 0.1524)
				)
				(justify mirror)
			)
		)
		(property "Value" "VAL*"
			(at -0.02032 2.13233 90)
			(unlocked yes)
			(layer "B.Fab")
			(hide yes)
			(effects
				(font
					(size 0.7874 0.5842)
					(thickness 0.1524)
				)
				(justify mirror)
			)
		)
		(property "Tolerance" "TOL*"
			(at -0.044704 3.05435 90)
			(unlocked yes)
			(layer "Cmts.User")
			(hide yes)
			(effects
				(font
					(size 0.7874 0.5842)
					(thickness 0.1524)
				)
				(justify mirror)
			)
		)
		(property "User Part Number" "PARTNUM*"
			(at -0.02032 4.024884 90)
			(unlocked yes)
			(layer "Cmts.User")
			(hide yes)
			(effects
				(font
					(size 0.7874 0.5842)
					(thickness 0.1524)
				)
				(justify mirror)
			)
		)
		(property "Device Type" "RESISTOR-G155-11002-01,10KOHM,A"
			(at -0.008382 1.210564 90)
			(unlocked yes)
			(layer "B.Fab")
			(hide yes)
			(effects
				(font
					(size 0.7874 0.5842)
					(thickness 0.1524)
				)
				(justify mirror)
			)
		)
		(duplicate_pad_numbers_are_jumpers no)
		(fp_line
			(start 1.143 -0.5588)
			(end 1.143 0.5588)
			(stroke
				(width 0.1)
				(type default)
			)
			(layer "B.SilkS")
		)
		(fp_line
			(start -1.143 -0.5588)
			(end 1.143 -0.5588)
			(stroke
				(width 0.1)
				(type default)
			)
			(layer "B.SilkS")
		)
		(fp_line
			(start 1.143 0.5588)
			(end -1.143 0.5588)
			(stroke
				(width 0.1)
				(type default)
			)
			(layer "B.SilkS")
		)
		(fp_line
			(start -1.143 0.5588)
			(end -1.143 -0.5588)
			(stroke
				(width 0.1)
				(type default)
			)
			(layer "B.SilkS")
		)
		(fp_poly
			(pts
				(xy 1.143 0.5588) (xy -1.143 0.5588) (xy -1.143 -0.5588) (xy 1.143 -0.5588)
			)
			(stroke
				(width 0)
				(type default)
			)
			(fill no)
			(layer "B.CrtYd")
		)
		(fp_line
			(start 0.508 -0.3048)
			(end 0.508 0.3048)
			(stroke
				(width 0.1)
				(type default)
			)
			(layer "B.Fab")
		)
		(fp_line
			(start -0.508 -0.3048)
			(end 0.508 -0.3048)
			(stroke
				(width 0.1)
				(type default)
			)
			(layer "B.Fab")
		)
		(fp_line
			(start 0.508 0.3048)
			(end -0.508 0.3048)
			(stroke
				(width 0.1)
				(type default)
			)
			(layer "B.Fab")
		)
		(fp_line
			(start -0.508 0.3048)
			(end -0.508 -0.3048)
			(stroke
				(width 0.1)
				(type default)
			)
			(layer "B.Fab")
		)
		(pad "1" smd rect
			(at 0.5334 0 270)
			(size 0.7112 0.6096)
			(layers "B.Cu" "B.Mask" "B.Paste")
			(net "FPGA_IN_MAC_PPS_OUTP")
		)
		(pad "2" smd rect
			(at -0.5334 0 270)
			(size 0.7112 0.6096)
			(layers "B.Cu" "B.Mask" "B.Paste")
			(net "SG")
		)
		(zone
			(layer "B.Cu")
			(hatch none 0.5)
			(connect_pads
				(clearance 0)
			)
			(min_thickness 0.25)
			(keepout
				(tracks not_allowed)
				(vias allowed)
				(pads allowed)
				(copperpour not_allowed)
				(footprints allowed)
			)
			(placement
				(enabled no)
				(sheetname "")
			)
			(fill
				(thermal_gap 0.5)
				(thermal_bridge_width 0.5)
				(island_removal_mode 0)
			)
			(polygon
				(pts
					(xy 115.3668 -29.5402) (xy 114.7572 -29.5402) (xy 114.7572 -29.3878) (xy 115.3668 -29.3878)
				)
			)
		)
		(zone
			(layer "B.Cu")
			(hatch none 0.5)
			(connect_pads
				(clearance 0)
			)
			(min_thickness 0.25)
			(keepout
				(tracks allowed)
				(vias not_allowed)
				(pads allowed)
				(copperpour not_allowed)
				(footprints allowed)
			)
			(placement
				(enabled no)
				(sheetname "")
			)
			(fill
				(thermal_gap 0.5)
				(thermal_bridge_width 0.5)
				(island_removal_mode 0)
			)
			(polygon
				(pts
					(xy 115.3668 -29.5402) (xy 114.7572 -29.5402) (xy 114.7572 -29.3878) (xy 115.3668 -29.3878)
				)
			)
		)
	)
	(footprint ""
		(layer "B.Cu")
		(at 109.728 -23.876 -90)
		(property "Reference" "C248"
			(at -0.127 2.96037 270)
			(unlocked yes)
			(layer "B.SilkS")
			(effects
				(font
					(size 0.7874 0.5842)
					(thickness 0.1524)
				)
				(justify mirror)
			)
		)
		(property "Value" "VAL*"
			(at -0.0762 2.067306 270)
			(unlocked yes)
			(layer "B.Fab")
			(hide yes)
			(effects
				(font
					(size 0.7874 0.5842)
					(thickness 0.1524)
				)
				(justify mirror)
			)
		)
		(property "Device Type" "CAPACITOR-G105-0B104-EK,0.1UF,A"
			(at -0.0508 1.127506 270)
			(unlocked yes)
			(layer "B.Fab")
			(hide yes)
			(effects
				(font
					(size 0.7874 0.5842)
					(thickness 0.1524)
				)
				(justify mirror)
			)
		)
		(property "User Part Number" "PARTNUM*"
			(at -0.1016 4.023106 270)
			(unlocked yes)
			(layer "Cmts.User")
			(hide yes)
			(effects
				(font
					(size 0.7874 0.5842)
					(thickness 0.1524)
				)
				(justify mirror)
			)
		)
		(property "Tolerance" "TOL*"
			(at -0.0762 3.032506 270)
			(unlocked yes)
			(layer "Cmts.User")
			(hide yes)
			(effects
				(font
					(size 0.7874 0.5842)
					(thickness 0.1524)
				)
				(justify mirror)
			)
		)
		(duplicate_pad_numbers_are_jumpers no)
		(fp_line
			(start -1.143 0.5588)
			(end -1.143 -0.5588)
			(stroke
				(width 0.1)
				(type default)
			)
			(layer "B.SilkS")
		)
		(fp_line
			(start 1.143 0.5588)
			(end -1.143 0.5588)
			(stroke
				(width 0.1)
				(type default)
			)
			(layer "B.SilkS")
		)
		(fp_line
			(start -1.143 -0.5588)
			(end 1.143 -0.5588)
			(stroke
				(width 0.1)
				(type default)
			)
			(layer "B.SilkS")
		)
		(fp_line
			(start 1.143 -0.5588)
			(end 1.143 0.5588)
			(stroke
				(width 0.1)
				(type default)
			)
			(layer "B.SilkS")
		)
		(fp_rect
			(start 1.143 -0.5588)
			(end -1.143 0.5588)
			(stroke
				(width 0)
				(type default)
			)
			(fill no)
			(layer "B.CrtYd")
		)
		(fp_line
			(start -0.508 0.3048)
			(end -0.508 -0.3048)
			(stroke
				(width 0.1)
				(type default)
			)
			(layer "B.Fab")
		)
		(fp_line
			(start 0.508 0.3048)
			(end -0.508 0.3048)
			(stroke
				(width 0.1)
				(type default)
			)
			(layer "B.Fab")
		)
		(fp_line
			(start -0.508 -0.3048)
			(end 0.508 -0.3048)
			(stroke
				(width 0.1)
				(type default)
			)
			(layer "B.Fab")
		)
		(fp_line
			(start 0.508 -0.3048)
			(end 0.508 0.3048)
			(stroke
				(width 0.1)
				(type default)
			)
			(layer "B.Fab")
		)
		(pad "1" smd rect
			(at 0.5334 0 90)
			(size 0.7112 0.6096)
			(layers "B.Cu" "B.Mask" "B.Paste")
			(net "VDD3V3_OSC_200M")
		)
		(pad "2" smd rect
			(at -0.5334 0 90)
			(size 0.7112 0.6096)
			(layers "B.Cu" "B.Mask" "B.Paste")
			(net "SG")
		)
		(zone
			(layer "B.Cu")
			(hatch none 0.5)
			(connect_pads
				(clearance 0)
			)
			(min_thickness 0.25)
			(keepout
				(tracks allowed)
				(vias not_allowed)
				(pads allowed)
				(copperpour not_allowed)
				(footprints allowed)
			)
			(placement
				(enabled no)
				(sheetname "")
			)
			(fill
				(thermal_gap 0.5)
				(thermal_bridge_width 0.5)
				(island_removal_mode 0)
			)
			(polygon
				(pts
					(xy 110.0328 -23.7998) (xy 110.0328 -23.9522) (xy 109.4232 -23.9522) (xy 109.4232 -23.7998)
				)
			)
		)
	)
	(footprint ""
		(layer "B.Cu")
		(at 89.9922 -101.2698 180)
		(property "Reference" "R36"
			(at -3.683 -0.03937 0)
			(unlocked yes)
			(layer "B.SilkS")
			(effects
				(font
					(size 0.7874 0.5842)
					(thickness 0.1524)
				)
				(justify mirror)
			)
		)
		(property "Value" "VAL*"
			(at -0.02032 2.13233 180)
			(unlocked yes)
			(layer "B.Fab")
			(hide yes)
			(effects
				(font
					(size 0.7874 0.5842)
					(thickness 0.1524)
				)
				(justify mirror)
			)
		)
		(property "Tolerance" "TOL*"
			(at -0.044704 3.05435 180)
			(unlocked yes)
			(layer "Cmts.User")
			(hide yes)
			(effects
				(font
					(size 0.7874 0.5842)
					(thickness 0.1524)
				)
				(justify mirror)
			)
		)
		(property "User Part Number" "PARTNUM*"
			(at -0.02032 4.024884 180)
			(unlocked yes)
			(layer "Cmts.User")
			(hide yes)
			(effects
				(font
					(size 0.7874 0.5842)
					(thickness 0.1524)
				)
				(justify mirror)
			)
		)
		(property "Device Type" "RESISTOR-G155-11002-01,10KOHM,A"
			(at -0.008382 1.210564 180)
			(unlocked yes)
			(layer "B.Fab")
			(hide yes)
			(effects
				(font
					(size 0.7874 0.5842)
					(thickness 0.1524)
				)
				(justify mirror)
			)
		)
		(duplicate_pad_numbers_are_jumpers no)
		(fp_line
			(start 1.143 0.5588)
			(end -1.143 0.5588)
			(stroke
				(width 0.1)
				(type default)
			)
			(layer "B.SilkS")
		)
		(fp_line
			(start 1.143 -0.5588)
			(end 1.143 0.5588)
			(stroke
				(width 0.1)
				(type default)
			)
			(layer "B.SilkS")
		)
		(fp_line
			(start -1.143 0.5588)
			(end -1.143 -0.5588)
			(stroke
				(width 0.1)
				(type default)
			)
			(layer "B.SilkS")
		)
		(fp_line
			(start -1.143 -0.5588)
			(end 1.143 -0.5588)
			(stroke
				(width 0.1)
				(type default)
			)
			(layer "B.SilkS")
		)
		(fp_rect
			(start 1.143 -0.5588)
			(end -1.143 0.5588)
			(stroke
				(width 0)
				(type default)
			)
			(fill no)
			(layer "B.CrtYd")
		)
		(fp_line
			(start 0.508 0.3048)
			(end -0.508 0.3048)
			(stroke
				(width 0.1)
				(type default)
			)
			(layer "B.Fab")
		)
		(fp_line
			(start 0.508 -0.3048)
			(end 0.508 0.3048)
			(stroke
				(width 0.1)
				(type default)
			)
			(layer "B.Fab")
		)
		(fp_line
			(start -0.508 0.3048)
			(end -0.508 -0.3048)
			(stroke
				(width 0.1)
				(type default)
			)
			(layer "B.Fab")
		)
		(fp_line
			(start -0.508 -0.3048)
			(end 0.508 -0.3048)
			(stroke
				(width 0.1)
				(type default)
			)
			(layer "B.Fab")
		)
		(pad "1" smd rect
			(at 0.5334 0)
			(size 0.7112 0.6096)
			(layers "B.Cu" "B.Mask" "B.Paste")
			(net "XP3R3V_COMP")
		)
		(pad "2" smd rect
			(at -0.5334 0)
			(size 0.7112 0.6096)
			(layers "B.Cu" "B.Mask" "B.Paste")
			(net "UNNAMED_517_CAPACITOR_I17_1")
		)
		(zone
			(layer "B.Cu")
			(hatch none 0.5)
			(connect_pads
				(clearance 0)
			)
			(min_thickness 0.25)
			(keepout
				(tracks allowed)
				(vias not_allowed)
				(pads allowed)
				(copperpour not_allowed)
				(footprints allowed)
			)
			(placement
				(enabled no)
				(sheetname "")
			)
			(fill
				(thermal_gap 0.5)
				(thermal_bridge_width 0.5)
				(island_removal_mode 0)
			)
			(polygon
				(pts
					(xy 89.916 -100.965) (xy 90.0684 -100.965) (xy 90.0684 -101.5746) (xy 89.916 -101.5746)
				)
			)
		)
	)
	(footprint ""
		(layer "B.Cu")
		(at 5.588 -75.565 180)
		(property "Reference" "R337"
			(at 3.048 0.59563 0)
			(unlocked yes)
			(layer "B.SilkS")
			(effects
				(font
					(size 0.7874 0.5842)
					(thickness 0.1524)
				)
				(justify mirror)
			)
		)
		(property "Value" "VAL*"
			(at -0.02032 2.13233 180)
			(unlocked yes)
			(layer "B.Fab")
			(hide yes)
			(effects
				(font
					(size 0.7874 0.5842)
					(thickness 0.1524)
				)
				(justify mirror)
			)
		)
		(property "Tolerance" "TOL*"
			(at -0.044704 3.05435 180)
			(unlocked yes)
			(layer "Cmts.User")
			(hide yes)
			(effects
				(font
					(size 0.7874 0.5842)
					(thickness 0.1524)
				)
				(justify mirror)
			)
		)
		(property "User Part Number" "PARTNUM*"
			(at -0.02032 4.024884 180)
			(unlocked yes)
			(layer "Cmts.User")
			(hide yes)
			(effects
				(font
					(size 0.7874 0.5842)
					(thickness 0.1524)
				)
				(justify mirror)
			)
		)
		(property "Device Type" "RESISTOR-G155-14701-01,4.7KOHMA"
			(at -0.008382 1.210564 180)
			(unlocked yes)
			(layer "B.Fab")
			(hide yes)
			(effects
				(font
					(size 0.7874 0.5842)
					(thickness 0.1524)
				)
				(justify mirror)
			)
		)
		(duplicate_pad_numbers_are_jumpers no)
		(fp_line
			(start 1.143 0.5588)
			(end -1.143 0.5588)
			(stroke
				(width 0.1)
				(type default)
			)
			(layer "B.SilkS")
		)
		(fp_line
			(start 1.143 -0.5588)
			(end 1.143 0.5588)
			(stroke
				(width 0.1)
				(type default)
			)
			(layer "B.SilkS")
		)
		(fp_line
			(start -1.143 0.5588)
			(end -1.143 -0.5588)
			(stroke
				(width 0.1)
				(type default)
			)
			(layer "B.SilkS")
		)
		(fp_line
			(start -1.143 -0.5588)
			(end 1.143 -0.5588)
			(stroke
				(width 0.1)
				(type default)
			)
			(layer "B.SilkS")
		)
		(fp_rect
			(start -1.143 0.5588)
			(end 1.143 -0.5588)
			(stroke
				(width 0)
				(type default)
			)
			(fill no)
			(layer "B.CrtYd")
		)
		(fp_line
			(start 0.508 0.3048)
			(end -0.508 0.3048)
			(stroke
				(width 0.1)
				(type default)
			)
			(layer "B.Fab")
		)
		(fp_line
			(start 0.508 -0.3048)
			(end 0.508 0.3048)
			(stroke
				(width 0.1)
				(type default)
			)
			(layer "B.Fab")
		)
		(fp_line
			(start -0.508 0.3048)
			(end -0.508 -0.3048)
			(stroke
				(width 0.1)
				(type default)
			)
			(layer "B.Fab")
		)
		(fp_line
			(start -0.508 -0.3048)
			(end 0.508 -0.3048)
			(stroke
				(width 0.1)
				(type default)
			)
			(layer "B.Fab")
		)
		(pad "1" smd rect
			(at 0.5334 0)
			(size 0.7112 0.6096)
			(layers "B.Cu" "B.Mask" "B.Paste")
			(net "XP3R3V_FPGA")
		)
		(pad "2" smd rect
			(at -0.5334 0)
			(size 0.7112 0.6096)
			(layers "B.Cu" "B.Mask" "B.Paste")
			(net "UNNAMED_6_LM75BDPTSSOP8_I34_A0")
		)
		(zone
			(layer "B.Cu")
			(hatch none 0.5)
			(connect_pads
				(clearance 0)
			)
			(min_thickness 0.25)
			(keepout
				(tracks allowed)
				(vias not_allowed)
				(pads allowed)
				(copperpour not_allowed)
				(footprints allowed)
			)
			(placement
				(enabled no)
				(sheetname "")
			)
			(fill
				(thermal_gap 0.5)
				(thermal_bridge_width 0.5)
				(island_removal_mode 0)
			)
			(polygon
				(pts
					(xy 5.6642 -75.8698) (xy 5.5118 -75.8698) (xy 5.5118 -75.2602) (xy 5.6642 -75.2602)
				)
			)
		)
	)
	(footprint ""
		(layer "B.Cu")
		(at 154.153108 -49.01311 90)
		(property "Reference" "R65"
			(at 3.56489 -0.141478 270)
			(unlocked yes)
			(layer "B.SilkS")
			(effects
				(font
					(size 0.7874 0.5842)
					(thickness 0.1524)
				)
				(justify mirror)
			)
		)
		(property "Value" "VAL*"
			(at -0.02032 2.13233 90)
			(unlocked yes)
			(layer "B.Fab")
			(hide yes)
			(effects
				(font
					(size 0.7874 0.5842)
					(thickness 0.1524)
				)
				(justify mirror)
			)
		)
		(property "Device Type" "RESISTOR-G155-14701-01,4.7KOHMA"
			(at -0.008382 1.210564 90)
			(unlocked yes)
			(layer "B.Fab")
			(hide yes)
			(effects
				(font
					(size 0.7874 0.5842)
					(thickness 0.1524)
				)
				(justify mirror)
			)
		)
		(property "User Part Number" "PARTNUM*"
			(at -0.02032 4.024884 90)
			(unlocked yes)
			(layer "Cmts.User")
			(hide yes)
			(effects
				(font
					(size 0.7874 0.5842)
					(thickness 0.1524)
				)
				(justify mirror)
			)
		)
		(property "Tolerance" "TOL*"
			(at -0.044704 3.05435 90)
			(unlocked yes)
			(layer "Cmts.User")
			(hide yes)
			(effects
				(font
					(size 0.7874 0.5842)
					(thickness 0.1524)
				)
				(justify mirror)
			)
		)
		(duplicate_pad_numbers_are_jumpers no)
		(fp_line
			(start 1.143 -0.5588)
			(end 1.143 0.5588)
			(stroke
				(width 0.1)
				(type default)
			)
			(layer "B.SilkS")
		)
		(fp_line
			(start -1.143 -0.5588)
			(end 1.143 -0.5588)
			(stroke
				(width 0.1)
				(type default)
			)
			(layer "B.SilkS")
		)
		(fp_line
			(start 1.143 0.5588)
			(end -1.143 0.5588)
			(stroke
				(width 0.1)
				(type default)
			)
			(layer "B.SilkS")
		)
		(fp_line
			(start -1.143 0.5588)
			(end -1.143 -0.5588)
			(stroke
				(width 0.1)
				(type default)
			)
			(layer "B.SilkS")
		)
		(fp_rect
			(start 1.143 0.5588)
			(end -1.143 -0.5588)
			(stroke
				(width 0)
				(type default)
			)
			(fill no)
			(layer "B.CrtYd")
		)
		(fp_line
			(start 0.508 -0.3048)
			(end 0.508 0.3048)
			(stroke
				(width 0.1)
				(type default)
			)
			(layer "B.Fab")
		)
		(fp_line
			(start -0.508 -0.3048)
			(end 0.508 -0.3048)
			(stroke
				(width 0.1)
				(type default)
			)
			(layer "B.Fab")
		)
		(fp_line
			(start 0.508 0.3048)
			(end -0.508 0.3048)
			(stroke
				(width 0.1)
				(type default)
			)
			(layer "B.Fab")
		)
		(fp_line
			(start -0.508 0.3048)
			(end -0.508 -0.3048)
			(stroke
				(width 0.1)
				(type default)
			)
			(layer "B.Fab")
		)
		(pad "1" smd rect
			(at 0.5334 0 270)
			(size 0.7112 0.6096)
			(layers "B.Cu" "B.Mask" "B.Paste")
			(net "XP3R3V_FPGA")
		)
		(pad "2" smd rect
			(at -0.5334 0 270)
			(size 0.7112 0.6096)
			(layers "B.Cu" "B.Mask" "B.Paste")
			(net "SHT3X_I2C_SCL")
		)
		(zone
			(layer "B.Cu")
			(hatch none 0.5)
			(connect_pads
				(clearance 0)
			)
			(min_thickness 0.25)
			(keepout
				(tracks allowed)
				(vias not_allowed)
				(pads allowed)
				(copperpour not_allowed)
				(footprints allowed)
			)
			(placement
				(enabled no)
				(sheetname "")
			)
			(fill
				(thermal_gap 0.5)
				(thermal_bridge_width 0.5)
				(island_removal_mode 0)
			)
			(polygon
				(pts
					(xy 154.457908 -49.08931) (xy 153.848308 -49.08931) (xy 153.848308 -48.93691) (xy 154.457908 -48.93691)
				)
			)
		)
	)
	(footprint ""
		(layer "B.Cu")
		(at 92.583 -35.433)
		(property "Reference" "L35"
			(at 1.2065 1.43637 0)
			(unlocked yes)
			(layer "B.SilkS")
			(effects
				(font
					(size 0.7874 0.5842)
					(thickness 0.1524)
				)
				(justify left mirror)
			)
		)
		(property "Value" "VAL*"
			(at 0.9398 3.70967 0)
			(unlocked yes)
			(layer "B.Fab")
			(hide yes)
			(effects
				(font
					(size 0.7874 0.5842)
					(thickness 0.1524)
				)
				(justify left mirror)
			)
		)
		(property "Device Type" "FERRITEBEAD-G191-10100-01,120OA"
			(at 0.9906 1.22047 0)
			(unlocked yes)
			(layer "B.Fab")
			(hide yes)
			(effects
				(font
					(size 0.7874 0.5842)
					(thickness 0.1524)
				)
				(justify left mirror)
			)
		)
		(property "User Part Number" "PARTNUM*"
			(at 2.54 2.46507 0)
			(unlocked yes)
			(layer "Cmts.User")
			(hide yes)
			(effects
				(font
					(size 0.7874 0.5842)
					(thickness 0.1524)
				)
				(justify left mirror)
			)
		)
		(property "Tolerance" "TOL*"
			(at 0.9906 5.00507 0)
			(unlocked yes)
			(layer "Cmts.User")
			(hide yes)
			(effects
				(font
					(size 0.7874 0.5842)
					(thickness 0.1524)
				)
				(justify left mirror)
			)
		)
		(duplicate_pad_numbers_are_jumpers no)
		(fp_line
			(start -1.3208 -0.7112)
			(end -1.3208 0.7112)
			(stroke
				(width 0.1)
				(type default)
			)
			(layer "B.SilkS")
		)
		(fp_line
			(start -1.3208 0.7112)
			(end 1.3208 0.7112)
			(stroke
				(width 0.1)
				(type default)
			)
			(layer "B.SilkS")
		)
		(fp_line
			(start 1.3208 -0.7112)
			(end -1.3208 -0.7112)
			(stroke
				(width 0.1)
				(type default)
			)
			(layer "B.SilkS")
		)
		(fp_line
			(start 1.3208 0.7112)
			(end 1.3208 -0.7112)
			(stroke
				(width 0.1)
				(type default)
			)
			(layer "B.SilkS")
		)
		(fp_rect
			(start 1.3208 0.7112)
			(end -1.3208 -0.7112)
			(stroke
				(width 0)
				(type default)
			)
			(fill no)
			(layer "B.CrtYd")
		)
		(fp_line
			(start -0.8128 -0.4572)
			(end -0.8128 0.4572)
			(stroke
				(width 0.1)
				(type default)
			)
			(layer "B.Fab")
		)
		(fp_line
			(start -0.8128 0.4572)
			(end 0.8128 0.4572)
			(stroke
				(width 0.1)
				(type default)
			)
			(layer "B.Fab")
		)
		(fp_line
			(start 0.8128 -0.4572)
			(end -0.8128 -0.4572)
			(stroke
				(width 0.1)
				(type default)
			)
			(layer "B.Fab")
		)
		(fp_line
			(start 0.8128 0.4572)
			(end 0.8128 -0.4572)
			(stroke
				(width 0.1)
				(type default)
			)
			(layer "B.Fab")
		)
		(pad "1" smd rect
			(at 0.6858 0 180)
			(size 0.762 0.8636)
			(layers "B.Cu" "B.Mask" "B.Paste")
			(net "FPGA_MGTAVTT")
		)
		(pad "2" smd rect
			(at -0.6858 0 180)
			(size 0.762 0.8636)
			(layers "B.Cu" "B.Mask" "B.Paste")
			(net "XP1R2V_FPGA")
		)
		(zone
			(layer "B.Cu")
			(hatch none 0.5)
			(connect_pads
				(clearance 0)
			)
			(min_thickness 0.25)
			(keepout
				(tracks not_allowed)
				(vias allowed)
				(pads allowed)
				(copperpour not_allowed)
				(footprints allowed)
			)
			(placement
				(enabled no)
				(sheetname "")
			)
			(fill
				(thermal_gap 0.5)
				(thermal_bridge_width 0.5)
				(island_removal_mode 0)
			)
			(polygon
				(pts
					(xy 92.7354 -34.9758) (xy 92.7354 -35.8902) (xy 92.4306 -35.8902) (xy 92.4306 -34.9758)
				)
			)
		)
		(zone
			(layer "B.Cu")
			(hatch none 0.5)
			(connect_pads
				(clearance 0)
			)
			(min_thickness 0.25)
			(keepout
				(tracks allowed)
				(vias not_allowed)
				(pads allowed)
				(copperpour not_allowed)
				(footprints allowed)
			)
			(placement
				(enabled no)
				(sheetname "")
			)
			(fill
				(thermal_gap 0.5)
				(thermal_bridge_width 0.5)
				(island_removal_mode 0)
			)
			(polygon
				(pts
					(xy 92.7354 -34.9758) (xy 92.7354 -35.8902) (xy 92.4306 -35.8902) (xy 92.4306 -34.9758)
				)
			)
		)
	)
	(footprint ""
		(layer "B.Cu")
		(at 77.3938 -85.09)
		(property "Reference" "R151"
			(at -1.1938 -2.24663 0)
			(unlocked yes)
			(layer "B.SilkS")
			(effects
				(font
					(size 0.7874 0.5842)
					(thickness 0.1524)
				)
				(justify mirror)
			)
		)
		(property "Value" "VAL*"
			(at -0.02032 2.13233 0)
			(unlocked yes)
			(layer "B.Fab")
			(hide yes)
			(effects
				(font
					(size 0.7874 0.5842)
					(thickness 0.1524)
				)
				(justify mirror)
			)
		)
		(property "Tolerance" "TOL*"
			(at -0.044704 3.05435 0)
			(unlocked yes)
			(layer "Cmts.User")
			(hide yes)
			(effects
				(font
					(size 0.7874 0.5842)
					(thickness 0.1524)
				)
				(justify mirror)
			)
		)
		(property "User Part Number" "PARTNUM*"
			(at -0.02032 4.024884 0)
			(unlocked yes)
			(layer "Cmts.User")
			(hide yes)
			(effects
				(font
					(size 0.7874 0.5842)
					(thickness 0.1524)
				)
				(justify mirror)
			)
		)
		(property "Device Type" "RESISTOR-G155-14701-01,4.7KOHMA"
			(at -0.008382 1.210564 0)
			(unlocked yes)
			(layer "B.Fab")
			(hide yes)
			(effects
				(font
					(size 0.7874 0.5842)
					(thickness 0.1524)
				)
				(justify mirror)
			)
		)
		(duplicate_pad_numbers_are_jumpers no)
		(fp_line
			(start -1.143 -0.5588)
			(end 1.143 -0.5588)
			(stroke
				(width 0.1)
				(type default)
			)
			(layer "B.SilkS")
		)
		(fp_line
			(start -1.143 0.5588)
			(end -1.143 -0.5588)
			(stroke
				(width 0.1)
				(type default)
			)
			(layer "B.SilkS")
		)
		(fp_line
			(start 1.143 -0.5588)
			(end 1.143 0.5588)
			(stroke
				(width 0.1)
				(type default)
			)
			(layer "B.SilkS")
		)
		(fp_line
			(start 1.143 0.5588)
			(end -1.143 0.5588)
			(stroke
				(width 0.1)
				(type default)
			)
			(layer "B.SilkS")
		)
		(fp_rect
			(start 1.143 -0.5588)
			(end -1.143 0.5588)
			(stroke
				(width 0)
				(type default)
			)
			(fill no)
			(layer "B.CrtYd")
		)
		(fp_line
			(start -0.508 -0.3048)
			(end 0.508 -0.3048)
			(stroke
				(width 0.1)
				(type default)
			)
			(layer "B.Fab")
		)
		(fp_line
			(start -0.508 0.3048)
			(end -0.508 -0.3048)
			(stroke
				(width 0.1)
				(type default)
			)
			(layer "B.Fab")
		)
		(fp_line
			(start 0.508 -0.3048)
			(end 0.508 0.3048)
			(stroke
				(width 0.1)
				(type default)
			)
			(layer "B.Fab")
		)
		(fp_line
			(start 0.508 0.3048)
			(end -0.508 0.3048)
			(stroke
				(width 0.1)
				(type default)
			)
			(layer "B.Fab")
		)
		(pad "1" smd rect
			(at 0.5334 0 180)
			(size 0.7112 0.6096)
			(layers "B.Cu" "B.Mask" "B.Paste")
			(net "XP3R3V_FPGA")
		)
		(pad "2" smd rect
			(at -0.5334 0 180)
			(size 0.7112 0.6096)
			(layers "B.Cu" "B.Mask" "B.Paste")
			(net "UNNAMED_5_PCA9546APWTSSOP16_I_2")
		)
		(zone
			(layer "B.Cu")
			(hatch none 0.5)
			(connect_pads
				(clearance 0)
			)
			(min_thickness 0.25)
			(keepout
				(tracks allowed)
				(vias not_allowed)
				(pads allowed)
				(copperpour not_allowed)
				(footprints allowed)
			)
			(placement
				(enabled no)
				(sheetname "")
			)
			(fill
				(thermal_gap 0.5)
				(thermal_bridge_width 0.5)
				(island_removal_mode 0)
			)
			(polygon
				(pts
					(xy 77.47 -85.3948) (xy 77.3176 -85.3948) (xy 77.3176 -84.7852) (xy 77.47 -84.7852)
				)
			)
		)
	)
	(footprint ""
		(layer "B.Cu")
		(at 36.9824 -105.2068)
		(property "Reference" "R32"
			(at -2.8194 -0.68453 0)
			(unlocked yes)
			(layer "B.SilkS")
			(effects
				(font
					(size 0.7874 0.5842)
					(thickness 0.1524)
				)
				(justify mirror)
			)
		)
		(property "Value" "VAL*"
			(at -0.02032 2.13233 0)
			(unlocked yes)
			(layer "B.Fab")
			(hide yes)
			(effects
				(font
					(size 0.7874 0.5842)
					(thickness 0.1524)
				)
				(justify mirror)
			)
		)
		(property "Tolerance" "TOL*"
			(at -0.044704 3.05435 0)
			(unlocked yes)
			(layer "Cmts.User")
			(hide yes)
			(effects
				(font
					(size 0.7874 0.5842)
					(thickness 0.1524)
				)
				(justify mirror)
			)
		)
		(property "User Part Number" "PARTNUM*"
			(at -0.02032 4.024884 0)
			(unlocked yes)
			(layer "Cmts.User")
			(hide yes)
			(effects
				(font
					(size 0.7874 0.5842)
					(thickness 0.1524)
				)
				(justify mirror)
			)
		)
		(property "Device Type" "RESISTOR-G155-03241-01,3.24KOHA"
			(at -0.008382 1.210564 0)
			(unlocked yes)
			(layer "B.Fab")
			(hide yes)
			(effects
				(font
					(size 0.7874 0.5842)
					(thickness 0.1524)
				)
				(justify mirror)
			)
		)
		(duplicate_pad_numbers_are_jumpers no)
		(fp_line
			(start -1.143 -0.5588)
			(end 1.143 -0.5588)
			(stroke
				(width 0.1)
				(type default)
			)
			(layer "B.SilkS")
		)
		(fp_line
			(start -1.143 0.5588)
			(end -1.143 -0.5588)
			(stroke
				(width 0.1)
				(type default)
			)
			(layer "B.SilkS")
		)
		(fp_line
			(start 1.143 -0.5588)
			(end 1.143 0.5588)
			(stroke
				(width 0.1)
				(type default)
			)
			(layer "B.SilkS")
		)
		(fp_line
			(start 1.143 0.5588)
			(end -1.143 0.5588)
			(stroke
				(width 0.1)
				(type default)
			)
			(layer "B.SilkS")
		)
		(fp_poly
			(pts
				(xy 1.143 0.5588) (xy -1.143 0.5588) (xy -1.143 -0.5588) (xy 1.143 -0.5588)
			)
			(stroke
				(width 0)
				(type default)
			)
			(fill no)
			(layer "B.CrtYd")
		)
		(fp_line
			(start -0.508 -0.3048)
			(end 0.508 -0.3048)
			(stroke
				(width 0.1)
				(type default)
			)
			(layer "B.Fab")
		)
		(fp_line
			(start -0.508 0.3048)
			(end -0.508 -0.3048)
			(stroke
				(width 0.1)
				(type default)
			)
			(layer "B.Fab")
		)
		(fp_line
			(start 0.508 -0.3048)
			(end 0.508 0.3048)
			(stroke
				(width 0.1)
				(type default)
			)
			(layer "B.Fab")
		)
		(fp_line
			(start 0.508 0.3048)
			(end -0.508 0.3048)
			(stroke
				(width 0.1)
				(type default)
			)
			(layer "B.Fab")
		)
		(pad "1" smd rect
			(at 0.5334 0 180)
			(size 0.7112 0.6096)
			(layers "B.Cu" "B.Mask" "B.Paste")
			(net "XP5R0V_FB_R_TO_AGND")
		)
		(pad "2" smd rect
			(at -0.5334 0 180)
			(size 0.7112 0.6096)
			(layers "B.Cu" "B.Mask" "B.Paste")
			(net "XP5R0V_AGND")
		)
		(zone
			(layer "B.Cu")
			(hatch none 0.5)
			(connect_pads
				(clearance 0)
			)
			(min_thickness 0.25)
			(keepout
				(tracks allowed)
				(vias not_allowed)
				(pads allowed)
				(copperpour not_allowed)
				(footprints allowed)
			)
			(placement
				(enabled no)
				(sheetname "")
			)
			(fill
				(thermal_gap 0.5)
				(thermal_bridge_width 0.5)
				(island_removal_mode 0)
			)
			(polygon
				(pts
					(xy 37.0586 -104.902) (xy 37.0586 -105.5116) (xy 36.9062 -105.5116) (xy 36.9062 -104.902)
				)
			)
		)
		(zone
			(layer "B.Cu")
			(hatch none 0.5)
			(connect_pads
				(clearance 0)
			)
			(min_thickness 0.25)
			(keepout
				(tracks not_allowed)
				(vias allowed)
				(pads allowed)
				(copperpour not_allowed)
				(footprints allowed)
			)
			(placement
				(enabled no)
				(sheetname "")
			)
			(fill
				(thermal_gap 0.5)
				(thermal_bridge_width 0.5)
				(island_removal_mode 0)
			)
			(polygon
				(pts
					(xy 37.0586 -104.902) (xy 37.0586 -105.5116) (xy 36.9062 -105.5116) (xy 36.9062 -104.902)
				)
			)
		)
	)
	(footprint ""
		(layer "B.Cu")
		(at 107.347004 -42.82313)
		(property "Reference" "C109"
			(at -41.180004 0.94488 0)
			(unlocked yes)
			(layer "B.SilkS")
			(effects
				(font
					(size 0.635 0.4064)
					(thickness 0.1524)
				)
				(justify mirror)
			)
		)
		(property "Value" "VAL*"
			(at 0 3.718306 0)
			(unlocked yes)
			(layer "B.Fab")
			(hide yes)
			(effects
				(font
					(size 0.7874 0.5842)
					(thickness 0.127)
				)
				(justify mirror)
			)
		)
		(property "Device Type" "CAPACITOR-G105-0B104-CK,0.1UF,A"
			(at 0 1.432306 0)
			(unlocked yes)
			(layer "B.Fab")
			(hide yes)
			(effects
				(font
					(size 0.7874 0.5842)
					(thickness 0.127)
				)
				(justify mirror)
			)
		)
		(property "User Part Number" "PARTNUM*"
			(at 0 2.575306 0)
			(unlocked yes)
			(layer "Cmts.User")
			(hide yes)
			(effects
				(font
					(size 0.7874 0.5842)
					(thickness 0.127)
				)
				(justify mirror)
			)
		)
		(property "Tolerance" "TOL*"
			(at 0 4.861306 0)
			(unlocked yes)
			(layer "Cmts.User")
			(hide yes)
			(effects
				(font
					(size 0.7874 0.5842)
					(thickness 0.127)
				)
				(justify mirror)
			)
		)
		(duplicate_pad_numbers_are_jumpers no)
		(fp_line
			(start -0.970026 -0.4699)
			(end -0.970026 0.4699)
			(stroke
				(width 0.1)
				(type default)
			)
			(layer "B.SilkS")
		)
		(fp_line
			(start -0.970026 0.4699)
			(end 0.970026 0.4699)
			(stroke
				(width 0.1)
				(type default)
			)
			(layer "B.SilkS")
		)
		(fp_line
			(start 0.970026 -0.4699)
			(end -0.970026 -0.4699)
			(stroke
				(width 0.1)
				(type default)
			)
			(layer "B.SilkS")
		)
		(fp_line
			(start 0.970026 0.4699)
			(end 0.970026 -0.4699)
			(stroke
				(width 0.1)
				(type default)
			)
			(layer "B.SilkS")
		)
		(fp_poly
			(pts
				(xy 0.970026 0.4699) (xy -0.970026 0.4699) (xy -0.970026 -0.4699) (xy 0.970026 -0.4699)
			)
			(stroke
				(width 0)
				(type default)
			)
			(fill no)
			(layer "B.CrtYd")
		)
		(fp_line
			(start -0.508 -0.3048)
			(end -0.508 0.3048)
			(stroke
				(width 0.1)
				(type default)
			)
			(layer "B.Fab")
		)
		(fp_line
			(start -0.508 0.3048)
			(end 0.508 0.3048)
			(stroke
				(width 0.1)
				(type default)
			)
			(layer "B.Fab")
		)
		(fp_line
			(start 0.508 -0.3048)
			(end -0.508 -0.3048)
			(stroke
				(width 0.1)
				(type default)
			)
			(layer "B.Fab")
		)
		(fp_line
			(start 0.508 0.3048)
			(end 0.508 -0.3048)
			(stroke
				(width 0.1)
				(type default)
			)
			(layer "B.Fab")
		)
		(pad "1" smd circle
			(at 0.500126 0 180)
			(size 0.635 0.635)
			(layers "B.Cu" "B.Mask" "B.Paste")
			(net "XP1R0V_FPGA_VCCINT")
		)
		(pad "2" smd circle
			(at -0.500126 0 180)
			(size 0.635 0.635)
			(layers "B.Cu" "B.Mask" "B.Paste")
			(net "SG")
		)
	)
	(footprint ""
		(layer "B.Cu")
		(at 113.847118 -40.323008 90)
		(property "Reference" "C152"
			(at -1.397508 -42.017188 270)
			(unlocked yes)
			(layer "B.SilkS")
			(effects
				(font
					(size 0.635 0.4064)
					(thickness 0.1524)
				)
				(justify mirror)
			)
		)
		(property "Value" "VAL*"
			(at 0 3.718306 90)
			(unlocked yes)
			(layer "B.Fab")
			(hide yes)
			(effects
				(font
					(size 0.7874 0.5842)
					(thickness 0.127)
				)
				(justify mirror)
			)
		)
		(property "Device Type" "CAPACITOR-G105-0B104-CK,0.1UF,A"
			(at 0 1.432306 90)
			(unlocked yes)
			(layer "B.Fab")
			(hide yes)
			(effects
				(font
					(size 0.7874 0.5842)
					(thickness 0.127)
				)
				(justify mirror)
			)
		)
		(property "User Part Number" "PARTNUM*"
			(at 0 2.575306 90)
			(unlocked yes)
			(layer "Cmts.User")
			(hide yes)
			(effects
				(font
					(size 0.7874 0.5842)
					(thickness 0.127)
				)
				(justify mirror)
			)
		)
		(property "Tolerance" "TOL*"
			(at 0 4.861306 90)
			(unlocked yes)
			(layer "Cmts.User")
			(hide yes)
			(effects
				(font
					(size 0.7874 0.5842)
					(thickness 0.127)
				)
				(justify mirror)
			)
		)
		(duplicate_pad_numbers_are_jumpers no)
		(fp_line
			(start 0.970026 -0.4699)
			(end -0.970026 -0.4699)
			(stroke
				(width 0.1)
				(type default)
			)
			(layer "B.SilkS")
		)
		(fp_line
			(start -0.970026 -0.4699)
			(end -0.970026 0.4699)
			(stroke
				(width 0.1)
				(type default)
			)
			(layer "B.SilkS")
		)
		(fp_line
			(start 0.970026 0.4699)
			(end 0.970026 -0.4699)
			(stroke
				(width 0.1)
				(type default)
			)
			(layer "B.SilkS")
		)
		(fp_line
			(start -0.970026 0.4699)
			(end 0.970026 0.4699)
			(stroke
				(width 0.1)
				(type default)
			)
			(layer "B.SilkS")
		)
		(fp_poly
			(pts
				(xy 0.970026 0.4699) (xy -0.970026 0.4699) (xy -0.970026 -0.4699) (xy 0.970026 -0.4699)
			)
			(stroke
				(width 0)
				(type default)
			)
			(fill no)
			(layer "B.CrtYd")
		)
		(fp_line
			(start 0.508 -0.3048)
			(end -0.508 -0.3048)
			(stroke
				(width 0.1)
				(type default)
			)
			(layer "B.Fab")
		)
		(fp_line
			(start -0.508 -0.3048)
			(end -0.508 0.3048)
			(stroke
				(width 0.1)
				(type default)
			)
			(layer "B.Fab")
		)
		(fp_line
			(start 0.508 0.3048)
			(end 0.508 -0.3048)
			(stroke
				(width 0.1)
				(type default)
			)
			(layer "B.Fab")
		)
		(fp_line
			(start -0.508 0.3048)
			(end 0.508 0.3048)
			(stroke
				(width 0.1)
				(type default)
			)
			(layer "B.Fab")
		)
		(pad "1" smd circle
			(at 0.500126 0 270)
			(size 0.635 0.635)
			(layers "B.Cu" "B.Mask" "B.Paste")
			(net "XP1R0V_FPGA_VCCINT")
		)
		(pad "2" smd circle
			(at -0.500126 0 270)
			(size 0.635 0.635)
			(layers "B.Cu" "B.Mask" "B.Paste")
			(net "SG")
		)
	)
	(footprint ""
		(layer "B.Cu")
		(at 22.4028 -90.7796 -90)
		(property "Reference" "R468"
			(at -2.5654 4.40817 270)
			(unlocked yes)
			(layer "B.SilkS")
			(effects
				(font
					(size 0.7874 0.5842)
					(thickness 0.1524)
				)
				(justify mirror)
			)
		)
		(property "Value" "VAL*"
			(at -0.02032 2.13233 270)
			(unlocked yes)
			(layer "B.Fab")
			(hide yes)
			(effects
				(font
					(size 0.7874 0.5842)
					(thickness 0.1524)
				)
				(justify mirror)
			)
		)
		(property "Tolerance" "TOL*"
			(at -0.044704 3.05435 270)
			(unlocked yes)
			(layer "Cmts.User")
			(hide yes)
			(effects
				(font
					(size 0.7874 0.5842)
					(thickness 0.1524)
				)
				(justify mirror)
			)
		)
		(property "User Part Number" "PARTNUM*"
			(at -0.02032 4.024884 270)
			(unlocked yes)
			(layer "Cmts.User")
			(hide yes)
			(effects
				(font
					(size 0.7874 0.5842)
					(thickness 0.1524)
				)
				(justify mirror)
			)
		)
		(property "Device Type" "RESISTOR-G155-133R0-01,33OHM,1%"
			(at -0.008382 1.210564 270)
			(unlocked yes)
			(layer "B.Fab")
			(hide yes)
			(effects
				(font
					(size 0.7874 0.5842)
					(thickness 0.1524)
				)
				(justify mirror)
			)
		)
		(duplicate_pad_numbers_are_jumpers no)
		(fp_line
			(start -1.143 0.5588)
			(end -1.143 -0.5588)
			(stroke
				(width 0.1)
				(type default)
			)
			(layer "B.SilkS")
		)
		(fp_line
			(start 1.143 0.5588)
			(end -1.143 0.5588)
			(stroke
				(width 0.1)
				(type default)
			)
			(layer "B.SilkS")
		)
		(fp_line
			(start -1.143 -0.5588)
			(end 1.143 -0.5588)
			(stroke
				(width 0.1)
				(type default)
			)
			(layer "B.SilkS")
		)
		(fp_line
			(start 1.143 -0.5588)
			(end 1.143 0.5588)
			(stroke
				(width 0.1)
				(type default)
			)
			(layer "B.SilkS")
		)
		(fp_poly
			(pts
				(xy 1.143 0.5588) (xy -1.143 0.5588) (xy -1.143 -0.5588) (xy 1.143 -0.5588)
			)
			(stroke
				(width 0)
				(type default)
			)
			(fill no)
			(layer "B.CrtYd")
		)
		(fp_line
			(start -0.508 0.3048)
			(end -0.508 -0.3048)
			(stroke
				(width 0.1)
				(type default)
			)
			(layer "B.Fab")
		)
		(fp_line
			(start 0.508 0.3048)
			(end -0.508 0.3048)
			(stroke
				(width 0.1)
				(type default)
			)
			(layer "B.Fab")
		)
		(fp_line
			(start -0.508 -0.3048)
			(end 0.508 -0.3048)
			(stroke
				(width 0.1)
				(type default)
			)
			(layer "B.Fab")
		)
		(fp_line
			(start 0.508 -0.3048)
			(end 0.508 0.3048)
			(stroke
				(width 0.1)
				(type default)
			)
			(layer "B.Fab")
		)
		(pad "1" smd rect
			(at 0.5334 0 90)
			(size 0.7112 0.6096)
			(layers "B.Cu" "B.Mask" "B.Paste")
			(net "R_FT4232_TDI")
		)
		(pad "2" smd rect
			(at -0.5334 0 90)
			(size 0.7112 0.6096)
			(layers "B.Cu" "B.Mask" "B.Paste")
			(net "FT4232_TDI_MOSI")
		)
		(zone
			(layer "B.Cu")
			(hatch none 0.5)
			(connect_pads
				(clearance 0)
			)
			(min_thickness 0.25)
			(keepout
				(tracks allowed)
				(vias not_allowed)
				(pads allowed)
				(copperpour not_allowed)
				(footprints allowed)
			)
			(placement
				(enabled no)
				(sheetname "")
			)
			(fill
				(thermal_gap 0.5)
				(thermal_bridge_width 0.5)
				(island_removal_mode 0)
			)
			(polygon
				(pts
					(xy 22.098 -90.7034) (xy 22.7076 -90.7034) (xy 22.7076 -90.8558) (xy 22.098 -90.8558)
				)
			)
		)
		(zone
			(layer "B.Cu")
			(hatch none 0.5)
			(connect_pads
				(clearance 0)
			)
			(min_thickness 0.25)
			(keepout
				(tracks not_allowed)
				(vias allowed)
				(pads allowed)
				(copperpour not_allowed)
				(footprints allowed)
			)
			(placement
				(enabled no)
				(sheetname "")
			)
			(fill
				(thermal_gap 0.5)
				(thermal_bridge_width 0.5)
				(island_removal_mode 0)
			)
			(polygon
				(pts
					(xy 22.098 -90.7034) (xy 22.7076 -90.7034) (xy 22.7076 -90.8558) (xy 22.098 -90.8558)
				)
			)
		)
	)
	(footprint ""
		(layer "B.Cu")
		(at 141.097 -107.696 90)
		(property "Reference" "R258"
			(at -0.762 1.03505 270)
			(unlocked yes)
			(layer "B.SilkS")
			(effects
				(font
					(size 0.635 0.4064)
					(thickness 0.1524)
				)
				(justify mirror)
			)
		)
		(property "Value" "VAL*"
			(at -0.02032 2.13233 90)
			(unlocked yes)
			(layer "B.Fab")
			(hide yes)
			(effects
				(font
					(size 0.7874 0.5842)
					(thickness 0.1524)
				)
				(justify mirror)
			)
		)
		(property "Device Type" "RESISTOR-G155-13300-01,330OHM,A"
			(at -0.008382 1.210564 90)
			(unlocked yes)
			(layer "B.Fab")
			(hide yes)
			(effects
				(font
					(size 0.7874 0.5842)
					(thickness 0.1524)
				)
				(justify mirror)
			)
		)
		(property "User Part Number" "PARTNUM*"
			(at -0.02032 4.024884 90)
			(unlocked yes)
			(layer "Cmts.User")
			(hide yes)
			(effects
				(font
					(size 0.7874 0.5842)
					(thickness 0.1524)
				)
				(justify mirror)
			)
		)
		(property "Tolerance" "TOL*"
			(at -0.044704 3.05435 90)
			(unlocked yes)
			(layer "Cmts.User")
			(hide yes)
			(effects
				(font
					(size 0.7874 0.5842)
					(thickness 0.1524)
				)
				(justify mirror)
			)
		)
		(duplicate_pad_numbers_are_jumpers no)
		(fp_line
			(start 1.143 -0.5588)
			(end 1.143 0.5588)
			(stroke
				(width 0.1)
				(type default)
			)
			(layer "B.SilkS")
		)
		(fp_line
			(start -1.143 -0.5588)
			(end 1.143 -0.5588)
			(stroke
				(width 0.1)
				(type default)
			)
			(layer "B.SilkS")
		)
		(fp_line
			(start 1.143 0.5588)
			(end -1.143 0.5588)
			(stroke
				(width 0.1)
				(type default)
			)
			(layer "B.SilkS")
		)
		(fp_line
			(start -1.143 0.5588)
			(end -1.143 -0.5588)
			(stroke
				(width 0.1)
				(type default)
			)
			(layer "B.SilkS")
		)
		(fp_rect
			(start -1.143 -0.5588)
			(end 1.143 0.5588)
			(stroke
				(width 0)
				(type default)
			)
			(fill no)
			(layer "B.CrtYd")
		)
		(fp_line
			(start 0.508 -0.3048)
			(end 0.508 0.3048)
			(stroke
				(width 0.1)
				(type default)
			)
			(layer "B.Fab")
		)
		(fp_line
			(start -0.508 -0.3048)
			(end 0.508 -0.3048)
			(stroke
				(width 0.1)
				(type default)
			)
			(layer "B.Fab")
		)
		(fp_line
			(start 0.508 0.3048)
			(end -0.508 0.3048)
			(stroke
				(width 0.1)
				(type default)
			)
			(layer "B.Fab")
		)
		(fp_line
			(start -0.508 0.3048)
			(end -0.508 -0.3048)
			(stroke
				(width 0.1)
				(type default)
			)
			(layer "B.Fab")
		)
		(pad "1" smd rect
			(at 0.5334 0 270)
			(size 0.7112 0.6096)
			(layers "B.Cu" "B.Mask" "B.Paste")
			(net "UNNAMED_14_OPTICAL_I11_A")
		)
		(pad "2" smd rect
			(at -0.5334 0 270)
			(size 0.7112 0.6096)
			(layers "B.Cu" "B.Mask" "B.Paste")
			(net "XP3R3V_FPGA")
		)
		(zone
			(layer "B.Cu")
			(hatch none 0.5)
			(connect_pads
				(clearance 0)
			)
			(min_thickness 0.25)
			(keepout
				(tracks allowed)
				(vias not_allowed)
				(pads allowed)
				(copperpour not_allowed)
				(footprints allowed)
			)
			(placement
				(enabled no)
				(sheetname "")
			)
			(fill
				(thermal_gap 0.5)
				(thermal_bridge_width 0.5)
				(island_removal_mode 0)
			)
			(polygon
				(pts
					(xy 140.7922 -107.6198) (xy 141.4018 -107.6198) (xy 141.4018 -107.7722) (xy 140.7922 -107.7722)
				)
			)
		)
	)
	(footprint ""
		(layer "B.Cu")
		(at 82.931 -103.378)
		(property "Reference" "C56"
			(at -2.413 0.03937 0)
			(unlocked yes)
			(layer "B.SilkS")
			(effects
				(font
					(size 0.7874 0.5842)
					(thickness 0.1524)
				)
				(justify mirror)
			)
		)
		(property "Value" "VAL*"
			(at -0.0762 2.067306 0)
			(unlocked yes)
			(layer "B.Fab")
			(hide yes)
			(effects
				(font
					(size 0.7874 0.5842)
					(thickness 0.1524)
				)
				(justify mirror)
			)
		)
		(property "Tolerance" "TOL*"
			(at -0.0762 3.032506 0)
			(unlocked yes)
			(layer "Cmts.User")
			(hide yes)
			(effects
				(font
					(size 0.7874 0.5842)
					(thickness 0.1524)
				)
				(justify mirror)
			)
		)
		(property "User Part Number" "PARTNUM*"
			(at -0.1016 4.023106 0)
			(unlocked yes)
			(layer "Cmts.User")
			(hide yes)
			(effects
				(font
					(size 0.7874 0.5842)
					(thickness 0.1524)
				)
				(justify mirror)
			)
		)
		(property "Device Type" "CAPACITOR-G105-0B104-EK,0.1UF,A"
			(at -0.0508 1.127506 0)
			(unlocked yes)
			(layer "B.Fab")
			(hide yes)
			(effects
				(font
					(size 0.7874 0.5842)
					(thickness 0.1524)
				)
				(justify mirror)
			)
		)
		(duplicate_pad_numbers_are_jumpers no)
		(fp_line
			(start -1.143 -0.5588)
			(end 1.143 -0.5588)
			(stroke
				(width 0.1)
				(type default)
			)
			(layer "B.SilkS")
		)
		(fp_line
			(start -1.143 0.5588)
			(end -1.143 -0.5588)
			(stroke
				(width 0.1)
				(type default)
			)
			(layer "B.SilkS")
		)
		(fp_line
			(start 1.143 -0.5588)
			(end 1.143 0.5588)
			(stroke
				(width 0.1)
				(type default)
			)
			(layer "B.SilkS")
		)
		(fp_line
			(start 1.143 0.5588)
			(end -1.143 0.5588)
			(stroke
				(width 0.1)
				(type default)
			)
			(layer "B.SilkS")
		)
		(fp_rect
			(start 1.143 0.5588)
			(end -1.143 -0.5588)
			(stroke
				(width 0)
				(type default)
			)
			(fill no)
			(layer "B.CrtYd")
		)
		(fp_line
			(start -0.508 -0.3048)
			(end 0.508 -0.3048)
			(stroke
				(width 0.1)
				(type default)
			)
			(layer "B.Fab")
		)
		(fp_line
			(start -0.508 0.3048)
			(end -0.508 -0.3048)
			(stroke
				(width 0.1)
				(type default)
			)
			(layer "B.Fab")
		)
		(fp_line
			(start 0.508 -0.3048)
			(end 0.508 0.3048)
			(stroke
				(width 0.1)
				(type default)
			)
			(layer "B.Fab")
		)
		(fp_line
			(start 0.508 0.3048)
			(end -0.508 0.3048)
			(stroke
				(width 0.1)
				(type default)
			)
			(layer "B.Fab")
		)
		(pad "1" smd rect
			(at 0.5334 0 180)
			(size 0.7112 0.6096)
			(layers "B.Cu" "B.Mask" "B.Paste")
			(net "UNNAMED_517_CAPACITOR_I27_1")
		)
		(pad "2" smd rect
			(at -0.5334 0 180)
			(size 0.7112 0.6096)
			(layers "B.Cu" "B.Mask" "B.Paste")
			(net "XP3R3V_SW")
		)
		(zone
			(layer "B.Cu")
			(hatch none 0.5)
			(connect_pads
				(clearance 0)
			)
			(min_thickness 0.25)
			(keepout
				(tracks allowed)
				(vias not_allowed)
				(pads allowed)
				(copperpour not_allowed)
				(footprints allowed)
			)
			(placement
				(enabled no)
				(sheetname "")
			)
			(fill
				(thermal_gap 0.5)
				(thermal_bridge_width 0.5)
				(island_removal_mode 0)
			)
			(polygon
				(pts
					(xy 83.0072 -103.0732) (xy 83.0072 -103.6828) (xy 82.8548 -103.6828) (xy 82.8548 -103.0732)
				)
			)
		)
	)
	(footprint ""
		(layer "B.Cu")
		(at 32.512 -79.121 90)
		(property "Reference" "R131"
			(at 0.254 1.10363 270)
			(unlocked yes)
			(layer "B.SilkS")
			(effects
				(font
					(size 0.7874 0.5842)
					(thickness 0.1524)
				)
				(justify mirror)
			)
		)
		(property "Value" "VAL*"
			(at -0.02032 2.13233 90)
			(unlocked yes)
			(layer "B.Fab")
			(hide yes)
			(effects
				(font
					(size 0.7874 0.5842)
					(thickness 0.1524)
				)
				(justify mirror)
			)
		)
		(property "Tolerance" "TOL*"
			(at -0.044704 3.05435 90)
			(unlocked yes)
			(layer "Cmts.User")
			(hide yes)
			(effects
				(font
					(size 0.7874 0.5842)
					(thickness 0.1524)
				)
				(justify mirror)
			)
		)
		(property "User Part Number" "PARTNUM*"
			(at -0.02032 4.024884 90)
			(unlocked yes)
			(layer "Cmts.User")
			(hide yes)
			(effects
				(font
					(size 0.7874 0.5842)
					(thickness 0.1524)
				)
				(justify mirror)
			)
		)
		(property "Device Type" "RESISTOR-G155-11000-01,100OHM,A"
			(at -0.008382 1.210564 90)
			(unlocked yes)
			(layer "B.Fab")
			(hide yes)
			(effects
				(font
					(size 0.7874 0.5842)
					(thickness 0.1524)
				)
				(justify mirror)
			)
		)
		(duplicate_pad_numbers_are_jumpers no)
		(fp_line
			(start 1.143 -0.5588)
			(end 1.143 0.5588)
			(stroke
				(width 0.1)
				(type default)
			)
			(layer "B.SilkS")
		)
		(fp_line
			(start -1.143 -0.5588)
			(end 1.143 -0.5588)
			(stroke
				(width 0.1)
				(type default)
			)
			(layer "B.SilkS")
		)
		(fp_line
			(start 1.143 0.5588)
			(end -1.143 0.5588)
			(stroke
				(width 0.1)
				(type default)
			)
			(layer "B.SilkS")
		)
		(fp_line
			(start -1.143 0.5588)
			(end -1.143 -0.5588)
			(stroke
				(width 0.1)
				(type default)
			)
			(layer "B.SilkS")
		)
		(fp_rect
			(start 1.143 -0.5588)
			(end -1.143 0.5588)
			(stroke
				(width 0)
				(type default)
			)
			(fill no)
			(layer "B.CrtYd")
		)
		(fp_line
			(start 0.508 -0.3048)
			(end 0.508 0.3048)
			(stroke
				(width 0.1)
				(type default)
			)
			(layer "B.Fab")
		)
		(fp_line
			(start -0.508 -0.3048)
			(end 0.508 -0.3048)
			(stroke
				(width 0.1)
				(type default)
			)
			(layer "B.Fab")
		)
		(fp_line
			(start 0.508 0.3048)
			(end -0.508 0.3048)
			(stroke
				(width 0.1)
				(type default)
			)
			(layer "B.Fab")
		)
		(fp_line
			(start -0.508 0.3048)
			(end -0.508 -0.3048)
			(stroke
				(width 0.1)
				(type default)
			)
			(layer "B.Fab")
		)
		(pad "1" smd rect
			(at 0.5334 0 270)
			(size 0.7112 0.6096)
			(layers "B.Cu" "B.Mask" "B.Paste")
			(net "R_FT4232_CHD_TX")
		)
		(pad "2" smd rect
			(at -0.5334 0 270)
			(size 0.7112 0.6096)
			(layers "B.Cu" "B.Mask" "B.Paste")
			(net "FT4232_CHD_TX")
		)
		(zone
			(layer "B.Cu")
			(hatch none 0.5)
			(connect_pads
				(clearance 0)
			)
			(min_thickness 0.25)
			(keepout
				(tracks allowed)
				(vias not_allowed)
				(pads allowed)
				(copperpour not_allowed)
				(footprints allowed)
			)
			(placement
				(enabled no)
				(sheetname "")
			)
			(fill
				(thermal_gap 0.5)
				(thermal_bridge_width 0.5)
				(island_removal_mode 0)
			)
			(polygon
				(pts
					(xy 32.2072 -79.1972) (xy 32.2072 -79.0448) (xy 32.8168 -79.0448) (xy 32.8168 -79.1972)
				)
			)
		)
	)
	(footprint ""
		(layer "B.Cu")
		(at 135.2042 -106.172254 90)
		(property "Reference" "R208"
			(at -7.747254 0.90043 270)
			(unlocked yes)
			(layer "B.SilkS")
			(effects
				(font
					(size 0.7874 0.5842)
					(thickness 0.1524)
				)
				(justify mirror)
			)
		)
		(property "Value" "VAL*"
			(at -0.02032 2.13233 90)
			(unlocked yes)
			(layer "B.Fab")
			(hide yes)
			(effects
				(font
					(size 0.7874 0.5842)
					(thickness 0.1524)
				)
				(justify mirror)
			)
		)
		(property "Device Type" "RESISTOR-G155-13300-01,330OHM,A"
			(at -0.008382 1.210564 90)
			(unlocked yes)
			(layer "B.Fab")
			(hide yes)
			(effects
				(font
					(size 0.7874 0.5842)
					(thickness 0.1524)
				)
				(justify mirror)
			)
		)
		(property "User Part Number" "PARTNUM*"
			(at -0.02032 4.024884 90)
			(unlocked yes)
			(layer "Cmts.User")
			(hide yes)
			(effects
				(font
					(size 0.7874 0.5842)
					(thickness 0.1524)
				)
				(justify mirror)
			)
		)
		(property "Tolerance" "TOL*"
			(at -0.044704 3.05435 90)
			(unlocked yes)
			(layer "Cmts.User")
			(hide yes)
			(effects
				(font
					(size 0.7874 0.5842)
					(thickness 0.1524)
				)
				(justify mirror)
			)
		)
		(duplicate_pad_numbers_are_jumpers no)
		(fp_line
			(start 1.143 -0.5588)
			(end 1.143 0.5588)
			(stroke
				(width 0.1)
				(type default)
			)
			(layer "B.SilkS")
		)
		(fp_line
			(start -1.143 -0.5588)
			(end 1.143 -0.5588)
			(stroke
				(width 0.1)
				(type default)
			)
			(layer "B.SilkS")
		)
		(fp_line
			(start 1.143 0.5588)
			(end -1.143 0.5588)
			(stroke
				(width 0.1)
				(type default)
			)
			(layer "B.SilkS")
		)
		(fp_line
			(start -1.143 0.5588)
			(end -1.143 -0.5588)
			(stroke
				(width 0.1)
				(type default)
			)
			(layer "B.SilkS")
		)
		(fp_rect
			(start -1.143 -0.5588)
			(end 1.143 0.5588)
			(stroke
				(width 0)
				(type default)
			)
			(fill no)
			(layer "B.CrtYd")
		)
		(fp_line
			(start 0.508 -0.3048)
			(end 0.508 0.3048)
			(stroke
				(width 0.1)
				(type default)
			)
			(layer "B.Fab")
		)
		(fp_line
			(start -0.508 -0.3048)
			(end 0.508 -0.3048)
			(stroke
				(width 0.1)
				(type default)
			)
			(layer "B.Fab")
		)
		(fp_line
			(start 0.508 0.3048)
			(end -0.508 0.3048)
			(stroke
				(width 0.1)
				(type default)
			)
			(layer "B.Fab")
		)
		(fp_line
			(start -0.508 0.3048)
			(end -0.508 -0.3048)
			(stroke
				(width 0.1)
				(type default)
			)
			(layer "B.Fab")
		)
		(pad "1" smd rect
			(at 0.5334 0 270)
			(size 0.7112 0.6096)
			(layers "B.Cu" "B.Mask" "B.Paste")
			(net "UNNAMED_14_OPTICAL_I292_A")
		)
		(pad "2" smd rect
			(at -0.5334 0 270)
			(size 0.7112 0.6096)
			(layers "B.Cu" "B.Mask" "B.Paste")
			(net "FPGA_DONE")
		)
		(zone
			(layer "B.Cu")
			(hatch none 0.5)
			(connect_pads
				(clearance 0)
			)
			(min_thickness 0.25)
			(keepout
				(tracks allowed)
				(vias not_allowed)
				(pads allowed)
				(copperpour not_allowed)
				(footprints allowed)
			)
			(placement
				(enabled no)
				(sheetname "")
			)
			(fill
				(thermal_gap 0.5)
				(thermal_bridge_width 0.5)
				(island_removal_mode 0)
			)
			(polygon
				(pts
					(xy 134.8994 -106.096054) (xy 135.509 -106.096054) (xy 135.509 -106.248454) (xy 134.8994 -106.248454)
				)
			)
		)
	)
	(footprint ""
		(layer "B.Cu")
		(at 104.347264 -39.823136 180)
		(property "Reference" "C118"
			(at 41.400984 -1.251966 0)
			(unlocked yes)
			(layer "B.SilkS")
			(effects
				(font
					(size 0.635 0.4064)
					(thickness 0.1524)
				)
				(justify mirror)
			)
		)
		(property "Value" "VAL*"
			(at 0 3.718306 180)
			(unlocked yes)
			(layer "B.Fab")
			(hide yes)
			(effects
				(font
					(size 0.7874 0.5842)
					(thickness 0.127)
				)
				(justify mirror)
			)
		)
		(property "Tolerance" "TOL*"
			(at 0 4.861306 180)
			(unlocked yes)
			(layer "Cmts.User")
			(hide yes)
			(effects
				(font
					(size 0.7874 0.5842)
					(thickness 0.127)
				)
				(justify mirror)
			)
		)
		(property "User Part Number" "PARTNUM*"
			(at 0 2.575306 180)
			(unlocked yes)
			(layer "Cmts.User")
			(hide yes)
			(effects
				(font
					(size 0.7874 0.5842)
					(thickness 0.127)
				)
				(justify mirror)
			)
		)
		(property "Device Type" "CAPACITOR-G105-0B104-CK,0.1UF,A"
			(at 0 1.432306 180)
			(unlocked yes)
			(layer "B.Fab")
			(hide yes)
			(effects
				(font
					(size 0.7874 0.5842)
					(thickness 0.127)
				)
				(justify mirror)
			)
		)
		(duplicate_pad_numbers_are_jumpers no)
		(fp_line
			(start 0.970026 0.4699)
			(end 0.970026 -0.4699)
			(stroke
				(width 0.1)
				(type default)
			)
			(layer "B.SilkS")
		)
		(fp_line
			(start 0.970026 -0.4699)
			(end -0.970026 -0.4699)
			(stroke
				(width 0.1)
				(type default)
			)
			(layer "B.SilkS")
		)
		(fp_line
			(start -0.970026 0.4699)
			(end 0.970026 0.4699)
			(stroke
				(width 0.1)
				(type default)
			)
			(layer "B.SilkS")
		)
		(fp_line
			(start -0.970026 -0.4699)
			(end -0.970026 0.4699)
			(stroke
				(width 0.1)
				(type default)
			)
			(layer "B.SilkS")
		)
		(fp_poly
			(pts
				(xy 0.970026 0.4699) (xy -0.970026 0.4699) (xy -0.970026 -0.4699) (xy 0.970026 -0.4699)
			)
			(stroke
				(width 0)
				(type default)
			)
			(fill no)
			(layer "B.CrtYd")
		)
		(fp_line
			(start 0.508 0.3048)
			(end 0.508 -0.3048)
			(stroke
				(width 0.1)
				(type default)
			)
			(layer "B.Fab")
		)
		(fp_line
			(start 0.508 -0.3048)
			(end -0.508 -0.3048)
			(stroke
				(width 0.1)
				(type default)
			)
			(layer "B.Fab")
		)
		(fp_line
			(start -0.508 0.3048)
			(end 0.508 0.3048)
			(stroke
				(width 0.1)
				(type default)
			)
			(layer "B.Fab")
		)
		(fp_line
			(start -0.508 -0.3048)
			(end -0.508 0.3048)
			(stroke
				(width 0.1)
				(type default)
			)
			(layer "B.Fab")
		)
		(pad "1" smd circle
			(at 0.500126 0)
			(size 0.635 0.635)
			(layers "B.Cu" "B.Mask" "B.Paste")
			(net "XP1R0V_FPGA_MGTAVCC")
		)
		(pad "2" smd circle
			(at -0.500126 0)
			(size 0.635 0.635)
			(layers "B.Cu" "B.Mask" "B.Paste")
			(net "SG")
		)
	)
	(footprint ""
		(layer "B.Cu")
		(at 71.13397 -15.367 -90)
		(property "Reference" "C28"
			(at 2.286 0.17272 270)
			(unlocked yes)
			(layer "B.SilkS")
			(effects
				(font
					(size 0.635 0.4064)
					(thickness 0.1524)
				)
				(justify mirror)
			)
		)
		(property "Value" "VAL*"
			(at -0.0762 2.067306 270)
			(unlocked yes)
			(layer "B.Fab")
			(hide yes)
			(effects
				(font
					(size 0.7874 0.5842)
					(thickness 0.1524)
				)
				(justify mirror)
			)
		)
		(property "Tolerance" "TOL*"
			(at -0.0762 3.032506 270)
			(unlocked yes)
			(layer "Cmts.User")
			(hide yes)
			(effects
				(font
					(size 0.7874 0.5842)
					(thickness 0.1524)
				)
				(justify mirror)
			)
		)
		(property "User Part Number" "PARTNUM*"
			(at -0.1016 4.023106 270)
			(unlocked yes)
			(layer "Cmts.User")
			(hide yes)
			(effects
				(font
					(size 0.7874 0.5842)
					(thickness 0.1524)
				)
				(justify mirror)
			)
		)
		(property "Device Type" "CAPACITOR-G105-0B104-CK,0.1UF,A"
			(at -0.0508 1.127506 270)
			(unlocked yes)
			(layer "B.Fab")
			(hide yes)
			(effects
				(font
					(size 0.7874 0.5842)
					(thickness 0.1524)
				)
				(justify mirror)
			)
		)
		(duplicate_pad_numbers_are_jumpers no)
		(fp_line
			(start -1.143 0.5588)
			(end -1.143 -0.5588)
			(stroke
				(width 0.1)
				(type default)
			)
			(layer "B.SilkS")
		)
		(fp_line
			(start 1.143 0.5588)
			(end -1.143 0.5588)
			(stroke
				(width 0.1)
				(type default)
			)
			(layer "B.SilkS")
		)
		(fp_line
			(start -1.143 -0.5588)
			(end 1.143 -0.5588)
			(stroke
				(width 0.1)
				(type default)
			)
			(layer "B.SilkS")
		)
		(fp_line
			(start 1.143 -0.5588)
			(end 1.143 0.5588)
			(stroke
				(width 0.1)
				(type default)
			)
			(layer "B.SilkS")
		)
		(fp_rect
			(start 1.143 0.5588)
			(end -1.143 -0.5588)
			(stroke
				(width 0)
				(type default)
			)
			(fill no)
			(layer "B.CrtYd")
		)
		(fp_line
			(start -0.508 0.3048)
			(end -0.508 -0.3048)
			(stroke
				(width 0.1)
				(type default)
			)
			(layer "B.Fab")
		)
		(fp_line
			(start 0.508 0.3048)
			(end -0.508 0.3048)
			(stroke
				(width 0.1)
				(type default)
			)
			(layer "B.Fab")
		)
		(fp_line
			(start -0.508 -0.3048)
			(end 0.508 -0.3048)
			(stroke
				(width 0.1)
				(type default)
			)
			(layer "B.Fab")
		)
		(fp_line
			(start 0.508 -0.3048)
			(end 0.508 0.3048)
			(stroke
				(width 0.1)
				(type default)
			)
			(layer "B.Fab")
		)
		(pad "1" smd rect
			(at 0.5334 0 90)
			(size 0.7112 0.6096)
			(layers "B.Cu" "B.Mask" "B.Paste")
			(net "C_CPU_RX_PCIE_MGT2_TXP")
		)
		(pad "2" smd rect
			(at -0.5334 0 90)
			(size 0.7112 0.6096)
			(layers "B.Cu" "B.Mask" "B.Paste")
			(net "CPU_RX_PCIE_MGT2_TXP")
		)
		(zone
			(layer "B.Cu")
			(hatch none 0.5)
			(connect_pads
				(clearance 0)
			)
			(min_thickness 0.25)
			(keepout
				(tracks allowed)
				(vias not_allowed)
				(pads allowed)
				(copperpour not_allowed)
				(footprints allowed)
			)
			(placement
				(enabled no)
				(sheetname "")
			)
			(fill
				(thermal_gap 0.5)
				(thermal_bridge_width 0.5)
				(island_removal_mode 0)
			)
			(polygon
				(pts
					(xy 70.82917 -15.2908) (xy 71.43877 -15.2908) (xy 71.43877 -15.4432) (xy 70.82917 -15.4432)
				)
			)
		)
	)
	(footprint ""
		(layer "B.Cu")
		(at 87.376 -73.279 90)
		(property "Reference" "R330"
			(at -3.556 -0.16637 270)
			(unlocked yes)
			(layer "B.SilkS")
			(effects
				(font
					(size 0.7874 0.5842)
					(thickness 0.1524)
				)
				(justify mirror)
			)
		)
		(property "Value" "VAL*"
			(at -0.02032 2.13233 90)
			(unlocked yes)
			(layer "B.Fab")
			(hide yes)
			(effects
				(font
					(size 0.7874 0.5842)
					(thickness 0.1524)
				)
				(justify mirror)
			)
		)
		(property "Device Type" "RESISTOR-G155-133R0-01,33OHM,1%"
			(at -0.008382 1.210564 90)
			(unlocked yes)
			(layer "B.Fab")
			(hide yes)
			(effects
				(font
					(size 0.7874 0.5842)
					(thickness 0.1524)
				)
				(justify mirror)
			)
		)
		(property "User Part Number" "PARTNUM*"
			(at -0.02032 4.024884 90)
			(unlocked yes)
			(layer "Cmts.User")
			(hide yes)
			(effects
				(font
					(size 0.7874 0.5842)
					(thickness 0.1524)
				)
				(justify mirror)
			)
		)
		(property "Tolerance" "TOL*"
			(at -0.044704 3.05435 90)
			(unlocked yes)
			(layer "Cmts.User")
			(hide yes)
			(effects
				(font
					(size 0.7874 0.5842)
					(thickness 0.1524)
				)
				(justify mirror)
			)
		)
		(duplicate_pad_numbers_are_jumpers no)
		(fp_line
			(start 1.143 -0.5588)
			(end 1.143 0.5588)
			(stroke
				(width 0.1)
				(type default)
			)
			(layer "B.SilkS")
		)
		(fp_line
			(start -1.143 -0.5588)
			(end 1.143 -0.5588)
			(stroke
				(width 0.1)
				(type default)
			)
			(layer "B.SilkS")
		)
		(fp_line
			(start 1.143 0.5588)
			(end -1.143 0.5588)
			(stroke
				(width 0.1)
				(type default)
			)
			(layer "B.SilkS")
		)
		(fp_line
			(start -1.143 0.5588)
			(end -1.143 -0.5588)
			(stroke
				(width 0.1)
				(type default)
			)
			(layer "B.SilkS")
		)
		(fp_rect
			(start 1.143 -0.5588)
			(end -1.143 0.5588)
			(stroke
				(width 0)
				(type default)
			)
			(fill no)
			(layer "B.CrtYd")
		)
		(fp_line
			(start 0.508 -0.3048)
			(end 0.508 0.3048)
			(stroke
				(width 0.1)
				(type default)
			)
			(layer "B.Fab")
		)
		(fp_line
			(start -0.508 -0.3048)
			(end 0.508 -0.3048)
			(stroke
				(width 0.1)
				(type default)
			)
			(layer "B.Fab")
		)
		(fp_line
			(start 0.508 0.3048)
			(end -0.508 0.3048)
			(stroke
				(width 0.1)
				(type default)
			)
			(layer "B.Fab")
		)
		(fp_line
			(start -0.508 0.3048)
			(end -0.508 -0.3048)
			(stroke
				(width 0.1)
				(type default)
			)
			(layer "B.Fab")
		)
		(pad "1" smd rect
			(at 0.5334 0 270)
			(size 0.7112 0.6096)
			(layers "B.Cu" "B.Mask" "B.Paste")
			(net "R_BNO080_EVN_SDA")
		)
		(pad "2" smd rect
			(at -0.5334 0 270)
			(size 0.7112 0.6096)
			(layers "B.Cu" "B.Mask" "B.Paste")
			(net "BNO080_EVN_SDA")
		)
		(zone
			(layer "B.Cu")
			(hatch none 0.5)
			(connect_pads
				(clearance 0)
			)
			(min_thickness 0.25)
			(keepout
				(tracks allowed)
				(vias not_allowed)
				(pads allowed)
				(copperpour not_allowed)
				(footprints allowed)
			)
			(placement
				(enabled no)
				(sheetname "")
			)
			(fill
				(thermal_gap 0.5)
				(thermal_bridge_width 0.5)
				(island_removal_mode 0)
			)
			(polygon
				(pts
					(xy 87.0712 -73.3552) (xy 87.0712 -73.2028) (xy 87.6808 -73.2028) (xy 87.6808 -73.3552)
				)
			)
		)
	)
	(footprint ""
		(layer "B.Cu")
		(at 114.34699 -52.82311)
		(property "Reference" "C134"
			(at -0.04699 -1.12014 0)
			(unlocked yes)
			(layer "B.SilkS")
			(effects
				(font
					(size 0.635 0.4064)
					(thickness 0.1524)
				)
				(justify mirror)
			)
		)
		(property "Value" "VAL*"
			(at 0 3.718306 0)
			(unlocked yes)
			(layer "B.Fab")
			(hide yes)
			(effects
				(font
					(size 0.7874 0.5842)
					(thickness 0.127)
				)
				(justify mirror)
			)
		)
		(property "Tolerance" "TOL*"
			(at 0 4.861306 0)
			(unlocked yes)
			(layer "Cmts.User")
			(hide yes)
			(effects
				(font
					(size 0.7874 0.5842)
					(thickness 0.127)
				)
				(justify mirror)
			)
		)
		(property "User Part Number" "PARTNUM*"
			(at 0 2.575306 0)
			(unlocked yes)
			(layer "Cmts.User")
			(hide yes)
			(effects
				(font
					(size 0.7874 0.5842)
					(thickness 0.127)
				)
				(justify mirror)
			)
		)
		(property "Device Type" "CAPACITOR-G105-0B104-CK,0.1UF,A"
			(at 0 1.432306 0)
			(unlocked yes)
			(layer "B.Fab")
			(hide yes)
			(effects
				(font
					(size 0.7874 0.5842)
					(thickness 0.127)
				)
				(justify mirror)
			)
		)
		(duplicate_pad_numbers_are_jumpers no)
		(fp_line
			(start -0.970026 -0.4699)
			(end -0.970026 0.4699)
			(stroke
				(width 0.1)
				(type default)
			)
			(layer "B.SilkS")
		)
		(fp_line
			(start -0.970026 0.4699)
			(end 0.970026 0.4699)
			(stroke
				(width 0.1)
				(type default)
			)
			(layer "B.SilkS")
		)
		(fp_line
			(start 0.970026 -0.4699)
			(end -0.970026 -0.4699)
			(stroke
				(width 0.1)
				(type default)
			)
			(layer "B.SilkS")
		)
		(fp_line
			(start 0.970026 0.4699)
			(end 0.970026 -0.4699)
			(stroke
				(width 0.1)
				(type default)
			)
			(layer "B.SilkS")
		)
		(fp_poly
			(pts
				(xy 0.970026 0.4699) (xy -0.970026 0.4699) (xy -0.970026 -0.4699) (xy 0.970026 -0.4699)
			)
			(stroke
				(width 0)
				(type default)
			)
			(fill no)
			(layer "B.CrtYd")
		)
		(fp_line
			(start -0.508 -0.3048)
			(end -0.508 0.3048)
			(stroke
				(width 0.1)
				(type default)
			)
			(layer "B.Fab")
		)
		(fp_line
			(start -0.508 0.3048)
			(end 0.508 0.3048)
			(stroke
				(width 0.1)
				(type default)
			)
			(layer "B.Fab")
		)
		(fp_line
			(start 0.508 -0.3048)
			(end -0.508 -0.3048)
			(stroke
				(width 0.1)
				(type default)
			)
			(layer "B.Fab")
		)
		(fp_line
			(start 0.508 0.3048)
			(end 0.508 -0.3048)
			(stroke
				(width 0.1)
				(type default)
			)
			(layer "B.Fab")
		)
		(pad "1" smd circle
			(at 0.500126 0 180)
			(size 0.635 0.635)
			(layers "B.Cu" "B.Mask" "B.Paste")
			(net "XP3R3V_FPGA")
		)
		(pad "2" smd circle
			(at -0.500126 0 180)
			(size 0.635 0.635)
			(layers "B.Cu" "B.Mask" "B.Paste")
			(net "SG")
		)
	)
	(footprint ""
		(layer "B.Cu")
		(at 151.892 -42.037 90)
		(property "Reference" "R433"
			(at -8.42137 0.635 0)
			(unlocked yes)
			(layer "B.SilkS")
			(effects
				(font
					(size 0.7874 0.5842)
					(thickness 0.1524)
				)
				(justify mirror)
			)
		)
		(property "Value" "VAL*"
			(at -0.02032 2.13233 90)
			(unlocked yes)
			(layer "B.Fab")
			(hide yes)
			(effects
				(font
					(size 0.7874 0.5842)
					(thickness 0.1524)
				)
				(justify mirror)
			)
		)
		(property "Tolerance" "TOL*"
			(at -0.044704 3.05435 90)
			(unlocked yes)
			(layer "Cmts.User")
			(hide yes)
			(effects
				(font
					(size 0.7874 0.5842)
					(thickness 0.1524)
				)
				(justify mirror)
			)
		)
		(property "User Part Number" "PARTNUM*"
			(at -0.02032 4.024884 90)
			(unlocked yes)
			(layer "Cmts.User")
			(hide yes)
			(effects
				(font
					(size 0.7874 0.5842)
					(thickness 0.1524)
				)
				(justify mirror)
			)
		)
		(property "Device Type" "RESISTOR-G155-133R0-01,33OHM,1%"
			(at -0.008382 1.210564 90)
			(unlocked yes)
			(layer "B.Fab")
			(hide yes)
			(effects
				(font
					(size 0.7874 0.5842)
					(thickness 0.1524)
				)
				(justify mirror)
			)
		)
		(duplicate_pad_numbers_are_jumpers no)
		(fp_line
			(start 1.143 -0.5588)
			(end 1.143 0.5588)
			(stroke
				(width 0.1)
				(type default)
			)
			(layer "B.SilkS")
		)
		(fp_line
			(start -1.143 -0.5588)
			(end 1.143 -0.5588)
			(stroke
				(width 0.1)
				(type default)
			)
			(layer "B.SilkS")
		)
		(fp_line
			(start 1.143 0.5588)
			(end -1.143 0.5588)
			(stroke
				(width 0.1)
				(type default)
			)
			(layer "B.SilkS")
		)
		(fp_line
			(start -1.143 0.5588)
			(end -1.143 -0.5588)
			(stroke
				(width 0.1)
				(type default)
			)
			(layer "B.SilkS")
		)
		(fp_poly
			(pts
				(xy 1.143 0.5588) (xy -1.143 0.5588) (xy -1.143 -0.5588) (xy 1.143 -0.5588)
			)
			(stroke
				(width 0)
				(type default)
			)
			(fill no)
			(layer "B.CrtYd")
		)
		(fp_line
			(start 0.508 -0.3048)
			(end 0.508 0.3048)
			(stroke
				(width 0.1)
				(type default)
			)
			(layer "B.Fab")
		)
		(fp_line
			(start -0.508 -0.3048)
			(end 0.508 -0.3048)
			(stroke
				(width 0.1)
				(type default)
			)
			(layer "B.Fab")
		)
		(fp_line
			(start 0.508 0.3048)
			(end -0.508 0.3048)
			(stroke
				(width 0.1)
				(type default)
			)
			(layer "B.Fab")
		)
		(fp_line
			(start -0.508 0.3048)
			(end -0.508 -0.3048)
			(stroke
				(width 0.1)
				(type default)
			)
			(layer "B.Fab")
		)
		(pad "1" smd rect
			(at 0.5334 0 270)
			(size 0.7112 0.6096)
			(layers "B.Cu" "B.Mask" "B.Paste")
			(net "UNNAMED_16_CONNHDR2X6FSSMT_I1_3")
		)
		(pad "2" smd rect
			(at -0.5334 0 270)
			(size 0.7112 0.6096)
			(layers "B.Cu" "B.Mask" "B.Paste")
			(net "FPGA_IO_1")
		)
		(zone
			(layer "B.Cu")
			(hatch none 0.5)
			(connect_pads
				(clearance 0)
			)
			(min_thickness 0.25)
			(keepout
				(tracks allowed)
				(vias not_allowed)
				(pads allowed)
				(copperpour not_allowed)
				(footprints allowed)
			)
			(placement
				(enabled no)
				(sheetname "")
			)
			(fill
				(thermal_gap 0.5)
				(thermal_bridge_width 0.5)
				(island_removal_mode 0)
			)
			(polygon
				(pts
					(xy 152.1968 -42.1132) (xy 151.5872 -42.1132) (xy 151.5872 -41.9608) (xy 152.1968 -41.9608)
				)
			)
		)
		(zone
			(layer "B.Cu")
			(hatch none 0.5)
			(connect_pads
				(clearance 0)
			)
			(min_thickness 0.25)
			(keepout
				(tracks not_allowed)
				(vias allowed)
				(pads allowed)
				(copperpour not_allowed)
				(footprints allowed)
			)
			(placement
				(enabled no)
				(sheetname "")
			)
			(fill
				(thermal_gap 0.5)
				(thermal_bridge_width 0.5)
				(island_removal_mode 0)
			)
			(polygon
				(pts
					(xy 152.1968 -42.1132) (xy 151.5872 -42.1132) (xy 151.5872 -41.9608) (xy 152.1968 -41.9608)
				)
			)
		)
	)
	(footprint ""
		(layer "B.Cu")
		(at 23.0632 -71.374 90)
		(property "Reference" "R91"
			(at -1.905 1.02743 270)
			(unlocked yes)
			(layer "B.SilkS")
			(effects
				(font
					(size 0.7874 0.5842)
					(thickness 0.1524)
				)
				(justify mirror)
			)
		)
		(property "Value" "VAL*"
			(at -0.02032 2.13233 90)
			(unlocked yes)
			(layer "B.Fab")
			(hide yes)
			(effects
				(font
					(size 0.7874 0.5842)
					(thickness 0.1524)
				)
				(justify mirror)
			)
		)
		(property "Device Type" "RESISTOR-G155-133R0-01,33OHM,1%"
			(at -0.008382 1.210564 90)
			(unlocked yes)
			(layer "B.Fab")
			(hide yes)
			(effects
				(font
					(size 0.7874 0.5842)
					(thickness 0.1524)
				)
				(justify mirror)
			)
		)
		(property "User Part Number" "PARTNUM*"
			(at -0.02032 4.024884 90)
			(unlocked yes)
			(layer "Cmts.User")
			(hide yes)
			(effects
				(font
					(size 0.7874 0.5842)
					(thickness 0.1524)
				)
				(justify mirror)
			)
		)
		(property "Tolerance" "TOL*"
			(at -0.044704 3.05435 90)
			(unlocked yes)
			(layer "Cmts.User")
			(hide yes)
			(effects
				(font
					(size 0.7874 0.5842)
					(thickness 0.1524)
				)
				(justify mirror)
			)
		)
		(duplicate_pad_numbers_are_jumpers no)
		(fp_line
			(start 1.143 -0.5588)
			(end 1.143 0.5588)
			(stroke
				(width 0.1)
				(type default)
			)
			(layer "B.SilkS")
		)
		(fp_line
			(start -1.143 -0.5588)
			(end 1.143 -0.5588)
			(stroke
				(width 0.1)
				(type default)
			)
			(layer "B.SilkS")
		)
		(fp_line
			(start 1.143 0.5588)
			(end -1.143 0.5588)
			(stroke
				(width 0.1)
				(type default)
			)
			(layer "B.SilkS")
		)
		(fp_line
			(start -1.143 0.5588)
			(end -1.143 -0.5588)
			(stroke
				(width 0.1)
				(type default)
			)
			(layer "B.SilkS")
		)
		(fp_rect
			(start 1.143 0.5588)
			(end -1.143 -0.5588)
			(stroke
				(width 0)
				(type default)
			)
			(fill no)
			(layer "B.CrtYd")
		)
		(fp_line
			(start 0.508 -0.3048)
			(end 0.508 0.3048)
			(stroke
				(width 0.1)
				(type default)
			)
			(layer "B.Fab")
		)
		(fp_line
			(start -0.508 -0.3048)
			(end 0.508 -0.3048)
			(stroke
				(width 0.1)
				(type default)
			)
			(layer "B.Fab")
		)
		(fp_line
			(start 0.508 0.3048)
			(end -0.508 0.3048)
			(stroke
				(width 0.1)
				(type default)
			)
			(layer "B.Fab")
		)
		(fp_line
			(start -0.508 0.3048)
			(end -0.508 -0.3048)
			(stroke
				(width 0.1)
				(type default)
			)
			(layer "B.Fab")
		)
		(pad "1" smd rect
			(at 0.5334 0 270)
			(size 0.7112 0.6096)
			(layers "B.Cu" "B.Mask" "B.Paste")
			(net "ANALOG_TUNING_IN")
		)
		(pad "2" smd rect
			(at -0.5334 0 270)
			(size 0.7112 0.6096)
			(layers "B.Cu" "B.Mask" "B.Paste")
			(net "SMA_ANALOG_TUNING_IN")
		)
		(zone
			(layer "B.Cu")
			(hatch none 0.5)
			(connect_pads
				(clearance 0)
			)
			(min_thickness 0.25)
			(keepout
				(tracks not_allowed)
				(vias allowed)
				(pads allowed)
				(copperpour not_allowed)
				(footprints allowed)
			)
			(placement
				(enabled no)
				(sheetname "")
			)
			(fill
				(thermal_gap 0.5)
				(thermal_bridge_width 0.5)
				(island_removal_mode 0)
			)
			(polygon
				(pts
					(xy 23.368 -71.4502) (xy 22.7584 -71.4502) (xy 22.7584 -71.2978) (xy 23.368 -71.2978)
				)
			)
		)
		(zone
			(layer "B.Cu")
			(hatch none 0.5)
			(connect_pads
				(clearance 0)
			)
			(min_thickness 0.25)
			(keepout
				(tracks allowed)
				(vias not_allowed)
				(pads allowed)
				(copperpour not_allowed)
				(footprints allowed)
			)
			(placement
				(enabled no)
				(sheetname "")
			)
			(fill
				(thermal_gap 0.5)
				(thermal_bridge_width 0.5)
				(island_removal_mode 0)
			)
			(polygon
				(pts
					(xy 23.368 -71.4502) (xy 22.7584 -71.4502) (xy 22.7584 -71.2978) (xy 23.368 -71.2978)
				)
			)
		)
	)
	(footprint ""
		(layer "B.Cu")
		(at 138.4808 -74.7649 90)
		(property "Reference" "R404"
			(at -0.38227 -3.4798 0)
			(unlocked yes)
			(layer "B.SilkS")
			(effects
				(font
					(size 0.7874 0.5842)
					(thickness 0.1524)
				)
				(justify mirror)
			)
		)
		(property "Value" "VAL*"
			(at -0.02032 2.13233 90)
			(unlocked yes)
			(layer "B.Fab")
			(hide yes)
			(effects
				(font
					(size 0.7874 0.5842)
					(thickness 0.1524)
				)
				(justify mirror)
			)
		)
		(property "Device Type" "RESISTOR-G155-11002-01,10KOHM,A"
			(at -0.008382 1.210564 90)
			(unlocked yes)
			(layer "B.Fab")
			(hide yes)
			(effects
				(font
					(size 0.7874 0.5842)
					(thickness 0.1524)
				)
				(justify mirror)
			)
		)
		(property "User Part Number" "PARTNUM*"
			(at -0.02032 4.024884 90)
			(unlocked yes)
			(layer "Cmts.User")
			(hide yes)
			(effects
				(font
					(size 0.7874 0.5842)
					(thickness 0.1524)
				)
				(justify mirror)
			)
		)
		(property "Tolerance" "TOL*"
			(at -0.044704 3.05435 90)
			(unlocked yes)
			(layer "Cmts.User")
			(hide yes)
			(effects
				(font
					(size 0.7874 0.5842)
					(thickness 0.1524)
				)
				(justify mirror)
			)
		)
		(duplicate_pad_numbers_are_jumpers no)
		(fp_line
			(start 1.143 -0.5588)
			(end 1.143 0.5588)
			(stroke
				(width 0.1)
				(type default)
			)
			(layer "B.SilkS")
		)
		(fp_line
			(start -1.143 -0.5588)
			(end 1.143 -0.5588)
			(stroke
				(width 0.1)
				(type default)
			)
			(layer "B.SilkS")
		)
		(fp_line
			(start 1.143 0.5588)
			(end -1.143 0.5588)
			(stroke
				(width 0.1)
				(type default)
			)
			(layer "B.SilkS")
		)
		(fp_line
			(start -1.143 0.5588)
			(end -1.143 -0.5588)
			(stroke
				(width 0.1)
				(type default)
			)
			(layer "B.SilkS")
		)
		(fp_rect
			(start 1.143 0.5588)
			(end -1.143 -0.5588)
			(stroke
				(width 0)
				(type default)
			)
			(fill no)
			(layer "B.CrtYd")
		)
		(fp_line
			(start 0.508 -0.3048)
			(end 0.508 0.3048)
			(stroke
				(width 0.1)
				(type default)
			)
			(layer "B.Fab")
		)
		(fp_line
			(start -0.508 -0.3048)
			(end 0.508 -0.3048)
			(stroke
				(width 0.1)
				(type default)
			)
			(layer "B.Fab")
		)
		(fp_line
			(start 0.508 0.3048)
			(end -0.508 0.3048)
			(stroke
				(width 0.1)
				(type default)
			)
			(layer "B.Fab")
		)
		(fp_line
			(start -0.508 0.3048)
			(end -0.508 -0.3048)
			(stroke
				(width 0.1)
				(type default)
			)
			(layer "B.Fab")
		)
		(pad "1" smd rect
			(at 0.5334 0 270)
			(size 0.7112 0.6096)
			(layers "B.Cu" "B.Mask" "B.Paste")
			(net "XP3R3V_FPGA")
		)
		(pad "2" smd rect
			(at -0.5334 0 270)
			(size 0.7112 0.6096)
			(layers "B.Cu" "B.Mask" "B.Paste")
			(net "FPGA_TMS")
		)
		(zone
			(layer "B.Cu")
			(hatch none 0.5)
			(connect_pads
				(clearance 0)
			)
			(min_thickness 0.25)
			(keepout
				(tracks not_allowed)
				(vias allowed)
				(pads allowed)
				(copperpour not_allowed)
				(footprints allowed)
			)
			(placement
				(enabled no)
				(sheetname "")
			)
			(fill
				(thermal_gap 0.5)
				(thermal_bridge_width 0.5)
				(island_removal_mode 0)
			)
			(polygon
				(pts
					(xy 138.7856 -74.8411) (xy 138.176 -74.8411) (xy 138.176 -74.6887) (xy 138.7856 -74.6887)
				)
			)
		)
		(zone
			(layer "B.Cu")
			(hatch none 0.5)
			(connect_pads
				(clearance 0)
			)
			(min_thickness 0.25)
			(keepout
				(tracks allowed)
				(vias not_allowed)
				(pads allowed)
				(copperpour not_allowed)
				(footprints allowed)
			)
			(placement
				(enabled no)
				(sheetname "")
			)
			(fill
				(thermal_gap 0.5)
				(thermal_bridge_width 0.5)
				(island_removal_mode 0)
			)
			(polygon
				(pts
					(xy 138.7856 -74.8411) (xy 138.176 -74.8411) (xy 138.176 -74.6887) (xy 138.7856 -74.6887)
				)
			)
		)
	)
	(footprint ""
		(layer "B.Cu")
		(at 29.845 -91.059 -90)
		(property "Reference" "R463"
			(at -3.175 0.03937 270)
			(unlocked yes)
			(layer "B.SilkS")
			(effects
				(font
					(size 0.7874 0.5842)
					(thickness 0.1524)
				)
				(justify mirror)
			)
		)
		(property "Value" "VAL*"
			(at -0.0508 2.245106 270)
			(unlocked yes)
			(layer "B.Fab")
			(hide yes)
			(effects
				(font
					(size 0.7874 0.5842)
					(thickness 0.1524)
				)
				(justify mirror)
			)
		)
		(property "User Part Number" "PARTNUM*"
			(at -0.0762 4.302506 270)
			(unlocked yes)
			(layer "Cmts.User")
			(hide yes)
			(effects
				(font
					(size 0.7874 0.5842)
					(thickness 0.1524)
				)
				(justify mirror)
			)
		)
		(property "Device Type" "RESISTOR-G155-01202-01,12KOHM,A"
			(at -0.0762 1.254506 270)
			(unlocked yes)
			(layer "B.Fab")
			(hide yes)
			(effects
				(font
					(size 0.7874 0.5842)
					(thickness 0.1524)
				)
				(justify mirror)
			)
		)
		(property "Tolerance" "TOL*"
			(at -0.0508 3.261106 270)
			(unlocked yes)
			(layer "Cmts.User")
			(hide yes)
			(effects
				(font
					(size 0.7874 0.5842)
					(thickness 0.1524)
				)
				(justify mirror)
			)
		)
		(duplicate_pad_numbers_are_jumpers no)
		(fp_line
			(start -1.143 0.5588)
			(end -1.143 -0.5588)
			(stroke
				(width 0.1)
				(type default)
			)
			(layer "B.SilkS")
		)
		(fp_line
			(start 1.143 0.5588)
			(end -1.143 0.5588)
			(stroke
				(width 0.1)
				(type default)
			)
			(layer "B.SilkS")
		)
		(fp_line
			(start -1.143 -0.5588)
			(end 1.143 -0.5588)
			(stroke
				(width 0.1)
				(type default)
			)
			(layer "B.SilkS")
		)
		(fp_line
			(start 1.143 -0.5588)
			(end 1.143 0.5588)
			(stroke
				(width 0.1)
				(type default)
			)
			(layer "B.SilkS")
		)
		(fp_poly
			(pts
				(xy 1.143 0.5588) (xy -1.143 0.5588) (xy -1.143 -0.5588) (xy 1.143 -0.5588)
			)
			(stroke
				(width 0)
				(type default)
			)
			(fill no)
			(layer "B.CrtYd")
		)
		(fp_line
			(start -0.508 0.3048)
			(end -0.508 -0.3048)
			(stroke
				(width 0.1)
				(type default)
			)
			(layer "B.Fab")
		)
		(fp_line
			(start 0.508 0.3048)
			(end -0.508 0.3048)
			(stroke
				(width 0.1)
				(type default)
			)
			(layer "B.Fab")
		)
		(fp_line
			(start -0.508 -0.3048)
			(end 0.508 -0.3048)
			(stroke
				(width 0.1)
				(type default)
			)
			(layer "B.Fab")
		)
		(fp_line
			(start 0.508 -0.3048)
			(end 0.508 0.3048)
			(stroke
				(width 0.1)
				(type default)
			)
			(layer "B.Fab")
		)
		(pad "1" smd rect
			(at 0.5334 0 90)
			(size 0.7112 0.6096)
			(layers "B.Cu" "B.Mask" "B.Paste")
			(net "UNNAMED_524_FT4232HLREELQFP64_6")
		)
		(pad "2" smd rect
			(at -0.5334 0 90)
			(size 0.7112 0.6096)
			(layers "B.Cu" "B.Mask" "B.Paste")
			(net "SG")
		)
		(zone
			(layer "B.Cu")
			(hatch none 0.5)
			(connect_pads
				(clearance 0)
			)
			(min_thickness 0.25)
			(keepout
				(tracks allowed)
				(vias not_allowed)
				(pads allowed)
				(copperpour not_allowed)
				(footprints allowed)
			)
			(placement
				(enabled no)
				(sheetname "")
			)
			(fill
				(thermal_gap 0.5)
				(thermal_bridge_width 0.5)
				(island_removal_mode 0)
			)
			(polygon
				(pts
					(xy 29.5402 -90.9828) (xy 30.1498 -90.9828) (xy 30.1498 -91.1352) (xy 29.5402 -91.1352)
				)
			)
		)
		(zone
			(layer "B.Cu")
			(hatch none 0.5)
			(connect_pads
				(clearance 0)
			)
			(min_thickness 0.25)
			(keepout
				(tracks not_allowed)
				(vias allowed)
				(pads allowed)
				(copperpour not_allowed)
				(footprints allowed)
			)
			(placement
				(enabled no)
				(sheetname "")
			)
			(fill
				(thermal_gap 0.5)
				(thermal_bridge_width 0.5)
				(island_removal_mode 0)
			)
			(polygon
				(pts
					(xy 29.5402 -90.9828) (xy 30.1498 -90.9828) (xy 30.1498 -91.1352) (xy 29.5402 -91.1352)
				)
			)
		)
	)
	(footprint ""
		(layer "B.Cu")
		(at 140.335 -76.708)
		(property "Reference" "R137"
			(at 0 -2.24663 0)
			(unlocked yes)
			(layer "B.SilkS")
			(effects
				(font
					(size 0.7874 0.5842)
					(thickness 0.1524)
				)
				(justify mirror)
			)
		)
		(property "Value" "VAL*"
			(at -0.02032 2.13233 0)
			(unlocked yes)
			(layer "B.Fab")
			(hide yes)
			(effects
				(font
					(size 0.7874 0.5842)
					(thickness 0.1524)
				)
				(justify mirror)
			)
		)
		(property "Tolerance" "TOL*"
			(at -0.044704 3.05435 0)
			(unlocked yes)
			(layer "Cmts.User")
			(hide yes)
			(effects
				(font
					(size 0.7874 0.5842)
					(thickness 0.1524)
				)
				(justify mirror)
			)
		)
		(property "User Part Number" "PARTNUM*"
			(at -0.02032 4.024884 0)
			(unlocked yes)
			(layer "Cmts.User")
			(hide yes)
			(effects
				(font
					(size 0.7874 0.5842)
					(thickness 0.1524)
				)
				(justify mirror)
			)
		)
		(property "Device Type" "RESISTOR-G155-133R0-01,33OHM,1%"
			(at -0.008382 1.210564 0)
			(unlocked yes)
			(layer "B.Fab")
			(hide yes)
			(effects
				(font
					(size 0.7874 0.5842)
					(thickness 0.1524)
				)
				(justify mirror)
			)
		)
		(duplicate_pad_numbers_are_jumpers no)
		(fp_line
			(start -1.143 -0.5588)
			(end 1.143 -0.5588)
			(stroke
				(width 0.1)
				(type default)
			)
			(layer "B.SilkS")
		)
		(fp_line
			(start -1.143 0.5588)
			(end -1.143 -0.5588)
			(stroke
				(width 0.1)
				(type default)
			)
			(layer "B.SilkS")
		)
		(fp_line
			(start 1.143 -0.5588)
			(end 1.143 0.5588)
			(stroke
				(width 0.1)
				(type default)
			)
			(layer "B.SilkS")
		)
		(fp_line
			(start 1.143 0.5588)
			(end -1.143 0.5588)
			(stroke
				(width 0.1)
				(type default)
			)
			(layer "B.SilkS")
		)
		(fp_rect
			(start 1.143 0.5588)
			(end -1.143 -0.5588)
			(stroke
				(width 0)
				(type default)
			)
			(fill no)
			(layer "B.CrtYd")
		)
		(fp_line
			(start -0.508 -0.3048)
			(end 0.508 -0.3048)
			(stroke
				(width 0.1)
				(type default)
			)
			(layer "B.Fab")
		)
		(fp_line
			(start -0.508 0.3048)
			(end -0.508 -0.3048)
			(stroke
				(width 0.1)
				(type default)
			)
			(layer "B.Fab")
		)
		(fp_line
			(start 0.508 -0.3048)
			(end 0.508 0.3048)
			(stroke
				(width 0.1)
				(type default)
			)
			(layer "B.Fab")
		)
		(fp_line
			(start 0.508 0.3048)
			(end -0.508 0.3048)
			(stroke
				(width 0.1)
				(type default)
			)
			(layer "B.Fab")
		)
		(pad "1" smd rect
			(at 0.5334 0 180)
			(size 0.7112 0.6096)
			(layers "B.Cu" "B.Mask" "B.Paste")
			(net "FT4232_FPGA_TDI")
		)
		(pad "2" smd rect
			(at -0.5334 0 180)
			(size 0.7112 0.6096)
			(layers "B.Cu" "B.Mask" "B.Paste")
			(net "FPGA_TDI")
		)
		(zone
			(layer "B.Cu")
			(hatch none 0.5)
			(connect_pads
				(clearance 0)
			)
			(min_thickness 0.25)
			(keepout
				(tracks allowed)
				(vias not_allowed)
				(pads allowed)
				(copperpour not_allowed)
				(footprints allowed)
			)
			(placement
				(enabled no)
				(sheetname "")
			)
			(fill
				(thermal_gap 0.5)
				(thermal_bridge_width 0.5)
				(island_removal_mode 0)
			)
			(polygon
				(pts
					(xy 140.4112 -76.4032) (xy 140.4112 -77.0128) (xy 140.2588 -77.0128) (xy 140.2588 -76.4032)
				)
			)
		)
	)
	(footprint ""
		(layer "B.Cu")
		(at 22.3012 -23.6728 90)
		(property "Reference" "R159"
			(at 2.6162 0.01143 270)
			(unlocked yes)
			(layer "B.SilkS")
			(effects
				(font
					(size 0.7874 0.5842)
					(thickness 0.1524)
				)
				(justify mirror)
			)
		)
		(property "Value" "VAL*"
			(at -0.02032 2.13233 90)
			(unlocked yes)
			(layer "B.Fab")
			(hide yes)
			(effects
				(font
					(size 0.7874 0.5842)
					(thickness 0.1524)
				)
				(justify mirror)
			)
		)
		(property "Tolerance" "TOL*"
			(at -0.044704 3.05435 90)
			(unlocked yes)
			(layer "Cmts.User")
			(hide yes)
			(effects
				(font
					(size 0.7874 0.5842)
					(thickness 0.1524)
				)
				(justify mirror)
			)
		)
		(property "User Part Number" "PARTNUM*"
			(at -0.02032 4.024884 90)
			(unlocked yes)
			(layer "Cmts.User")
			(hide yes)
			(effects
				(font
					(size 0.7874 0.5842)
					(thickness 0.1524)
				)
				(justify mirror)
			)
		)
		(property "Device Type" "RESISTOR-G155-14701-01,4.7KOHMA"
			(at -0.008382 1.210564 90)
			(unlocked yes)
			(layer "B.Fab")
			(hide yes)
			(effects
				(font
					(size 0.7874 0.5842)
					(thickness 0.1524)
				)
				(justify mirror)
			)
		)
		(duplicate_pad_numbers_are_jumpers no)
		(fp_line
			(start 1.143 -0.5588)
			(end 1.143 0.5588)
			(stroke
				(width 0.1)
				(type default)
			)
			(layer "B.SilkS")
		)
		(fp_line
			(start -1.143 -0.5588)
			(end 1.143 -0.5588)
			(stroke
				(width 0.1)
				(type default)
			)
			(layer "B.SilkS")
		)
		(fp_line
			(start 1.143 0.5588)
			(end -1.143 0.5588)
			(stroke
				(width 0.1)
				(type default)
			)
			(layer "B.SilkS")
		)
		(fp_line
			(start -1.143 0.5588)
			(end -1.143 -0.5588)
			(stroke
				(width 0.1)
				(type default)
			)
			(layer "B.SilkS")
		)
		(fp_rect
			(start 1.143 -0.5588)
			(end -1.143 0.5588)
			(stroke
				(width 0)
				(type default)
			)
			(fill no)
			(layer "B.CrtYd")
		)
		(fp_line
			(start 0.508 -0.3048)
			(end 0.508 0.3048)
			(stroke
				(width 0.1)
				(type default)
			)
			(layer "B.Fab")
		)
		(fp_line
			(start -0.508 -0.3048)
			(end 0.508 -0.3048)
			(stroke
				(width 0.1)
				(type default)
			)
			(layer "B.Fab")
		)
		(fp_line
			(start 0.508 0.3048)
			(end -0.508 0.3048)
			(stroke
				(width 0.1)
				(type default)
			)
			(layer "B.Fab")
		)
		(fp_line
			(start -0.508 0.3048)
			(end -0.508 -0.3048)
			(stroke
				(width 0.1)
				(type default)
			)
			(layer "B.Fab")
		)
		(pad "1" smd rect
			(at 0.5334 0 270)
			(size 0.7112 0.6096)
			(layers "B.Cu" "B.Mask" "B.Paste")
			(net "UNNAMED_5_24LC16BTISTTSSOP8_I15")
		)
		(pad "2" smd rect
			(at -0.5334 0 270)
			(size 0.7112 0.6096)
			(layers "B.Cu" "B.Mask" "B.Paste")
			(net "SG")
		)
		(zone
			(layer "B.Cu")
			(hatch none 0.5)
			(connect_pads
				(clearance 0)
			)
			(min_thickness 0.25)
			(keepout
				(tracks allowed)
				(vias not_allowed)
				(pads allowed)
				(copperpour not_allowed)
				(footprints allowed)
			)
			(placement
				(enabled no)
				(sheetname "")
			)
			(fill
				(thermal_gap 0.5)
				(thermal_bridge_width 0.5)
				(island_removal_mode 0)
			)
			(polygon
				(pts
					(xy 21.9964 -23.749) (xy 21.9964 -23.5966) (xy 22.606 -23.5966) (xy 22.606 -23.749)
				)
			)
		)
	)
	(footprint ""
		(layer "B.Cu")
		(at 101.347016 -48.823118)
		(property "Reference" "C167"
			(at -1.144016 1.052068 0)
			(unlocked yes)
			(layer "B.SilkS")
			(effects
				(font
					(size 0.635 0.4064)
					(thickness 0.1524)
				)
				(justify mirror)
			)
		)
		(property "Value" "VAL*"
			(at 0 3.718306 0)
			(unlocked yes)
			(layer "B.Fab")
			(hide yes)
			(effects
				(font
					(size 0.7874 0.5842)
					(thickness 0.127)
				)
				(justify mirror)
			)
		)
		(property "Device Type" "CAPACITOR-G105-0F475-BM,4.7UF,A"
			(at 0 1.432306 0)
			(unlocked yes)
			(layer "B.Fab")
			(hide yes)
			(effects
				(font
					(size 0.7874 0.5842)
					(thickness 0.127)
				)
				(justify mirror)
			)
		)
		(property "User Part Number" "PARTNUM*"
			(at 0 2.575306 0)
			(unlocked yes)
			(layer "Cmts.User")
			(hide yes)
			(effects
				(font
					(size 0.7874 0.5842)
					(thickness 0.127)
				)
				(justify mirror)
			)
		)
		(property "Tolerance" "TOL*"
			(at 0 4.861306 0)
			(unlocked yes)
			(layer "Cmts.User")
			(hide yes)
			(effects
				(font
					(size 0.7874 0.5842)
					(thickness 0.127)
				)
				(justify mirror)
			)
		)
		(duplicate_pad_numbers_are_jumpers no)
		(fp_line
			(start -0.970026 -0.4699)
			(end -0.970026 0.4699)
			(stroke
				(width 0.1)
				(type default)
			)
			(layer "B.SilkS")
		)
		(fp_line
			(start -0.970026 0.4699)
			(end 0.970026 0.4699)
			(stroke
				(width 0.1)
				(type default)
			)
			(layer "B.SilkS")
		)
		(fp_line
			(start 0.970026 -0.4699)
			(end -0.970026 -0.4699)
			(stroke
				(width 0.1)
				(type default)
			)
			(layer "B.SilkS")
		)
		(fp_line
			(start 0.970026 0.4699)
			(end 0.970026 -0.4699)
			(stroke
				(width 0.1)
				(type default)
			)
			(layer "B.SilkS")
		)
		(fp_poly
			(pts
				(xy 0.970026 0.4699) (xy -0.970026 0.4699) (xy -0.970026 -0.4699) (xy 0.970026 -0.4699)
			)
			(stroke
				(width 0)
				(type default)
			)
			(fill no)
			(layer "B.CrtYd")
		)
		(fp_line
			(start -0.508 -0.3048)
			(end -0.508 0.3048)
			(stroke
				(width 0.1)
				(type default)
			)
			(layer "B.Fab")
		)
		(fp_line
			(start -0.508 0.3048)
			(end 0.508 0.3048)
			(stroke
				(width 0.1)
				(type default)
			)
			(layer "B.Fab")
		)
		(fp_line
			(start 0.508 -0.3048)
			(end -0.508 -0.3048)
			(stroke
				(width 0.1)
				(type default)
			)
			(layer "B.Fab")
		)
		(fp_line
			(start 0.508 0.3048)
			(end 0.508 -0.3048)
			(stroke
				(width 0.1)
				(type default)
			)
			(layer "B.Fab")
		)
		(pad "1" smd circle
			(at 0.500126 0 180)
			(size 0.635 0.635)
			(layers "B.Cu" "B.Mask" "B.Paste")
			(net "XP3R3V_FPGA")
		)
		(pad "2" smd circle
			(at -0.500126 0 180)
			(size 0.635 0.635)
			(layers "B.Cu" "B.Mask" "B.Paste")
			(net "SG")
		)
	)
	(footprint ""
		(layer "B.Cu")
		(at 5.588 -73.025)
		(property "Reference" "R336"
			(at -2.921 -0.59563 0)
			(unlocked yes)
			(layer "B.SilkS")
			(effects
				(font
					(size 0.7874 0.5842)
					(thickness 0.1524)
				)
				(justify mirror)
			)
		)
		(property "Value" "VAL*"
			(at -0.02032 2.13233 0)
			(unlocked yes)
			(layer "B.Fab")
			(hide yes)
			(effects
				(font
					(size 0.7874 0.5842)
					(thickness 0.1524)
				)
				(justify mirror)
			)
		)
		(property "Tolerance" "TOL*"
			(at -0.044704 3.05435 0)
			(unlocked yes)
			(layer "Cmts.User")
			(hide yes)
			(effects
				(font
					(size 0.7874 0.5842)
					(thickness 0.1524)
				)
				(justify mirror)
			)
		)
		(property "User Part Number" "PARTNUM*"
			(at -0.02032 4.024884 0)
			(unlocked yes)
			(layer "Cmts.User")
			(hide yes)
			(effects
				(font
					(size 0.7874 0.5842)
					(thickness 0.1524)
				)
				(justify mirror)
			)
		)
		(property "Device Type" "RESISTOR-G155-11001-01,1KOHM,1%"
			(at -0.008382 1.210564 0)
			(unlocked yes)
			(layer "B.Fab")
			(hide yes)
			(effects
				(font
					(size 0.7874 0.5842)
					(thickness 0.1524)
				)
				(justify mirror)
			)
		)
		(duplicate_pad_numbers_are_jumpers no)
		(fp_line
			(start -1.143 -0.5588)
			(end 1.143 -0.5588)
			(stroke
				(width 0.1)
				(type default)
			)
			(layer "B.SilkS")
		)
		(fp_line
			(start -1.143 0.5588)
			(end -1.143 -0.5588)
			(stroke
				(width 0.1)
				(type default)
			)
			(layer "B.SilkS")
		)
		(fp_line
			(start 1.143 -0.5588)
			(end 1.143 0.5588)
			(stroke
				(width 0.1)
				(type default)
			)
			(layer "B.SilkS")
		)
		(fp_line
			(start 1.143 0.5588)
			(end -1.143 0.5588)
			(stroke
				(width 0.1)
				(type default)
			)
			(layer "B.SilkS")
		)
		(fp_rect
			(start 1.143 0.5588)
			(end -1.143 -0.5588)
			(stroke
				(width 0)
				(type default)
			)
			(fill no)
			(layer "B.CrtYd")
		)
		(fp_line
			(start -0.508 -0.3048)
			(end 0.508 -0.3048)
			(stroke
				(width 0.1)
				(type default)
			)
			(layer "B.Fab")
		)
		(fp_line
			(start -0.508 0.3048)
			(end -0.508 -0.3048)
			(stroke
				(width 0.1)
				(type default)
			)
			(layer "B.Fab")
		)
		(fp_line
			(start 0.508 -0.3048)
			(end 0.508 0.3048)
			(stroke
				(width 0.1)
				(type default)
			)
			(layer "B.Fab")
		)
		(fp_line
			(start 0.508 0.3048)
			(end -0.508 0.3048)
			(stroke
				(width 0.1)
				(type default)
			)
			(layer "B.Fab")
		)
		(pad "1" smd rect
			(at 0.5334 0 180)
			(size 0.7112 0.6096)
			(layers "B.Cu" "B.Mask" "B.Paste")
			(net "UNNAMED_6_LM75BDPTSSOP8_I34_A1")
		)
		(pad "2" smd rect
			(at -0.5334 0 180)
			(size 0.7112 0.6096)
			(layers "B.Cu" "B.Mask" "B.Paste")
			(net "SG")
		)
		(zone
			(layer "B.Cu")
			(hatch none 0.5)
			(connect_pads
				(clearance 0)
			)
			(min_thickness 0.25)
			(keepout
				(tracks allowed)
				(vias not_allowed)
				(pads allowed)
				(copperpour not_allowed)
				(footprints allowed)
			)
			(placement
				(enabled no)
				(sheetname "")
			)
			(fill
				(thermal_gap 0.5)
				(thermal_bridge_width 0.5)
				(island_removal_mode 0)
			)
			(polygon
				(pts
					(xy 5.6642 -72.7202) (xy 5.6642 -73.3298) (xy 5.5118 -73.3298) (xy 5.5118 -72.7202)
				)
			)
		)
	)
	(footprint ""
		(layer "B.Cu")
		(at 116.34724 -47.82312 180)
		(property "Reference" "R270"
			(at 42.94124 -2.71907 0)
			(unlocked yes)
			(layer "B.SilkS")
			(effects
				(font
					(size 0.635 0.4064)
					(thickness 0.1524)
				)
				(justify mirror)
			)
		)
		(property "Value" "VAL*"
			(at 0 3.718306 180)
			(unlocked yes)
			(layer "B.Fab")
			(hide yes)
			(effects
				(font
					(size 0.7874 0.5842)
					(thickness 0.127)
				)
				(justify mirror)
			)
		)
		(property "Tolerance" "TOL*"
			(at 0 4.861306 180)
			(unlocked yes)
			(layer "Cmts.User")
			(hide yes)
			(effects
				(font
					(size 0.7874 0.5842)
					(thickness 0.127)
				)
				(justify mirror)
			)
		)
		(property "User Part Number" "PARTNUM*"
			(at 0 2.575306 180)
			(unlocked yes)
			(layer "Cmts.User")
			(hide yes)
			(effects
				(font
					(size 0.7874 0.5842)
					(thickness 0.127)
				)
				(justify mirror)
			)
		)
		(property "Device Type" "RESISTOR-G155-14701-01,4.7KOHMA"
			(at 0 1.432306 180)
			(unlocked yes)
			(layer "B.Fab")
			(hide yes)
			(effects
				(font
					(size 0.7874 0.5842)
					(thickness 0.127)
				)
				(justify mirror)
			)
		)
		(duplicate_pad_numbers_are_jumpers no)
		(fp_line
			(start 0.970026 0.4699)
			(end 0.970026 -0.4699)
			(stroke
				(width 0.1)
				(type default)
			)
			(layer "B.SilkS")
		)
		(fp_line
			(start 0.970026 -0.4699)
			(end -0.970026 -0.4699)
			(stroke
				(width 0.1)
				(type default)
			)
			(layer "B.SilkS")
		)
		(fp_line
			(start -0.970026 0.4699)
			(end 0.970026 0.4699)
			(stroke
				(width 0.1)
				(type default)
			)
			(layer "B.SilkS")
		)
		(fp_line
			(start -0.970026 -0.4699)
			(end -0.970026 0.4699)
			(stroke
				(width 0.1)
				(type default)
			)
			(layer "B.SilkS")
		)
		(fp_poly
			(pts
				(xy 0.970026 0.4699) (xy -0.970026 0.4699) (xy -0.970026 -0.4699) (xy 0.970026 -0.4699)
			)
			(stroke
				(width 0)
				(type default)
			)
			(fill no)
			(layer "B.CrtYd")
		)
		(fp_line
			(start 0.508 0.3048)
			(end 0.508 -0.3048)
			(stroke
				(width 0.1)
				(type default)
			)
			(layer "B.Fab")
		)
		(fp_line
			(start 0.508 -0.3048)
			(end -0.508 -0.3048)
			(stroke
				(width 0.1)
				(type default)
			)
			(layer "B.Fab")
		)
		(fp_line
			(start -0.508 0.3048)
			(end 0.508 0.3048)
			(stroke
				(width 0.1)
				(type default)
			)
			(layer "B.Fab")
		)
		(fp_line
			(start -0.508 -0.3048)
			(end -0.508 0.3048)
			(stroke
				(width 0.1)
				(type default)
			)
			(layer "B.Fab")
		)
		(pad "1" smd circle
			(at 0.500126 0)
			(size 0.635 0.635)
			(layers "B.Cu" "B.Mask" "B.Paste")
			(net "SG")
		)
		(pad "2" smd circle
			(at -0.500126 0)
			(size 0.635 0.635)
			(layers "B.Cu" "B.Mask" "B.Paste")
			(net "FPGA_IN_GPSTP1_OUT")
		)
	)
	(footprint ""
		(layer "B.Cu")
		(at 113.919 -61.976 -90)
		(property "Reference" "R216"
			(at -3.429 -0.08763 270)
			(unlocked yes)
			(layer "B.SilkS")
			(effects
				(font
					(size 0.7874 0.5842)
					(thickness 0.1524)
				)
				(justify mirror)
			)
		)
		(property "Value" "VAL*"
			(at -0.02032 2.13233 270)
			(unlocked yes)
			(layer "B.Fab")
			(hide yes)
			(effects
				(font
					(size 0.7874 0.5842)
					(thickness 0.1524)
				)
				(justify mirror)
			)
		)
		(property "Device Type" "RESISTOR-G155-11001-01,1KOHM,1%"
			(at -0.008382 1.210564 270)
			(unlocked yes)
			(layer "B.Fab")
			(hide yes)
			(effects
				(font
					(size 0.7874 0.5842)
					(thickness 0.1524)
				)
				(justify mirror)
			)
		)
		(property "User Part Number" "PARTNUM*"
			(at -0.02032 4.024884 270)
			(unlocked yes)
			(layer "Cmts.User")
			(hide yes)
			(effects
				(font
					(size 0.7874 0.5842)
					(thickness 0.1524)
				)
				(justify mirror)
			)
		)
		(property "Tolerance" "TOL*"
			(at -0.044704 3.05435 270)
			(unlocked yes)
			(layer "Cmts.User")
			(hide yes)
			(effects
				(font
					(size 0.7874 0.5842)
					(thickness 0.1524)
				)
				(justify mirror)
			)
		)
		(duplicate_pad_numbers_are_jumpers no)
		(fp_line
			(start -1.143 0.5588)
			(end -1.143 -0.5588)
			(stroke
				(width 0.1)
				(type default)
			)
			(layer "B.SilkS")
		)
		(fp_line
			(start 1.143 0.5588)
			(end -1.143 0.5588)
			(stroke
				(width 0.1)
				(type default)
			)
			(layer "B.SilkS")
		)
		(fp_line
			(start -1.143 -0.5588)
			(end 1.143 -0.5588)
			(stroke
				(width 0.1)
				(type default)
			)
			(layer "B.SilkS")
		)
		(fp_line
			(start 1.143 -0.5588)
			(end 1.143 0.5588)
			(stroke
				(width 0.1)
				(type default)
			)
			(layer "B.SilkS")
		)
		(fp_rect
			(start 1.143 0.5588)
			(end -1.143 -0.5588)
			(stroke
				(width 0)
				(type default)
			)
			(fill no)
			(layer "B.CrtYd")
		)
		(fp_line
			(start -0.508 0.3048)
			(end -0.508 -0.3048)
			(stroke
				(width 0.1)
				(type default)
			)
			(layer "B.Fab")
		)
		(fp_line
			(start 0.508 0.3048)
			(end -0.508 0.3048)
			(stroke
				(width 0.1)
				(type default)
			)
			(layer "B.Fab")
		)
		(fp_line
			(start -0.508 -0.3048)
			(end 0.508 -0.3048)
			(stroke
				(width 0.1)
				(type default)
			)
			(layer "B.Fab")
		)
		(fp_line
			(start 0.508 -0.3048)
			(end 0.508 0.3048)
			(stroke
				(width 0.1)
				(type default)
			)
			(layer "B.Fab")
		)
		(pad "1" smd rect
			(at 0.5334 0 90)
			(size 0.7112 0.6096)
			(layers "B.Cu" "B.Mask" "B.Paste")
			(net "FPGA_BRD_REV1")
		)
		(pad "2" smd rect
			(at -0.5334 0 90)
			(size 0.7112 0.6096)
			(layers "B.Cu" "B.Mask" "B.Paste")
			(net "SG")
		)
		(zone
			(layer "B.Cu")
			(hatch none 0.5)
			(connect_pads
				(clearance 0)
			)
			(min_thickness 0.25)
			(keepout
				(tracks allowed)
				(vias not_allowed)
				(pads allowed)
				(copperpour not_allowed)
				(footprints allowed)
			)
			(placement
				(enabled no)
				(sheetname "")
			)
			(fill
				(thermal_gap 0.5)
				(thermal_bridge_width 0.5)
				(island_removal_mode 0)
			)
			(polygon
				(pts
					(xy 113.6142 -61.8998) (xy 114.2238 -61.8998) (xy 114.2238 -62.0522) (xy 113.6142 -62.0522)
				)
			)
		)
	)
	(footprint ""
		(layer "B.Cu")
		(at 124.587 -51.435 180)
		(property "Reference" "R264"
			(at -3.302 -0.16637 0)
			(unlocked yes)
			(layer "B.SilkS")
			(effects
				(font
					(size 0.7874 0.5842)
					(thickness 0.1524)
				)
				(justify mirror)
			)
		)
		(property "Value" "VAL*"
			(at -0.02032 2.13233 180)
			(unlocked yes)
			(layer "B.Fab")
			(hide yes)
			(effects
				(font
					(size 0.7874 0.5842)
					(thickness 0.1524)
				)
				(justify mirror)
			)
		)
		(property "Tolerance" "TOL*"
			(at -0.044704 3.05435 180)
			(unlocked yes)
			(layer "Cmts.User")
			(hide yes)
			(effects
				(font
					(size 0.7874 0.5842)
					(thickness 0.1524)
				)
				(justify mirror)
			)
		)
		(property "User Part Number" "PARTNUM*"
			(at -0.02032 4.024884 180)
			(unlocked yes)
			(layer "Cmts.User")
			(hide yes)
			(effects
				(font
					(size 0.7874 0.5842)
					(thickness 0.1524)
				)
				(justify mirror)
			)
		)
		(property "Device Type" "RESISTOR-G155-11003-01,100KOHMA"
			(at -0.008382 1.210564 180)
			(unlocked yes)
			(layer "B.Fab")
			(hide yes)
			(effects
				(font
					(size 0.7874 0.5842)
					(thickness 0.1524)
				)
				(justify mirror)
			)
		)
		(duplicate_pad_numbers_are_jumpers no)
		(fp_line
			(start 1.143 0.5588)
			(end -1.143 0.5588)
			(stroke
				(width 0.1)
				(type default)
			)
			(layer "B.SilkS")
		)
		(fp_line
			(start 1.143 -0.5588)
			(end 1.143 0.5588)
			(stroke
				(width 0.1)
				(type default)
			)
			(layer "B.SilkS")
		)
		(fp_line
			(start -1.143 0.5588)
			(end -1.143 -0.5588)
			(stroke
				(width 0.1)
				(type default)
			)
			(layer "B.SilkS")
		)
		(fp_line
			(start -1.143 -0.5588)
			(end 1.143 -0.5588)
			(stroke
				(width 0.1)
				(type default)
			)
			(layer "B.SilkS")
		)
		(fp_rect
			(start 1.143 0.5588)
			(end -1.143 -0.5588)
			(stroke
				(width 0)
				(type default)
			)
			(fill no)
			(layer "B.CrtYd")
		)
		(fp_line
			(start 0.508 0.3048)
			(end -0.508 0.3048)
			(stroke
				(width 0.1)
				(type default)
			)
			(layer "B.Fab")
		)
		(fp_line
			(start 0.508 -0.3048)
			(end 0.508 0.3048)
			(stroke
				(width 0.1)
				(type default)
			)
			(layer "B.Fab")
		)
		(fp_line
			(start -0.508 0.3048)
			(end -0.508 -0.3048)
			(stroke
				(width 0.1)
				(type default)
			)
			(layer "B.Fab")
		)
		(fp_line
			(start -0.508 -0.3048)
			(end 0.508 -0.3048)
			(stroke
				(width 0.1)
				(type default)
			)
			(layer "B.Fab")
		)
		(pad "1" smd rect
			(at 0.5334 0)
			(size 0.7112 0.6096)
			(layers "B.Cu" "B.Mask" "B.Paste")
			(net "XP3R3V_FPGA")
		)
		(pad "2" smd rect
			(at -0.5334 0)
			(size 0.7112 0.6096)
			(layers "B.Cu" "B.Mask" "B.Paste")
			(net "R_MAC_UART_RX_FPGA_TX")
		)
		(zone
			(layer "B.Cu")
			(hatch none 0.5)
			(connect_pads
				(clearance 0)
			)
			(min_thickness 0.25)
			(keepout
				(tracks not_allowed)
				(vias allowed)
				(pads allowed)
				(copperpour not_allowed)
				(footprints allowed)
			)
			(placement
				(enabled no)
				(sheetname "")
			)
			(fill
				(thermal_gap 0.5)
				(thermal_bridge_width 0.5)
				(island_removal_mode 0)
			)
			(polygon
				(pts
					(xy 124.5108 -51.7398) (xy 124.5108 -51.1302) (xy 124.6632 -51.1302) (xy 124.6632 -51.7398)
				)
			)
		)
		(zone
			(layer "B.Cu")
			(hatch none 0.5)
			(connect_pads
				(clearance 0)
			)
			(min_thickness 0.25)
			(keepout
				(tracks allowed)
				(vias not_allowed)
				(pads allowed)
				(copperpour not_allowed)
				(footprints allowed)
			)
			(placement
				(enabled no)
				(sheetname "")
			)
			(fill
				(thermal_gap 0.5)
				(thermal_bridge_width 0.5)
				(island_removal_mode 0)
			)
			(polygon
				(pts
					(xy 124.5108 -51.7398) (xy 124.5108 -51.1302) (xy 124.6632 -51.1302) (xy 124.6632 -51.7398)
				)
			)
		)
	)
	(footprint ""
		(layer "B.Cu")
		(at 17.7292 -23.6728 90)
		(property "Reference" "R163"
			(at 1.3462 -1.13157 270)
			(unlocked yes)
			(layer "B.SilkS")
			(effects
				(font
					(size 0.7874 0.5842)
					(thickness 0.1524)
				)
				(justify mirror)
			)
		)
		(property "Value" "VAL*"
			(at -0.02032 2.13233 90)
			(unlocked yes)
			(layer "B.Fab")
			(hide yes)
			(effects
				(font
					(size 0.7874 0.5842)
					(thickness 0.1524)
				)
				(justify mirror)
			)
		)
		(property "Tolerance" "TOL*"
			(at -0.044704 3.05435 90)
			(unlocked yes)
			(layer "Cmts.User")
			(hide yes)
			(effects
				(font
					(size 0.7874 0.5842)
					(thickness 0.1524)
				)
				(justify mirror)
			)
		)
		(property "User Part Number" "PARTNUM*"
			(at -0.02032 4.024884 90)
			(unlocked yes)
			(layer "Cmts.User")
			(hide yes)
			(effects
				(font
					(size 0.7874 0.5842)
					(thickness 0.1524)
				)
				(justify mirror)
			)
		)
		(property "Device Type" "RESISTOR-G155-14701-01,4.7KOHMA"
			(at -0.008382 1.210564 90)
			(unlocked yes)
			(layer "B.Fab")
			(hide yes)
			(effects
				(font
					(size 0.7874 0.5842)
					(thickness 0.1524)
				)
				(justify mirror)
			)
		)
		(duplicate_pad_numbers_are_jumpers no)
		(fp_line
			(start 1.143 -0.5588)
			(end 1.143 0.5588)
			(stroke
				(width 0.1)
				(type default)
			)
			(layer "B.SilkS")
		)
		(fp_line
			(start -1.143 -0.5588)
			(end 1.143 -0.5588)
			(stroke
				(width 0.1)
				(type default)
			)
			(layer "B.SilkS")
		)
		(fp_line
			(start 1.143 0.5588)
			(end -1.143 0.5588)
			(stroke
				(width 0.1)
				(type default)
			)
			(layer "B.SilkS")
		)
		(fp_line
			(start -1.143 0.5588)
			(end -1.143 -0.5588)
			(stroke
				(width 0.1)
				(type default)
			)
			(layer "B.SilkS")
		)
		(fp_poly
			(pts
				(xy 1.143 0.5588) (xy -1.143 0.5588) (xy -1.143 -0.5588) (xy 1.143 -0.5588)
			)
			(stroke
				(width 0)
				(type default)
			)
			(fill no)
			(layer "B.CrtYd")
		)
		(fp_line
			(start 0.508 -0.3048)
			(end 0.508 0.3048)
			(stroke
				(width 0.1)
				(type default)
			)
			(layer "B.Fab")
		)
		(fp_line
			(start -0.508 -0.3048)
			(end 0.508 -0.3048)
			(stroke
				(width 0.1)
				(type default)
			)
			(layer "B.Fab")
		)
		(fp_line
			(start 0.508 0.3048)
			(end -0.508 0.3048)
			(stroke
				(width 0.1)
				(type default)
			)
			(layer "B.Fab")
		)
		(fp_line
			(start -0.508 0.3048)
			(end -0.508 -0.3048)
			(stroke
				(width 0.1)
				(type default)
			)
			(layer "B.Fab")
		)
		(pad "1" smd rect
			(at 0.5334 0 270)
			(size 0.7112 0.6096)
			(layers "B.Cu" "B.Mask" "B.Paste")
			(net "UNNAMED_5_24LC16BTISTTSSOP8_I_2")
		)
		(pad "2" smd rect
			(at -0.5334 0 270)
			(size 0.7112 0.6096)
			(layers "B.Cu" "B.Mask" "B.Paste")
			(net "SG")
		)
		(zone
			(layer "B.Cu")
			(hatch none 0.5)
			(connect_pads
				(clearance 0)
			)
			(min_thickness 0.25)
			(keepout
				(tracks allowed)
				(vias not_allowed)
				(pads allowed)
				(copperpour not_allowed)
				(footprints allowed)
			)
			(placement
				(enabled no)
				(sheetname "")
			)
			(fill
				(thermal_gap 0.5)
				(thermal_bridge_width 0.5)
				(island_removal_mode 0)
			)
			(polygon
				(pts
					(xy 18.034 -23.749) (xy 17.4244 -23.749) (xy 17.4244 -23.5966) (xy 18.034 -23.5966)
				)
			)
		)
		(zone
			(layer "B.Cu")
			(hatch none 0.5)
			(connect_pads
				(clearance 0)
			)
			(min_thickness 0.25)
			(keepout
				(tracks not_allowed)
				(vias allowed)
				(pads allowed)
				(copperpour not_allowed)
				(footprints allowed)
			)
			(placement
				(enabled no)
				(sheetname "")
			)
			(fill
				(thermal_gap 0.5)
				(thermal_bridge_width 0.5)
				(island_removal_mode 0)
			)
			(polygon
				(pts
					(xy 18.034 -23.749) (xy 17.4244 -23.749) (xy 17.4244 -23.5966) (xy 18.034 -23.5966)
				)
			)
		)
	)
	(footprint ""
		(layer "B.Cu")
		(at 107.347004 -45.823124)
		(property "Reference" "C200"
			(at -2.318004 0.261874 0)
			(unlocked yes)
			(layer "B.SilkS")
			(effects
				(font
					(size 0.635 0.4064)
					(thickness 0.1524)
				)
				(justify mirror)
			)
		)
		(property "Value" "VAL*"
			(at 0 3.718306 0)
			(unlocked yes)
			(layer "B.Fab")
			(hide yes)
			(effects
				(font
					(size 0.7874 0.5842)
					(thickness 0.127)
				)
				(justify mirror)
			)
		)
		(property "Tolerance" "TOL*"
			(at 0 4.861306 0)
			(unlocked yes)
			(layer "Cmts.User")
			(hide yes)
			(effects
				(font
					(size 0.7874 0.5842)
					(thickness 0.127)
				)
				(justify mirror)
			)
		)
		(property "User Part Number" "PARTNUM*"
			(at 0 2.575306 0)
			(unlocked yes)
			(layer "Cmts.User")
			(hide yes)
			(effects
				(font
					(size 0.7874 0.5842)
					(thickness 0.127)
				)
				(justify mirror)
			)
		)
		(property "Device Type" "CAPACITOR-G105-0B104-CK,0.1UF,A"
			(at 0 1.432306 0)
			(unlocked yes)
			(layer "B.Fab")
			(hide yes)
			(effects
				(font
					(size 0.7874 0.5842)
					(thickness 0.127)
				)
				(justify mirror)
			)
		)
		(duplicate_pad_numbers_are_jumpers no)
		(fp_line
			(start -0.970026 -0.4699)
			(end -0.970026 0.4699)
			(stroke
				(width 0.1)
				(type default)
			)
			(layer "B.SilkS")
		)
		(fp_line
			(start -0.970026 0.4699)
			(end 0.970026 0.4699)
			(stroke
				(width 0.1)
				(type default)
			)
			(layer "B.SilkS")
		)
		(fp_line
			(start 0.970026 -0.4699)
			(end -0.970026 -0.4699)
			(stroke
				(width 0.1)
				(type default)
			)
			(layer "B.SilkS")
		)
		(fp_line
			(start 0.970026 0.4699)
			(end 0.970026 -0.4699)
			(stroke
				(width 0.1)
				(type default)
			)
			(layer "B.SilkS")
		)
		(fp_poly
			(pts
				(xy 0.970026 0.4699) (xy -0.970026 0.4699) (xy -0.970026 -0.4699) (xy 0.970026 -0.4699)
			)
			(stroke
				(width 0)
				(type default)
			)
			(fill no)
			(layer "B.CrtYd")
		)
		(fp_line
			(start -0.508 -0.3048)
			(end -0.508 0.3048)
			(stroke
				(width 0.1)
				(type default)
			)
			(layer "B.Fab")
		)
		(fp_line
			(start -0.508 0.3048)
			(end 0.508 0.3048)
			(stroke
				(width 0.1)
				(type default)
			)
			(layer "B.Fab")
		)
		(fp_line
			(start 0.508 -0.3048)
			(end -0.508 -0.3048)
			(stroke
				(width 0.1)
				(type default)
			)
			(layer "B.Fab")
		)
		(fp_line
			(start 0.508 0.3048)
			(end 0.508 -0.3048)
			(stroke
				(width 0.1)
				(type default)
			)
			(layer "B.Fab")
		)
		(pad "1" smd circle
			(at 0.500126 0 180)
			(size 0.635 0.635)
			(layers "B.Cu" "B.Mask" "B.Paste")
			(net "XP1R8V_FPGA_VCCAUX")
		)
		(pad "2" smd circle
			(at -0.500126 0 180)
			(size 0.635 0.635)
			(layers "B.Cu" "B.Mask" "B.Paste")
			(net "SG")
		)
	)
	(footprint ""
		(layer "B.Cu")
		(at 34.417 -88.9 180)
		(property "Reference" "C96"
			(at -0.127 -1.18237 0)
			(unlocked yes)
			(layer "B.SilkS")
			(effects
				(font
					(size 0.7874 0.5842)
					(thickness 0.1524)
				)
				(justify mirror)
			)
		)
		(property "Value" "VAL*"
			(at -0.0762 2.067306 180)
			(unlocked yes)
			(layer "B.Fab")
			(hide yes)
			(effects
				(font
					(size 0.7874 0.5842)
					(thickness 0.1524)
				)
				(justify mirror)
			)
		)
		(property "Tolerance" "TOL*"
			(at -0.0762 3.032506 180)
			(unlocked yes)
			(layer "Cmts.User")
			(hide yes)
			(effects
				(font
					(size 0.7874 0.5842)
					(thickness 0.1524)
				)
				(justify mirror)
			)
		)
		(property "User Part Number" "PARTNUM*"
			(at -0.1016 4.023106 180)
			(unlocked yes)
			(layer "Cmts.User")
			(hide yes)
			(effects
				(font
					(size 0.7874 0.5842)
					(thickness 0.1524)
				)
				(justify mirror)
			)
		)
		(property "Device Type" "CAPACITOR-G105-0B104-EK,0.1UF,A"
			(at -0.0508 1.127506 180)
			(unlocked yes)
			(layer "B.Fab")
			(hide yes)
			(effects
				(font
					(size 0.7874 0.5842)
					(thickness 0.1524)
				)
				(justify mirror)
			)
		)
		(duplicate_pad_numbers_are_jumpers no)
		(fp_line
			(start 1.143 0.5588)
			(end -1.143 0.5588)
			(stroke
				(width 0.1)
				(type default)
			)
			(layer "B.SilkS")
		)
		(fp_line
			(start 1.143 -0.5588)
			(end 1.143 0.5588)
			(stroke
				(width 0.1)
				(type default)
			)
			(layer "B.SilkS")
		)
		(fp_line
			(start -1.143 0.5588)
			(end -1.143 -0.5588)
			(stroke
				(width 0.1)
				(type default)
			)
			(layer "B.SilkS")
		)
		(fp_line
			(start -1.143 -0.5588)
			(end 1.143 -0.5588)
			(stroke
				(width 0.1)
				(type default)
			)
			(layer "B.SilkS")
		)
		(fp_rect
			(start 1.143 0.5588)
			(end -1.143 -0.5588)
			(stroke
				(width 0)
				(type default)
			)
			(fill no)
			(layer "B.CrtYd")
		)
		(fp_line
			(start 0.508 0.3048)
			(end -0.508 0.3048)
			(stroke
				(width 0.1)
				(type default)
			)
			(layer "B.Fab")
		)
		(fp_line
			(start 0.508 -0.3048)
			(end 0.508 0.3048)
			(stroke
				(width 0.1)
				(type default)
			)
			(layer "B.Fab")
		)
		(fp_line
			(start -0.508 0.3048)
			(end -0.508 -0.3048)
			(stroke
				(width 0.1)
				(type default)
			)
			(layer "B.Fab")
		)
		(fp_line
			(start -0.508 -0.3048)
			(end 0.508 -0.3048)
			(stroke
				(width 0.1)
				(type default)
			)
			(layer "B.Fab")
		)
		(pad "1" smd rect
			(at 0.5334 0)
			(size 0.7112 0.6096)
			(layers "B.Cu" "B.Mask" "B.Paste")
			(net "FT4232_VREGOUT")
		)
		(pad "2" smd rect
			(at -0.5334 0)
			(size 0.7112 0.6096)
			(layers "B.Cu" "B.Mask" "B.Paste")
			(net "SG")
		)
		(zone
			(layer "B.Cu")
			(hatch none 0.5)
			(connect_pads
				(clearance 0)
			)
			(min_thickness 0.25)
			(keepout
				(tracks allowed)
				(vias not_allowed)
				(pads allowed)
				(copperpour not_allowed)
				(footprints allowed)
			)
			(placement
				(enabled no)
				(sheetname "")
			)
			(fill
				(thermal_gap 0.5)
				(thermal_bridge_width 0.5)
				(island_removal_mode 0)
			)
			(polygon
				(pts
					(xy 34.3408 -89.2048) (xy 34.3408 -88.5952) (xy 34.4932 -88.5952) (xy 34.4932 -89.2048)
				)
			)
		)
	)
	(footprint ""
		(layer "B.Cu")
		(at 135.0264 -91.6178 -90)
		(property "Reference" "CR3"
			(at -0.4826 2.98577 270)
			(unlocked yes)
			(layer "B.SilkS")
			(effects
				(font
					(size 0.7874 0.5842)
					(thickness 0.1524)
				)
				(justify mirror)
			)
		)
		(property "Value" "VAL*"
			(at -0.06985 6.435344 270)
			(unlocked yes)
			(layer "B.Fab")
			(hide yes)
			(effects
				(font
					(size 0.7874 0.5842)
					(thickness 0.1524)
				)
				(justify mirror)
			)
		)
		(property "User Part Number" "PARTNUM*"
			(at 0 4.531868 270)
			(unlocked yes)
			(layer "Cmts.User")
			(hide yes)
			(effects
				(font
					(size 0.7874 0.5842)
					(thickness 0.1524)
				)
				(justify mirror)
			)
		)
		(property "Device Type" "DIODE_2-G122-00005-01"
			(at 0 3.338068 270)
			(unlocked yes)
			(layer "B.Fab")
			(hide yes)
			(effects
				(font
					(size 0.7874 0.5842)
					(thickness 0.1524)
				)
				(justify mirror)
			)
		)
		(property "Tolerance" "TOL*"
			(at -0.031496 5.488178 270)
			(unlocked yes)
			(layer "Cmts.User")
			(hide yes)
			(effects
				(font
					(size 0.7874 0.5842)
					(thickness 0.1524)
				)
				(justify mirror)
			)
		)
		(duplicate_pad_numbers_are_jumpers no)
		(fp_line
			(start -3.543554 2.229104)
			(end 3.543554 2.229104)
			(stroke
				(width 0.1)
				(type default)
			)
			(layer "B.SilkS")
		)
		(fp_line
			(start 3.543554 2.229104)
			(end 3.543554 -2.229104)
			(stroke
				(width 0.1)
				(type default)
			)
			(layer "B.SilkS")
		)
		(fp_line
			(start 3.861562 -1.763014)
			(end 5.131562 -1.763014)
			(stroke
				(width 0.1)
				(type default)
			)
			(layer "B.SilkS")
		)
		(fp_line
			(start -3.543554 -2.229104)
			(end -3.543554 2.229104)
			(stroke
				(width 0.1)
				(type default)
			)
			(layer "B.SilkS")
		)
		(fp_line
			(start 3.543554 -2.229104)
			(end -3.543554 -2.229104)
			(stroke
				(width 0.1)
				(type default)
			)
			(layer "B.SilkS")
		)
		(fp_line
			(start 4.496562 -2.398014)
			(end 4.496562 -1.128014)
			(stroke
				(width 0.1)
				(type default)
			)
			(layer "B.SilkS")
		)
		(fp_rect
			(start -4.051554 -2.229104)
			(end -3.543554 2.229104)
			(stroke
				(width 0)
				(type default)
			)
			(fill yes)
			(layer "B.SilkS")
		)
		(fp_rect
			(start -4.051554 -2.483104)
			(end 3.797554 2.483104)
			(stroke
				(width 0)
				(type default)
			)
			(fill no)
			(layer "B.CrtYd")
		)
		(fp_line
			(start -2.29997 1.975104)
			(end -2.29997 -1.975104)
			(stroke
				(width 0.1)
				(type default)
			)
			(layer "B.Fab")
		)
		(fp_line
			(start 2.29997 1.975104)
			(end -2.29997 1.975104)
			(stroke
				(width 0.1)
				(type default)
			)
			(layer "B.Fab")
		)
		(fp_line
			(start 3.861308 -1.763268)
			(end 5.131308 -1.763268)
			(stroke
				(width 0.1)
				(type default)
			)
			(layer "B.Fab")
		)
		(fp_line
			(start -2.29997 -1.975104)
			(end 2.29997 -1.975104)
			(stroke
				(width 0.1)
				(type default)
			)
			(layer "B.Fab")
		)
		(fp_line
			(start 2.29997 -1.975104)
			(end 2.29997 1.975104)
			(stroke
				(width 0.1)
				(type default)
			)
			(layer "B.Fab")
		)
		(fp_line
			(start 4.496308 -2.398268)
			(end 4.496308 -1.128268)
			(stroke
				(width 0.1)
				(type default)
			)
			(layer "B.Fab")
		)
		(fp_rect
			(start -2.29997 -1.975104)
			(end -1.79197 1.975104)
			(stroke
				(width 0)
				(type default)
			)
			(fill yes)
			(layer "B.Fab")
		)
		(fp_text user "A"
			(at 4.66217 0.4064 0)
			(unlocked yes)
			(layer "B.SilkS")
			(effects
				(font
					(size 0.7874 0.5842)
					(thickness 0.1524)
				)
				(justify mirror)
			)
		)
		(fp_text user "C"
			(at -4.48183 -1.6256 0)
			(unlocked yes)
			(layer "B.SilkS")
			(effects
				(font
					(size 0.7874 0.5842)
					(thickness 0.1524)
				)
				(justify mirror)
			)
		)
		(fp_text user "A"
			(at 3.39217 0.4064 0)
			(unlocked yes)
			(layer "B.Fab")
			(effects
				(font
					(size 0.7874 0.5842)
					(thickness 0.1524)
				)
				(justify mirror)
			)
		)
		(fp_text user "C"
			(at -4.10083 0.0254 0)
			(unlocked yes)
			(layer "B.Fab")
			(effects
				(font
					(size 0.7874 0.5842)
					(thickness 0.1524)
				)
				(justify mirror)
			)
		)
		(pad "A" smd rect
			(at 2.210054 0 90)
			(size 2.159 2.7432)
			(layers "B.Cu" "B.Mask" "B.Paste")
			(net "SG")
		)
		(pad "C" smd rect
			(at -2.210054 0 90)
			(size 2.159 2.7432)
			(layers "B.Cu" "B.Mask" "B.Paste")
			(net "XP12R0V")
		)
	)
	(footprint ""
		(layer "B.Cu")
		(at 95.631 -84.455)
		(property "Reference" "R204"
			(at -0.254 -5.54863 0)
			(unlocked yes)
			(layer "B.SilkS")
			(effects
				(font
					(size 0.7874 0.5842)
					(thickness 0.1524)
				)
				(justify mirror)
			)
		)
		(property "Value" "VAL*"
			(at -0.02032 2.13233 0)
			(unlocked yes)
			(layer "B.Fab")
			(hide yes)
			(effects
				(font
					(size 0.7874 0.5842)
					(thickness 0.1524)
				)
				(justify mirror)
			)
		)
		(property "Tolerance" "TOL*"
			(at -0.044704 3.05435 0)
			(unlocked yes)
			(layer "Cmts.User")
			(hide yes)
			(effects
				(font
					(size 0.7874 0.5842)
					(thickness 0.1524)
				)
				(justify mirror)
			)
		)
		(property "User Part Number" "PARTNUM*"
			(at -0.02032 4.024884 0)
			(unlocked yes)
			(layer "Cmts.User")
			(hide yes)
			(effects
				(font
					(size 0.7874 0.5842)
					(thickness 0.1524)
				)
				(justify mirror)
			)
		)
		(property "Device Type" "RESISTOR-G155-133R0-01,33OHM,1%"
			(at -0.008382 1.210564 0)
			(unlocked yes)
			(layer "B.Fab")
			(hide yes)
			(effects
				(font
					(size 0.7874 0.5842)
					(thickness 0.1524)
				)
				(justify mirror)
			)
		)
		(duplicate_pad_numbers_are_jumpers no)
		(fp_line
			(start -1.143 -0.5588)
			(end 1.143 -0.5588)
			(stroke
				(width 0.1)
				(type default)
			)
			(layer "B.SilkS")
		)
		(fp_line
			(start -1.143 0.5588)
			(end -1.143 -0.5588)
			(stroke
				(width 0.1)
				(type default)
			)
			(layer "B.SilkS")
		)
		(fp_line
			(start 1.143 -0.5588)
			(end 1.143 0.5588)
			(stroke
				(width 0.1)
				(type default)
			)
			(layer "B.SilkS")
		)
		(fp_line
			(start 1.143 0.5588)
			(end -1.143 0.5588)
			(stroke
				(width 0.1)
				(type default)
			)
			(layer "B.SilkS")
		)
		(fp_rect
			(start -1.143 0.5588)
			(end 1.143 -0.5588)
			(stroke
				(width 0)
				(type default)
			)
			(fill no)
			(layer "B.CrtYd")
		)
		(fp_line
			(start -0.508 -0.3048)
			(end 0.508 -0.3048)
			(stroke
				(width 0.1)
				(type default)
			)
			(layer "B.Fab")
		)
		(fp_line
			(start -0.508 0.3048)
			(end -0.508 -0.3048)
			(stroke
				(width 0.1)
				(type default)
			)
			(layer "B.Fab")
		)
		(fp_line
			(start 0.508 -0.3048)
			(end 0.508 0.3048)
			(stroke
				(width 0.1)
				(type default)
			)
			(layer "B.Fab")
		)
		(fp_line
			(start 0.508 0.3048)
			(end -0.508 0.3048)
			(stroke
				(width 0.1)
				(type default)
			)
			(layer "B.Fab")
		)
		(pad "1" smd rect
			(at 0.5334 0 180)
			(size 0.7112 0.6096)
			(layers "B.Cu" "B.Mask" "B.Paste")
			(net "UNNAMED_127_MT25QL128ABA1ESES_1")
		)
		(pad "2" smd rect
			(at -0.5334 0 180)
			(size 0.7112 0.6096)
			(layers "B.Cu" "B.Mask" "B.Paste")
			(net "FLASH_DQ1_MISO")
		)
		(zone
			(layer "B.Cu")
			(hatch none 0.5)
			(connect_pads
				(clearance 0)
			)
			(min_thickness 0.25)
			(keepout
				(tracks allowed)
				(vias not_allowed)
				(pads allowed)
				(copperpour not_allowed)
				(footprints allowed)
			)
			(placement
				(enabled no)
				(sheetname "")
			)
			(fill
				(thermal_gap 0.5)
				(thermal_bridge_width 0.5)
				(island_removal_mode 0)
			)
			(polygon
				(pts
					(xy 95.5548 -84.1502) (xy 95.7072 -84.1502) (xy 95.7072 -84.7598) (xy 95.5548 -84.7598)
				)
			)
		)
	)
	(footprint ""
		(layer "B.Cu")
		(at 20.0152 -23.6728 -90)
		(property "Reference" "R160"
			(at -3.8862 -0.26543 270)
			(unlocked yes)
			(layer "B.SilkS")
			(effects
				(font
					(size 0.7874 0.5842)
					(thickness 0.1524)
				)
				(justify mirror)
			)
		)
		(property "Value" "VAL*"
			(at -0.02032 2.13233 270)
			(unlocked yes)
			(layer "B.Fab")
			(hide yes)
			(effects
				(font
					(size 0.7874 0.5842)
					(thickness 0.1524)
				)
				(justify mirror)
			)
		)
		(property "Tolerance" "TOL*"
			(at -0.044704 3.05435 270)
			(unlocked yes)
			(layer "Cmts.User")
			(hide yes)
			(effects
				(font
					(size 0.7874 0.5842)
					(thickness 0.1524)
				)
				(justify mirror)
			)
		)
		(property "User Part Number" "PARTNUM*"
			(at -0.02032 4.024884 270)
			(unlocked yes)
			(layer "Cmts.User")
			(hide yes)
			(effects
				(font
					(size 0.7874 0.5842)
					(thickness 0.1524)
				)
				(justify mirror)
			)
		)
		(property "Device Type" "RESISTOR-G155-14701-01,4.7KOHMA"
			(at -0.008382 1.210564 270)
			(unlocked yes)
			(layer "B.Fab")
			(hide yes)
			(effects
				(font
					(size 0.7874 0.5842)
					(thickness 0.1524)
				)
				(justify mirror)
			)
		)
		(duplicate_pad_numbers_are_jumpers no)
		(fp_line
			(start -1.143 0.5588)
			(end -1.143 -0.5588)
			(stroke
				(width 0.1)
				(type default)
			)
			(layer "B.SilkS")
		)
		(fp_line
			(start 1.143 0.5588)
			(end -1.143 0.5588)
			(stroke
				(width 0.1)
				(type default)
			)
			(layer "B.SilkS")
		)
		(fp_line
			(start -1.143 -0.5588)
			(end 1.143 -0.5588)
			(stroke
				(width 0.1)
				(type default)
			)
			(layer "B.SilkS")
		)
		(fp_line
			(start 1.143 -0.5588)
			(end 1.143 0.5588)
			(stroke
				(width 0.1)
				(type default)
			)
			(layer "B.SilkS")
		)
		(fp_rect
			(start 1.143 -0.5588)
			(end -1.143 0.5588)
			(stroke
				(width 0)
				(type default)
			)
			(fill no)
			(layer "B.CrtYd")
		)
		(fp_line
			(start -0.508 0.3048)
			(end -0.508 -0.3048)
			(stroke
				(width 0.1)
				(type default)
			)
			(layer "B.Fab")
		)
		(fp_line
			(start 0.508 0.3048)
			(end -0.508 0.3048)
			(stroke
				(width 0.1)
				(type default)
			)
			(layer "B.Fab")
		)
		(fp_line
			(start -0.508 -0.3048)
			(end 0.508 -0.3048)
			(stroke
				(width 0.1)
				(type default)
			)
			(layer "B.Fab")
		)
		(fp_line
			(start 0.508 -0.3048)
			(end 0.508 0.3048)
			(stroke
				(width 0.1)
				(type default)
			)
			(layer "B.Fab")
		)
		(pad "1" smd rect
			(at 0.5334 0 90)
			(size 0.7112 0.6096)
			(layers "B.Cu" "B.Mask" "B.Paste")
			(net "XP3R3V_FPGA")
		)
		(pad "2" smd rect
			(at -0.5334 0 90)
			(size 0.7112 0.6096)
			(layers "B.Cu" "B.Mask" "B.Paste")
			(net "UNNAMED_5_24LC16BTISTTSSOP8_I_1")
		)
		(zone
			(layer "B.Cu")
			(hatch none 0.5)
			(connect_pads
				(clearance 0)
			)
			(min_thickness 0.25)
			(keepout
				(tracks allowed)
				(vias not_allowed)
				(pads allowed)
				(copperpour not_allowed)
				(footprints allowed)
			)
			(placement
				(enabled no)
				(sheetname "")
			)
			(fill
				(thermal_gap 0.5)
				(thermal_bridge_width 0.5)
				(island_removal_mode 0)
			)
			(polygon
				(pts
					(xy 20.32 -23.5966) (xy 20.32 -23.749) (xy 19.7104 -23.749) (xy 19.7104 -23.5966)
				)
			)
		)
	)
	(footprint ""
		(layer "B.Cu")
		(at 118.847108 -47.323248 -90)
		(property "Reference" "R271"
			(at -1.698752 -1.771142 270)
			(unlocked yes)
			(layer "B.SilkS")
			(effects
				(font
					(size 0.635 0.4064)
					(thickness 0.1524)
				)
				(justify mirror)
			)
		)
		(property "Value" "VAL*"
			(at 0 3.718306 270)
			(unlocked yes)
			(layer "B.Fab")
			(hide yes)
			(effects
				(font
					(size 0.7874 0.5842)
					(thickness 0.127)
				)
				(justify mirror)
			)
		)
		(property "Tolerance" "TOL*"
			(at 0 4.861306 270)
			(unlocked yes)
			(layer "Cmts.User")
			(hide yes)
			(effects
				(font
					(size 0.7874 0.5842)
					(thickness 0.127)
				)
				(justify mirror)
			)
		)
		(property "User Part Number" "PARTNUM*"
			(at 0 2.575306 270)
			(unlocked yes)
			(layer "Cmts.User")
			(hide yes)
			(effects
				(font
					(size 0.7874 0.5842)
					(thickness 0.127)
				)
				(justify mirror)
			)
		)
		(property "Device Type" "RESISTOR-G155-14701-01,4.7KOHMA"
			(at 0 1.432306 270)
			(unlocked yes)
			(layer "B.Fab")
			(hide yes)
			(effects
				(font
					(size 0.7874 0.5842)
					(thickness 0.127)
				)
				(justify mirror)
			)
		)
		(duplicate_pad_numbers_are_jumpers no)
		(fp_line
			(start -0.970026 0.4699)
			(end 0.970026 0.4699)
			(stroke
				(width 0.1)
				(type default)
			)
			(layer "B.SilkS")
		)
		(fp_line
			(start 0.970026 0.4699)
			(end 0.970026 -0.4699)
			(stroke
				(width 0.1)
				(type default)
			)
			(layer "B.SilkS")
		)
		(fp_line
			(start -0.970026 -0.4699)
			(end -0.970026 0.4699)
			(stroke
				(width 0.1)
				(type default)
			)
			(layer "B.SilkS")
		)
		(fp_line
			(start 0.970026 -0.4699)
			(end -0.970026 -0.4699)
			(stroke
				(width 0.1)
				(type default)
			)
			(layer "B.SilkS")
		)
		(fp_poly
			(pts
				(xy 0.970026 0.4699) (xy -0.970026 0.4699) (xy -0.970026 -0.4699) (xy 0.970026 -0.4699)
			)
			(stroke
				(width 0)
				(type default)
			)
			(fill no)
			(layer "B.CrtYd")
		)
		(fp_line
			(start -0.508 0.3048)
			(end 0.508 0.3048)
			(stroke
				(width 0.1)
				(type default)
			)
			(layer "B.Fab")
		)
		(fp_line
			(start 0.508 0.3048)
			(end 0.508 -0.3048)
			(stroke
				(width 0.1)
				(type default)
			)
			(layer "B.Fab")
		)
		(fp_line
			(start -0.508 -0.3048)
			(end -0.508 0.3048)
			(stroke
				(width 0.1)
				(type default)
			)
			(layer "B.Fab")
		)
		(fp_line
			(start 0.508 -0.3048)
			(end -0.508 -0.3048)
			(stroke
				(width 0.1)
				(type default)
			)
			(layer "B.Fab")
		)
		(pad "1" smd circle
			(at 0.500126 0 90)
			(size 0.635 0.635)
			(layers "B.Cu" "B.Mask" "B.Paste")
			(net "SG")
		)
		(pad "2" smd circle
			(at -0.500126 0 90)
			(size 0.635 0.635)
			(layers "B.Cu" "B.Mask" "B.Paste")
			(net "FPGA_IN_GPSTP2_OUT")
		)
	)
	(footprint ""
		(layer "B.Cu")
		(at 47.2186 -87.9602)
		(property "Reference" "U31"
			(at 0.2794 -3.69443 0)
			(unlocked yes)
			(layer "B.SilkS")
			(effects
				(font
					(size 0.7874 0.5842)
					(thickness 0.1524)
				)
				(justify mirror)
			)
		)
		(property "Value" ""
			(at 0 0 0)
			(layer "B.Fab")
			(effects
				(font
					(size 1.27 1.27)
				)
				(justify mirror)
			)
		)
		(property "User Part Number" "PARTNUM*"
			(at 0.0508 4.52247 0)
			(unlocked yes)
			(layer "Cmts.User")
			(hide yes)
			(effects
				(font
					(size 0.7874 0.5842)
					(thickness 0.1524)
				)
				(justify mirror)
			)
		)
		(property "Device Type" "CAT93C46VI_GT3_SOIC8-G221-1007A"
			(at 0.0254 3.50647 0)
			(unlocked yes)
			(layer "B.Fab")
			(hide yes)
			(effects
				(font
					(size 0.7874 0.5842)
					(thickness 0.1524)
				)
				(justify mirror)
			)
		)
		(duplicate_pad_numbers_are_jumpers no)
		(fp_line
			(start -3.8862 -2.413)
			(end -3.8862 2.413)
			(stroke
				(width 0.1)
				(type default)
			)
			(layer "B.SilkS")
		)
		(fp_line
			(start -3.8862 2.413)
			(end -2.2098 2.413)
			(stroke
				(width 0.1)
				(type default)
			)
			(layer "B.SilkS")
		)
		(fp_line
			(start -2.2098 -2.7051)
			(end -2.2098 -2.413)
			(stroke
				(width 0.1)
				(type default)
			)
			(layer "B.SilkS")
		)
		(fp_line
			(start -2.2098 -2.413)
			(end -3.8862 -2.413)
			(stroke
				(width 0.1)
				(type default)
			)
			(layer "B.SilkS")
		)
		(fp_line
			(start -2.2098 2.413)
			(end -2.2098 2.7051)
			(stroke
				(width 0.1)
				(type default)
			)
			(layer "B.SilkS")
		)
		(fp_line
			(start -2.2098 2.7051)
			(end 2.2098 2.7051)
			(stroke
				(width 0.1)
				(type default)
			)
			(layer "B.SilkS")
		)
		(fp_line
			(start 2.2098 -2.7051)
			(end -2.2098 -2.7051)
			(stroke
				(width 0.1)
				(type default)
			)
			(layer "B.SilkS")
		)
		(fp_line
			(start 2.2098 -2.413)
			(end 2.2098 -2.7051)
			(stroke
				(width 0.1)
				(type default)
			)
			(layer "B.SilkS")
		)
		(fp_line
			(start 2.2098 2.413)
			(end 3.8862 2.413)
			(stroke
				(width 0.1)
				(type default)
			)
			(layer "B.SilkS")
		)
		(fp_line
			(start 2.2098 2.7051)
			(end 2.2098 2.413)
			(stroke
				(width 0.1)
				(type default)
			)
			(layer "B.SilkS")
		)
		(fp_line
			(start 3.8862 -2.413)
			(end 2.2098 -2.413)
			(stroke
				(width 0.1)
				(type default)
			)
			(layer "B.SilkS")
		)
		(fp_line
			(start 3.8862 2.413)
			(end 3.8862 -2.413)
			(stroke
				(width 0.1)
				(type default)
			)
			(layer "B.SilkS")
		)
		(fp_poly
			(pts
				(arc
					(start 4.9784 -2.9718)
					(mid 4.2164 -2.9718)
					(end 4.9784 -2.9718)
				)
			)
			(stroke
				(width 0)
				(type default)
			)
			(fill yes)
			(layer "B.SilkS")
		)
		(fp_poly
			(pts
				(xy -4.1402 2.9591) (xy -4.1402 -2.9591) (xy 4.1402 -2.9591) (xy 4.1402 2.9591)
			)
			(stroke
				(width 0)
				(type default)
			)
			(fill no)
			(layer "B.CrtYd")
		)
		(fp_line
			(start -2.9972 -2.1082)
			(end -2.9972 -1.7018)
			(stroke
				(width 0.1)
				(type default)
			)
			(layer "B.Fab")
		)
		(fp_line
			(start -2.9972 -1.7018)
			(end -1.9558 -1.7018)
			(stroke
				(width 0.1)
				(type default)
			)
			(layer "B.Fab")
		)
		(fp_line
			(start -2.9972 -0.8382)
			(end -2.9972 -0.4318)
			(stroke
				(width 0.1)
				(type default)
			)
			(layer "B.Fab")
		)
		(fp_line
			(start -2.9972 -0.4318)
			(end -1.9558 -0.4318)
			(stroke
				(width 0.1)
				(type default)
			)
			(layer "B.Fab")
		)
		(fp_line
			(start -2.9972 0.4318)
			(end -2.9972 0.8382)
			(stroke
				(width 0.1)
				(type default)
			)
			(layer "B.Fab")
		)
		(fp_line
			(start -2.9972 0.8382)
			(end -1.9558 0.8382)
			(stroke
				(width 0.1)
				(type default)
			)
			(layer "B.Fab")
		)
		(fp_line
			(start -2.9972 1.7018)
			(end -2.9972 2.1082)
			(stroke
				(width 0.1)
				(type default)
			)
			(layer "B.Fab")
		)
		(fp_line
			(start -2.9972 2.1082)
			(end -1.9558 2.1082)
			(stroke
				(width 0.1)
				(type default)
			)
			(layer "B.Fab")
		)
		(fp_line
			(start -1.9558 -2.4511)
			(end -1.9558 2.4511)
			(stroke
				(width 0.1)
				(type default)
			)
			(layer "B.Fab")
		)
		(fp_line
			(start -1.9558 -2.1082)
			(end -2.9972 -2.1082)
			(stroke
				(width 0.1)
				(type default)
			)
			(layer "B.Fab")
		)
		(fp_line
			(start -1.9558 -0.8382)
			(end -2.9972 -0.8382)
			(stroke
				(width 0.1)
				(type default)
			)
			(layer "B.Fab")
		)
		(fp_line
			(start -1.9558 0.4318)
			(end -2.9972 0.4318)
			(stroke
				(width 0.1)
				(type default)
			)
			(layer "B.Fab")
		)
		(fp_line
			(start -1.9558 1.7018)
			(end -2.9972 1.7018)
			(stroke
				(width 0.1)
				(type default)
			)
			(layer "B.Fab")
		)
		(fp_line
			(start -1.9558 2.4511)
			(end 1.9558 2.4511)
			(stroke
				(width 0.1)
				(type default)
			)
			(layer "B.Fab")
		)
		(fp_line
			(start 1.9558 -2.4511)
			(end -1.9558 -2.4511)
			(stroke
				(width 0.1)
				(type default)
			)
			(layer "B.Fab")
		)
		(fp_line
			(start 1.9558 -2.1082)
			(end 2.9972 -2.1082)
			(stroke
				(width 0.1)
				(type default)
			)
			(layer "B.Fab")
		)
		(fp_line
			(start 1.9558 -0.8382)
			(end 2.9972 -0.8382)
			(stroke
				(width 0.1)
				(type default)
			)
			(layer "B.Fab")
		)
		(fp_line
			(start 1.9558 0.4318)
			(end 2.9972 0.4318)
			(stroke
				(width 0.1)
				(type default)
			)
			(layer "B.Fab")
		)
		(fp_line
			(start 1.9558 1.7018)
			(end 2.9972 1.7018)
			(stroke
				(width 0.1)
				(type default)
			)
			(layer "B.Fab")
		)
		(fp_line
			(start 1.9558 2.4511)
			(end 1.9558 -2.4511)
			(stroke
				(width 0.1)
				(type default)
			)
			(layer "B.Fab")
		)
		(fp_line
			(start 2.9972 -2.1082)
			(end 2.9972 -1.7018)
			(stroke
				(width 0.1)
				(type default)
			)
			(layer "B.Fab")
		)
		(fp_line
			(start 2.9972 -1.7018)
			(end 1.9558 -1.7018)
			(stroke
				(width 0.1)
				(type default)
			)
			(layer "B.Fab")
		)
		(fp_line
			(start 2.9972 -0.8382)
			(end 2.9972 -0.4318)
			(stroke
				(width 0.1)
				(type default)
			)
			(layer "B.Fab")
		)
		(fp_line
			(start 2.9972 -0.4318)
			(end 1.9558 -0.4318)
			(stroke
				(width 0.1)
				(type default)
			)
			(layer "B.Fab")
		)
		(fp_line
			(start 2.9972 0.4318)
			(end 2.9972 0.8382)
			(stroke
				(width 0.1)
				(type default)
			)
			(layer "B.Fab")
		)
		(fp_line
			(start 2.9972 0.8382)
			(end 1.9558 0.8382)
			(stroke
				(width 0.1)
				(type default)
			)
			(layer "B.Fab")
		)
		(fp_line
			(start 2.9972 1.7018)
			(end 2.9972 2.1082)
			(stroke
				(width 0.1)
				(type default)
			)
			(layer "B.Fab")
		)
		(fp_line
			(start 2.9972 2.1082)
			(end 1.9558 2.1082)
			(stroke
				(width 0.1)
				(type default)
			)
			(layer "B.Fab")
		)
		(fp_poly
			(pts
				(arc
					(start 1.284478 -1.899158)
					(mid 0.522478 -1.899158)
					(end 1.284478 -1.899158)
				)
			)
			(stroke
				(width 0)
				(type default)
			)
			(fill yes)
			(layer "B.Fab")
		)
		(fp_text user "8"
			(at -4.4196 -2.04343 0)
			(unlocked yes)
			(layer "B.SilkS")
			(effects
				(font
					(size 0.7874 0.5842)
					(thickness 0.1524)
				)
				(justify mirror)
			)
		)
		(fp_text user "5"
			(at -4.4196 2.90957 0)
			(unlocked yes)
			(layer "B.SilkS")
			(effects
				(font
					(size 0.7874 0.5842)
					(thickness 0.1524)
				)
				(justify mirror)
			)
		)
		(fp_text user "4"
			(at 4.4704 2.78257 0)
			(unlocked yes)
			(layer "B.SilkS")
			(effects
				(font
					(size 0.7874 0.5842)
					(thickness 0.1524)
				)
				(justify mirror)
			)
		)
		(fp_text user "5"
			(at -4.3942 1.93167 0)
			(unlocked yes)
			(layer "B.Fab")
			(effects
				(font
					(size 0.7874 0.5842)
					(thickness 0.1524)
				)
				(justify mirror)
			)
		)
		(fp_text user "8"
			(at -4.3688 -1.87833 0)
			(unlocked yes)
			(layer "B.Fab")
			(effects
				(font
					(size 0.7874 0.5842)
					(thickness 0.1524)
				)
				(justify mirror)
			)
		)
		(fp_text user "4"
			(at 4.3942 2.03327 0)
			(unlocked yes)
			(layer "B.Fab")
			(effects
				(font
					(size 0.7874 0.5842)
					(thickness 0.1524)
				)
				(justify mirror)
			)
		)
		(pad "1" smd rect
			(at 2.8067 -1.905 90)
			(size 0.508 1.651)
			(layers "B.Cu" "B.Mask" "B.Paste")
			(net "FTDI_EE_CS")
		)
		(pad "2" smd rect
			(at 2.8067 -0.635 90)
			(size 0.508 1.651)
			(layers "B.Cu" "B.Mask" "B.Paste")
			(net "FTDI_EE_CLK")
		)
		(pad "3" smd rect
			(at 2.8067 0.635 90)
			(size 0.508 1.651)
			(layers "B.Cu" "B.Mask" "B.Paste")
			(net "FTDI_EE_DAT")
		)
		(pad "4" smd rect
			(at 2.8067 1.905 90)
			(size 0.508 1.651)
			(layers "B.Cu" "B.Mask" "B.Paste")
			(net "FTDI_EE_DO")
		)
		(pad "5" smd rect
			(at -2.8067 1.905 90)
			(size 0.508 1.651)
			(layers "B.Cu" "B.Mask" "B.Paste")
			(net "SG")
		)
		(pad "6" smd rect
			(at -2.8067 0.635 90)
			(size 0.508 1.651)
			(layers "B.Cu" "B.Mask" "B.Paste")
			(net "XP3R3V_FT4232")
		)
		(pad "7" smd rect
			(at -2.8067 -0.635 90)
			(size 0.508 1.651)
			(layers "B.Cu" "B.Mask" "B.Paste")
			(net "Net_296")
		)
		(pad "8" smd rect
			(at -2.8067 -1.905 90)
			(size 0.508 1.651)
			(layers "B.Cu" "B.Mask" "B.Paste")
			(net "XP3R3V_FT4232")
		)
	)
	(footprint ""
		(layer "B.Cu")
		(at 75.184 -73.152 -90)
		(property "Reference" "C58"
			(at -3.429 -0.34163 270)
			(unlocked yes)
			(layer "B.SilkS")
			(effects
				(font
					(size 0.7874 0.5842)
					(thickness 0.1524)
				)
				(justify mirror)
			)
		)
		(property "Value" "VAL*"
			(at -0.0762 3.134106 270)
			(unlocked yes)
			(layer "B.Fab")
			(hide yes)
			(effects
				(font
					(size 0.7874 0.5842)
					(thickness 0.1524)
				)
				(justify mirror)
			)
		)
		(property "Device Type" "CAPACITOR-G107-0F106-EM,10UF,2A"
			(at -0.0508 2.194306 270)
			(unlocked yes)
			(layer "B.Fab")
			(hide yes)
			(effects
				(font
					(size 0.7874 0.5842)
					(thickness 0.1524)
				)
				(justify mirror)
			)
		)
		(property "User Part Number" "PARTNUM*"
			(at -0.1016 5.013706 270)
			(unlocked yes)
			(layer "Cmts.User")
			(hide yes)
			(effects
				(font
					(size 0.7874 0.5842)
					(thickness 0.1524)
				)
				(justify mirror)
			)
		)
		(property "Tolerance" "TOL*"
			(at -0.0762 4.048506 270)
			(unlocked yes)
			(layer "Cmts.User")
			(hide yes)
			(effects
				(font
					(size 0.7874 0.5842)
					(thickness 0.1524)
				)
				(justify mirror)
			)
		)
		(duplicate_pad_numbers_are_jumpers no)
		(fp_line
			(start -1.5748 0.9398)
			(end -1.5748 -0.9398)
			(stroke
				(width 0.1)
				(type default)
			)
			(layer "B.SilkS")
		)
		(fp_line
			(start 1.5748 0.9398)
			(end -1.5748 0.9398)
			(stroke
				(width 0.1)
				(type default)
			)
			(layer "B.SilkS")
		)
		(fp_line
			(start -1.5748 -0.9398)
			(end 1.5748 -0.9398)
			(stroke
				(width 0.1)
				(type default)
			)
			(layer "B.SilkS")
		)
		(fp_line
			(start 1.5748 -0.9398)
			(end 1.5748 0.9398)
			(stroke
				(width 0.1)
				(type default)
			)
			(layer "B.SilkS")
		)
		(fp_rect
			(start 1.5748 0.9398)
			(end -1.5748 -0.9398)
			(stroke
				(width 0)
				(type default)
			)
			(fill no)
			(layer "B.CrtYd")
		)
		(fp_line
			(start -1.016 0.635)
			(end -1.016 -0.635)
			(stroke
				(width 0.1)
				(type default)
			)
			(layer "B.Fab")
		)
		(fp_line
			(start 1.016 0.635)
			(end -1.016 0.635)
			(stroke
				(width 0.1)
				(type default)
			)
			(layer "B.Fab")
		)
		(fp_line
			(start -1.016 -0.635)
			(end 1.016 -0.635)
			(stroke
				(width 0.1)
				(type default)
			)
			(layer "B.Fab")
		)
		(fp_line
			(start 1.016 -0.635)
			(end 1.016 0.635)
			(stroke
				(width 0.1)
				(type default)
			)
			(layer "B.Fab")
		)
		(pad "1" smd rect
			(at 0.8382 0 90)
			(size 0.9652 1.3716)
			(layers "B.Cu" "B.Mask" "B.Paste")
			(net "XP5R0V_MAC")
		)
		(pad "2" smd rect
			(at -0.8382 0 90)
			(size 0.9652 1.3716)
			(layers "B.Cu" "B.Mask" "B.Paste")
			(net "SG")
		)
		(zone
			(layer "B.Cu")
			(hatch none 0.5)
			(connect_pads
				(clearance 0)
			)
			(min_thickness 0.25)
			(keepout
				(tracks allowed)
				(vias not_allowed)
				(pads allowed)
				(copperpour not_allowed)
				(footprints allowed)
			)
			(placement
				(enabled no)
				(sheetname "")
			)
			(fill
				(thermal_gap 0.5)
				(thermal_bridge_width 0.5)
				(island_removal_mode 0)
			)
			(polygon
				(pts
					(xy 74.549 -72.9234) (xy 75.819 -72.9234) (xy 75.819 -73.3806) (xy 74.549 -73.3806)
				)
			)
		)
	)
	(footprint ""
		(layer "B.Cu")
		(at 102.84714 -35.323018 -90)
		(property "Reference" "C213"
			(at 1.668018 43.56989 270)
			(unlocked yes)
			(layer "B.SilkS")
			(effects
				(font
					(size 0.635 0.4064)
					(thickness 0.1524)
				)
				(justify mirror)
			)
		)
		(property "Value" "VAL*"
			(at 0 3.718306 270)
			(unlocked yes)
			(layer "B.Fab")
			(hide yes)
			(effects
				(font
					(size 0.7874 0.5842)
					(thickness 0.127)
				)
				(justify mirror)
			)
		)
		(property "Tolerance" "TOL*"
			(at 0 4.861306 270)
			(unlocked yes)
			(layer "Cmts.User")
			(hide yes)
			(effects
				(font
					(size 0.7874 0.5842)
					(thickness 0.127)
				)
				(justify mirror)
			)
		)
		(property "User Part Number" "PARTNUM*"
			(at 0 2.575306 270)
			(unlocked yes)
			(layer "Cmts.User")
			(hide yes)
			(effects
				(font
					(size 0.7874 0.5842)
					(thickness 0.127)
				)
				(justify mirror)
			)
		)
		(property "Device Type" "CAPACITOR-G105-0B104-CK,0.1UF,A"
			(at 0 1.432306 270)
			(unlocked yes)
			(layer "B.Fab")
			(hide yes)
			(effects
				(font
					(size 0.7874 0.5842)
					(thickness 0.127)
				)
				(justify mirror)
			)
		)
		(duplicate_pad_numbers_are_jumpers no)
		(fp_line
			(start -0.970026 0.4699)
			(end 0.970026 0.4699)
			(stroke
				(width 0.1)
				(type default)
			)
			(layer "B.SilkS")
		)
		(fp_line
			(start 0.970026 0.4699)
			(end 0.970026 -0.4699)
			(stroke
				(width 0.1)
				(type default)
			)
			(layer "B.SilkS")
		)
		(fp_line
			(start -0.970026 -0.4699)
			(end -0.970026 0.4699)
			(stroke
				(width 0.1)
				(type default)
			)
			(layer "B.SilkS")
		)
		(fp_line
			(start 0.970026 -0.4699)
			(end -0.970026 -0.4699)
			(stroke
				(width 0.1)
				(type default)
			)
			(layer "B.SilkS")
		)
		(fp_poly
			(pts
				(xy 0.970026 0.4699) (xy -0.970026 0.4699) (xy -0.970026 -0.4699) (xy 0.970026 -0.4699)
			)
			(stroke
				(width 0)
				(type default)
			)
			(fill no)
			(layer "B.CrtYd")
		)
		(fp_line
			(start -0.508 0.3048)
			(end 0.508 0.3048)
			(stroke
				(width 0.1)
				(type default)
			)
			(layer "B.Fab")
		)
		(fp_line
			(start 0.508 0.3048)
			(end 0.508 -0.3048)
			(stroke
				(width 0.1)
				(type default)
			)
			(layer "B.Fab")
		)
		(fp_line
			(start -0.508 -0.3048)
			(end -0.508 0.3048)
			(stroke
				(width 0.1)
				(type default)
			)
			(layer "B.Fab")
		)
		(fp_line
			(start 0.508 -0.3048)
			(end -0.508 -0.3048)
			(stroke
				(width 0.1)
				(type default)
			)
			(layer "B.Fab")
		)
		(pad "1" smd circle
			(at 0.500126 0 90)
			(size 0.635 0.635)
			(layers "B.Cu" "B.Mask" "B.Paste")
			(net "XP2R5V_FPGA")
		)
		(pad "2" smd circle
			(at -0.500126 0 90)
			(size 0.635 0.635)
			(layers "B.Cu" "B.Mask" "B.Paste")
			(net "SG")
		)
	)
	(footprint ""
		(layer "B.Cu")
		(at 145.8214 -99.2378 180)
		(property "Reference" "R16"
			(at -3.1496 -0.09017 0)
			(unlocked yes)
			(layer "B.SilkS")
			(effects
				(font
					(size 0.7874 0.5842)
					(thickness 0.1524)
				)
				(justify mirror)
			)
		)
		(property "Value" "VAL*"
			(at -0.0508 2.245106 180)
			(unlocked yes)
			(layer "B.Fab")
			(hide yes)
			(effects
				(font
					(size 0.7874 0.5842)
					(thickness 0.1524)
				)
				(justify mirror)
			)
		)
		(property "Tolerance" "TOL*"
			(at -0.0508 3.261106 180)
			(unlocked yes)
			(layer "Cmts.User")
			(hide yes)
			(effects
				(font
					(size 0.7874 0.5842)
					(thickness 0.1524)
				)
				(justify mirror)
			)
		)
		(property "Device Type" "RESISTOR-G155-03921-01,3.92KOHA"
			(at -0.0762 1.254506 180)
			(unlocked yes)
			(layer "B.Fab")
			(hide yes)
			(effects
				(font
					(size 0.7874 0.5842)
					(thickness 0.1524)
				)
				(justify mirror)
			)
		)
		(property "User Part Number" "PARTNUM*"
			(at -0.0762 4.302506 180)
			(unlocked yes)
			(layer "Cmts.User")
			(hide yes)
			(effects
				(font
					(size 0.7874 0.5842)
					(thickness 0.1524)
				)
				(justify mirror)
			)
		)
		(duplicate_pad_numbers_are_jumpers no)
		(fp_line
			(start 1.143 0.5588)
			(end -1.143 0.5588)
			(stroke
				(width 0.1)
				(type default)
			)
			(layer "B.SilkS")
		)
		(fp_line
			(start 1.143 -0.5588)
			(end 1.143 0.5588)
			(stroke
				(width 0.1)
				(type default)
			)
			(layer "B.SilkS")
		)
		(fp_line
			(start -1.143 0.5588)
			(end -1.143 -0.5588)
			(stroke
				(width 0.1)
				(type default)
			)
			(layer "B.SilkS")
		)
		(fp_line
			(start -1.143 -0.5588)
			(end 1.143 -0.5588)
			(stroke
				(width 0.1)
				(type default)
			)
			(layer "B.SilkS")
		)
		(fp_rect
			(start 1.143 -0.5588)
			(end -1.143 0.5588)
			(stroke
				(width 0)
				(type default)
			)
			(fill no)
			(layer "B.CrtYd")
		)
		(fp_line
			(start 0.508 0.3048)
			(end -0.508 0.3048)
			(stroke
				(width 0.1)
				(type default)
			)
			(layer "B.Fab")
		)
		(fp_line
			(start 0.508 -0.3048)
			(end 0.508 0.3048)
			(stroke
				(width 0.1)
				(type default)
			)
			(layer "B.Fab")
		)
		(fp_line
			(start -0.508 0.3048)
			(end -0.508 -0.3048)
			(stroke
				(width 0.1)
				(type default)
			)
			(layer "B.Fab")
		)
		(fp_line
			(start -0.508 -0.3048)
			(end 0.508 -0.3048)
			(stroke
				(width 0.1)
				(type default)
			)
			(layer "B.Fab")
		)
		(pad "1" smd rect
			(at 0.5334 0)
			(size 0.7112 0.6096)
			(layers "B.Cu" "B.Mask" "B.Paste")
			(net "XP12R0V_A_FLTB")
		)
		(pad "2" smd rect
			(at -0.5334 0)
			(size 0.7112 0.6096)
			(layers "B.Cu" "B.Mask" "B.Paste")
			(net "SG")
		)
		(zone
			(layer "B.Cu")
			(hatch none 0.5)
			(connect_pads
				(clearance 0)
			)
			(min_thickness 0.25)
			(keepout
				(tracks allowed)
				(vias not_allowed)
				(pads allowed)
				(copperpour not_allowed)
				(footprints allowed)
			)
			(placement
				(enabled no)
				(sheetname "")
			)
			(fill
				(thermal_gap 0.5)
				(thermal_bridge_width 0.5)
				(island_removal_mode 0)
			)
			(polygon
				(pts
					(xy 145.7452 -98.933) (xy 145.8976 -98.933) (xy 145.8976 -99.5426) (xy 145.7452 -99.5426)
				)
			)
		)
	)
	(footprint ""
		(layer "B.Cu")
		(at 63.784988 -15.367 -90)
		(property "Reference" "C25"
			(at 2.032 -0.191262 270)
			(unlocked yes)
			(layer "B.SilkS")
			(effects
				(font
					(size 0.635 0.4064)
					(thickness 0.1524)
				)
				(justify mirror)
			)
		)
		(property "Value" "VAL*"
			(at -0.0762 2.067306 270)
			(unlocked yes)
			(layer "B.Fab")
			(hide yes)
			(effects
				(font
					(size 0.7874 0.5842)
					(thickness 0.1524)
				)
				(justify mirror)
			)
		)
		(property "Tolerance" "TOL*"
			(at -0.0762 3.032506 270)
			(unlocked yes)
			(layer "Cmts.User")
			(hide yes)
			(effects
				(font
					(size 0.7874 0.5842)
					(thickness 0.1524)
				)
				(justify mirror)
			)
		)
		(property "User Part Number" "PARTNUM*"
			(at -0.1016 4.023106 270)
			(unlocked yes)
			(layer "Cmts.User")
			(hide yes)
			(effects
				(font
					(size 0.7874 0.5842)
					(thickness 0.1524)
				)
				(justify mirror)
			)
		)
		(property "Device Type" "CAPACITOR-G105-0B104-CK,0.1UF,A"
			(at -0.0508 1.127506 270)
			(unlocked yes)
			(layer "B.Fab")
			(hide yes)
			(effects
				(font
					(size 0.7874 0.5842)
					(thickness 0.1524)
				)
				(justify mirror)
			)
		)
		(duplicate_pad_numbers_are_jumpers no)
		(fp_line
			(start -1.143 0.5588)
			(end -1.143 -0.5588)
			(stroke
				(width 0.1)
				(type default)
			)
			(layer "B.SilkS")
		)
		(fp_line
			(start 1.143 0.5588)
			(end -1.143 0.5588)
			(stroke
				(width 0.1)
				(type default)
			)
			(layer "B.SilkS")
		)
		(fp_line
			(start -1.143 -0.5588)
			(end 1.143 -0.5588)
			(stroke
				(width 0.1)
				(type default)
			)
			(layer "B.SilkS")
		)
		(fp_line
			(start 1.143 -0.5588)
			(end 1.143 0.5588)
			(stroke
				(width 0.1)
				(type default)
			)
			(layer "B.SilkS")
		)
		(fp_rect
			(start 1.143 0.5588)
			(end -1.143 -0.5588)
			(stroke
				(width 0)
				(type default)
			)
			(fill no)
			(layer "B.CrtYd")
		)
		(fp_line
			(start -0.508 0.3048)
			(end -0.508 -0.3048)
			(stroke
				(width 0.1)
				(type default)
			)
			(layer "B.Fab")
		)
		(fp_line
			(start 0.508 0.3048)
			(end -0.508 0.3048)
			(stroke
				(width 0.1)
				(type default)
			)
			(layer "B.Fab")
		)
		(fp_line
			(start -0.508 -0.3048)
			(end 0.508 -0.3048)
			(stroke
				(width 0.1)
				(type default)
			)
			(layer "B.Fab")
		)
		(fp_line
			(start 0.508 -0.3048)
			(end 0.508 0.3048)
			(stroke
				(width 0.1)
				(type default)
			)
			(layer "B.Fab")
		)
		(pad "1" smd rect
			(at 0.5334 0 90)
			(size 0.7112 0.6096)
			(layers "B.Cu" "B.Mask" "B.Paste")
			(net "C_CPU_RX_PCIE_MGT0_TXN")
		)
		(pad "2" smd rect
			(at -0.5334 0 90)
			(size 0.7112 0.6096)
			(layers "B.Cu" "B.Mask" "B.Paste")
			(net "CPU_RX_PCIE_MGT0_TXN")
		)
		(zone
			(layer "B.Cu")
			(hatch none 0.5)
			(connect_pads
				(clearance 0)
			)
			(min_thickness 0.25)
			(keepout
				(tracks allowed)
				(vias not_allowed)
				(pads allowed)
				(copperpour not_allowed)
				(footprints allowed)
			)
			(placement
				(enabled no)
				(sheetname "")
			)
			(fill
				(thermal_gap 0.5)
				(thermal_bridge_width 0.5)
				(island_removal_mode 0)
			)
			(polygon
				(pts
					(xy 63.480188 -15.2908) (xy 64.089788 -15.2908) (xy 64.089788 -15.4432) (xy 63.480188 -15.4432)
				)
			)
		)
	)
	(footprint ""
		(layer "B.Cu")
		(at 145.288 -50.546 180)
		(property "Reference" "R253"
			(at -0.254 -1.81737 0)
			(unlocked yes)
			(layer "B.SilkS")
			(effects
				(font
					(size 0.7874 0.5842)
					(thickness 0.1524)
				)
				(justify mirror)
			)
		)
		(property "Value" "VAL*"
			(at -0.0508 3.159506 180)
			(unlocked yes)
			(layer "B.Fab")
			(hide yes)
			(effects
				(font
					(size 0.7874 0.5842)
					(thickness 0.1524)
				)
				(justify mirror)
			)
		)
		(property "Tolerance" "TOL*"
			(at -0.0508 4.124706 180)
			(unlocked yes)
			(layer "Cmts.User")
			(hide yes)
			(effects
				(font
					(size 0.7874 0.5842)
					(thickness 0.1524)
				)
				(justify mirror)
			)
		)
		(property "User Part Number" "PARTNUM*"
			(at -0.0508 5.089906 180)
			(unlocked yes)
			(layer "Cmts.User")
			(hide yes)
			(effects
				(font
					(size 0.7874 0.5842)
					(thickness 0.1524)
				)
				(justify mirror)
			)
		)
		(property "Device Type" "RESISTOR-G157-12R20-01,2.2OHM,A"
			(at 0 2.194306 180)
			(unlocked yes)
			(layer "B.Fab")
			(hide yes)
			(effects
				(font
					(size 0.7874 0.5842)
					(thickness 0.1524)
				)
				(justify mirror)
			)
		)
		(duplicate_pad_numbers_are_jumpers no)
		(fp_line
			(start 1.5748 0.9398)
			(end -1.5748 0.9398)
			(stroke
				(width 0.1)
				(type default)
			)
			(layer "B.SilkS")
		)
		(fp_line
			(start 1.5748 -0.9398)
			(end 1.5748 0.9398)
			(stroke
				(width 0.1)
				(type default)
			)
			(layer "B.SilkS")
		)
		(fp_line
			(start -1.5748 0.9398)
			(end -1.5748 -0.9398)
			(stroke
				(width 0.1)
				(type default)
			)
			(layer "B.SilkS")
		)
		(fp_line
			(start -1.5748 -0.9398)
			(end 1.5748 -0.9398)
			(stroke
				(width 0.1)
				(type default)
			)
			(layer "B.SilkS")
		)
		(fp_rect
			(start -1.5748 -0.9398)
			(end 1.5748 0.9398)
			(stroke
				(width 0)
				(type default)
			)
			(fill no)
			(layer "B.CrtYd")
		)
		(fp_line
			(start 1.016 0.635)
			(end -1.016 0.635)
			(stroke
				(width 0.1)
				(type default)
			)
			(layer "B.Fab")
		)
		(fp_line
			(start 1.016 -0.635)
			(end 1.016 0.635)
			(stroke
				(width 0.1)
				(type default)
			)
			(layer "B.Fab")
		)
		(fp_line
			(start -1.016 0.635)
			(end -1.016 -0.635)
			(stroke
				(width 0.1)
				(type default)
			)
			(layer "B.Fab")
		)
		(fp_line
			(start -1.016 -0.635)
			(end 1.016 -0.635)
			(stroke
				(width 0.1)
				(type default)
			)
			(layer "B.Fab")
		)
		(pad "1" smd rect
			(at 0.8382 0)
			(size 0.9652 1.3716)
			(layers "B.Cu" "B.Mask" "B.Paste")
			(net "UNNAMED_523_CAPACITOR_I31_2")
		)
		(pad "2" smd rect
			(at -0.8382 0)
			(size 0.9652 1.3716)
			(layers "B.Cu" "B.Mask" "B.Paste")
			(net "SG")
		)
		(zone
			(layer "B.Cu")
			(hatch none 0.5)
			(connect_pads
				(clearance 0)
			)
			(min_thickness 0.25)
			(keepout
				(tracks allowed)
				(vias not_allowed)
				(pads allowed)
				(copperpour not_allowed)
				(footprints allowed)
			)
			(placement
				(enabled no)
				(sheetname "")
			)
			(fill
				(thermal_gap 0.5)
				(thermal_bridge_width 0.5)
				(island_removal_mode 0)
			)
			(polygon
				(pts
					(xy 145.5166 -49.911) (xy 145.5166 -51.181) (xy 145.0594 -51.181) (xy 145.0594 -49.911)
				)
			)
		)
	)
	(footprint ""
		(layer "B.Cu")
		(at 137.16 -46.228 -90)
		(property "Reference" "C179"
			(at 0 -1.87833 270)
			(unlocked yes)
			(layer "B.SilkS")
			(effects
				(font
					(size 0.7874 0.5842)
					(thickness 0.1524)
				)
				(justify mirror)
			)
		)
		(property "Value" "VAL*"
			(at -0.0762 3.134106 270)
			(unlocked yes)
			(layer "B.Fab")
			(hide yes)
			(effects
				(font
					(size 0.7874 0.5842)
					(thickness 0.1524)
				)
				(justify mirror)
			)
		)
		(property "Tolerance" "TOL*"
			(at -0.0762 4.048506 270)
			(unlocked yes)
			(layer "Cmts.User")
			(hide yes)
			(effects
				(font
					(size 0.7874 0.5842)
					(thickness 0.1524)
				)
				(justify mirror)
			)
		)
		(property "User Part Number" "PARTNUM*"
			(at -0.1016 5.013706 270)
			(unlocked yes)
			(layer "Cmts.User")
			(hide yes)
			(effects
				(font
					(size 0.7874 0.5842)
					(thickness 0.1524)
				)
				(justify mirror)
			)
		)
		(property "Device Type" "CAPACITOR-G107-0F476-AM,47UF,2A"
			(at -0.0508 2.194306 270)
			(unlocked yes)
			(layer "B.Fab")
			(hide yes)
			(effects
				(font
					(size 0.7874 0.5842)
					(thickness 0.1524)
				)
				(justify mirror)
			)
		)
		(duplicate_pad_numbers_are_jumpers no)
		(fp_line
			(start -1.5748 0.9398)
			(end -1.5748 -0.9398)
			(stroke
				(width 0.1)
				(type default)
			)
			(layer "B.SilkS")
		)
		(fp_line
			(start 1.5748 0.9398)
			(end -1.5748 0.9398)
			(stroke
				(width 0.1)
				(type default)
			)
			(layer "B.SilkS")
		)
		(fp_line
			(start -1.5748 -0.9398)
			(end 1.5748 -0.9398)
			(stroke
				(width 0.1)
				(type default)
			)
			(layer "B.SilkS")
		)
		(fp_line
			(start 1.5748 -0.9398)
			(end 1.5748 0.9398)
			(stroke
				(width 0.1)
				(type default)
			)
			(layer "B.SilkS")
		)
		(fp_rect
			(start 1.5748 0.9398)
			(end -1.5748 -0.9398)
			(stroke
				(width 0)
				(type default)
			)
			(fill no)
			(layer "B.CrtYd")
		)
		(fp_line
			(start -1.016 0.635)
			(end -1.016 -0.635)
			(stroke
				(width 0.1)
				(type default)
			)
			(layer "B.Fab")
		)
		(fp_line
			(start 1.016 0.635)
			(end -1.016 0.635)
			(stroke
				(width 0.1)
				(type default)
			)
			(layer "B.Fab")
		)
		(fp_line
			(start -1.016 -0.635)
			(end 1.016 -0.635)
			(stroke
				(width 0.1)
				(type default)
			)
			(layer "B.Fab")
		)
		(fp_line
			(start 1.016 -0.635)
			(end 1.016 0.635)
			(stroke
				(width 0.1)
				(type default)
			)
			(layer "B.Fab")
		)
		(pad "1" smd rect
			(at 0.8382 0 90)
			(size 0.9652 1.3716)
			(layers "B.Cu" "B.Mask" "B.Paste")
			(net "XP1R0V_FPGA")
		)
		(pad "2" smd rect
			(at -0.8382 0 90)
			(size 0.9652 1.3716)
			(layers "B.Cu" "B.Mask" "B.Paste")
			(net "SG")
		)
		(zone
			(layer "B.Cu")
			(hatch none 0.5)
			(connect_pads
				(clearance 0)
			)
			(min_thickness 0.25)
			(keepout
				(tracks allowed)
				(vias not_allowed)
				(pads allowed)
				(copperpour not_allowed)
				(footprints allowed)
			)
			(placement
				(enabled no)
				(sheetname "")
			)
			(fill
				(thermal_gap 0.5)
				(thermal_bridge_width 0.5)
				(island_removal_mode 0)
			)
			(polygon
				(pts
					(xy 136.525 -45.9994) (xy 137.795 -45.9994) (xy 137.795 -46.4566) (xy 136.525 -46.4566)
				)
			)
		)
	)
	(footprint ""
		(layer "B.Cu")
		(at 111.847122 -40.323008 90)
		(property "Reference" "C171"
			(at -1.397508 -42.018712 270)
			(unlocked yes)
			(layer "B.SilkS")
			(effects
				(font
					(size 0.635 0.4064)
					(thickness 0.1524)
				)
				(justify mirror)
			)
		)
		(property "Value" "VAL*"
			(at 0 3.718306 90)
			(unlocked yes)
			(layer "B.Fab")
			(hide yes)
			(effects
				(font
					(size 0.7874 0.5842)
					(thickness 0.127)
				)
				(justify mirror)
			)
		)
		(property "Tolerance" "TOL*"
			(at 0 4.861306 90)
			(unlocked yes)
			(layer "Cmts.User")
			(hide yes)
			(effects
				(font
					(size 0.7874 0.5842)
					(thickness 0.127)
				)
				(justify mirror)
			)
		)
		(property "User Part Number" "PARTNUM*"
			(at 0 2.575306 90)
			(unlocked yes)
			(layer "Cmts.User")
			(hide yes)
			(effects
				(font
					(size 0.7874 0.5842)
					(thickness 0.127)
				)
				(justify mirror)
			)
		)
		(property "Device Type" "CAPACITOR-G105-0B104-CK,0.1UF,A"
			(at 0 1.432306 90)
			(unlocked yes)
			(layer "B.Fab")
			(hide yes)
			(effects
				(font
					(size 0.7874 0.5842)
					(thickness 0.127)
				)
				(justify mirror)
			)
		)
		(duplicate_pad_numbers_are_jumpers no)
		(fp_line
			(start 0.970026 -0.4699)
			(end -0.970026 -0.4699)
			(stroke
				(width 0.1)
				(type default)
			)
			(layer "B.SilkS")
		)
		(fp_line
			(start -0.970026 -0.4699)
			(end -0.970026 0.4699)
			(stroke
				(width 0.1)
				(type default)
			)
			(layer "B.SilkS")
		)
		(fp_line
			(start 0.970026 0.4699)
			(end 0.970026 -0.4699)
			(stroke
				(width 0.1)
				(type default)
			)
			(layer "B.SilkS")
		)
		(fp_line
			(start -0.970026 0.4699)
			(end 0.970026 0.4699)
			(stroke
				(width 0.1)
				(type default)
			)
			(layer "B.SilkS")
		)
		(fp_poly
			(pts
				(xy 0.970026 0.4699) (xy -0.970026 0.4699) (xy -0.970026 -0.4699) (xy 0.970026 -0.4699)
			)
			(stroke
				(width 0)
				(type default)
			)
			(fill no)
			(layer "B.CrtYd")
		)
		(fp_line
			(start 0.508 -0.3048)
			(end -0.508 -0.3048)
			(stroke
				(width 0.1)
				(type default)
			)
			(layer "B.Fab")
		)
		(fp_line
			(start -0.508 -0.3048)
			(end -0.508 0.3048)
			(stroke
				(width 0.1)
				(type default)
			)
			(layer "B.Fab")
		)
		(fp_line
			(start 0.508 0.3048)
			(end 0.508 -0.3048)
			(stroke
				(width 0.1)
				(type default)
			)
			(layer "B.Fab")
		)
		(fp_line
			(start -0.508 0.3048)
			(end 0.508 0.3048)
			(stroke
				(width 0.1)
				(type default)
			)
			(layer "B.Fab")
		)
		(pad "1" smd circle
			(at 0.500126 0 270)
			(size 0.635 0.635)
			(layers "B.Cu" "B.Mask" "B.Paste")
			(net "XP1R0V_FPGA_VCCINT")
		)
		(pad "2" smd circle
			(at -0.500126 0 270)
			(size 0.635 0.635)
			(layers "B.Cu" "B.Mask" "B.Paste")
			(net "SG")
		)
	)
	(footprint ""
		(layer "B.Cu")
		(at 100.346764 -51.823112)
		(property "Reference" "C157"
			(at -2.175764 0.038862 0)
			(unlocked yes)
			(layer "B.SilkS")
			(effects
				(font
					(size 0.635 0.4064)
					(thickness 0.1524)
				)
				(justify mirror)
			)
		)
		(property "Value" "VAL*"
			(at 0 3.718306 0)
			(unlocked yes)
			(layer "B.Fab")
			(hide yes)
			(effects
				(font
					(size 0.7874 0.5842)
					(thickness 0.127)
				)
				(justify mirror)
			)
		)
		(property "Device Type" "CAPACITOR-G105-0B104-CK,0.1UF,A"
			(at 0 1.432306 0)
			(unlocked yes)
			(layer "B.Fab")
			(hide yes)
			(effects
				(font
					(size 0.7874 0.5842)
					(thickness 0.127)
				)
				(justify mirror)
			)
		)
		(property "User Part Number" "PARTNUM*"
			(at 0 2.575306 0)
			(unlocked yes)
			(layer "Cmts.User")
			(hide yes)
			(effects
				(font
					(size 0.7874 0.5842)
					(thickness 0.127)
				)
				(justify mirror)
			)
		)
		(property "Tolerance" "TOL*"
			(at 0 4.861306 0)
			(unlocked yes)
			(layer "Cmts.User")
			(hide yes)
			(effects
				(font
					(size 0.7874 0.5842)
					(thickness 0.127)
				)
				(justify mirror)
			)
		)
		(duplicate_pad_numbers_are_jumpers no)
		(fp_line
			(start -0.970026 -0.4699)
			(end -0.970026 0.4699)
			(stroke
				(width 0.1)
				(type default)
			)
			(layer "B.SilkS")
		)
		(fp_line
			(start -0.970026 0.4699)
			(end 0.970026 0.4699)
			(stroke
				(width 0.1)
				(type default)
			)
			(layer "B.SilkS")
		)
		(fp_line
			(start 0.970026 -0.4699)
			(end -0.970026 -0.4699)
			(stroke
				(width 0.1)
				(type default)
			)
			(layer "B.SilkS")
		)
		(fp_line
			(start 0.970026 0.4699)
			(end 0.970026 -0.4699)
			(stroke
				(width 0.1)
				(type default)
			)
			(layer "B.SilkS")
		)
		(fp_poly
			(pts
				(xy 0.970026 0.4699) (xy -0.970026 0.4699) (xy -0.970026 -0.4699) (xy 0.970026 -0.4699)
			)
			(stroke
				(width 0)
				(type default)
			)
			(fill no)
			(layer "B.CrtYd")
		)
		(fp_line
			(start -0.508 -0.3048)
			(end -0.508 0.3048)
			(stroke
				(width 0.1)
				(type default)
			)
			(layer "B.Fab")
		)
		(fp_line
			(start -0.508 0.3048)
			(end 0.508 0.3048)
			(stroke
				(width 0.1)
				(type default)
			)
			(layer "B.Fab")
		)
		(fp_line
			(start 0.508 -0.3048)
			(end -0.508 -0.3048)
			(stroke
				(width 0.1)
				(type default)
			)
			(layer "B.Fab")
		)
		(fp_line
			(start 0.508 0.3048)
			(end 0.508 -0.3048)
			(stroke
				(width 0.1)
				(type default)
			)
			(layer "B.Fab")
		)
		(pad "1" smd circle
			(at 0.500126 0 180)
			(size 0.635 0.635)
			(layers "B.Cu" "B.Mask" "B.Paste")
			(net "XP3R3V_FPGA")
		)
		(pad "2" smd circle
			(at -0.500126 0 180)
			(size 0.635 0.635)
			(layers "B.Cu" "B.Mask" "B.Paste")
			(net "SG")
		)
	)
	(footprint ""
		(layer "B.Cu")
		(at 105.41 -64.2874 90)
		(property "Reference" "R328"
			(at 3.5306 -0.16637 270)
			(unlocked yes)
			(layer "B.SilkS")
			(effects
				(font
					(size 0.7874 0.5842)
					(thickness 0.1524)
				)
				(justify mirror)
			)
		)
		(property "Value" "VAL*"
			(at -0.02032 2.13233 90)
			(unlocked yes)
			(layer "B.Fab")
			(hide yes)
			(effects
				(font
					(size 0.7874 0.5842)
					(thickness 0.1524)
				)
				(justify mirror)
			)
		)
		(property "Tolerance" "TOL*"
			(at -0.044704 3.05435 90)
			(unlocked yes)
			(layer "Cmts.User")
			(hide yes)
			(effects
				(font
					(size 0.7874 0.5842)
					(thickness 0.1524)
				)
				(justify mirror)
			)
		)
		(property "User Part Number" "PARTNUM*"
			(at -0.02032 4.024884 90)
			(unlocked yes)
			(layer "Cmts.User")
			(hide yes)
			(effects
				(font
					(size 0.7874 0.5842)
					(thickness 0.1524)
				)
				(justify mirror)
			)
		)
		(property "Device Type" "RESISTOR-G155-14701-01,4.7KOHMA"
			(at -0.008382 1.210564 90)
			(unlocked yes)
			(layer "B.Fab")
			(hide yes)
			(effects
				(font
					(size 0.7874 0.5842)
					(thickness 0.1524)
				)
				(justify mirror)
			)
		)
		(duplicate_pad_numbers_are_jumpers no)
		(fp_line
			(start 1.143 -0.5588)
			(end 1.143 0.5588)
			(stroke
				(width 0.1)
				(type default)
			)
			(layer "B.SilkS")
		)
		(fp_line
			(start -1.143 -0.5588)
			(end 1.143 -0.5588)
			(stroke
				(width 0.1)
				(type default)
			)
			(layer "B.SilkS")
		)
		(fp_line
			(start 1.143 0.5588)
			(end -1.143 0.5588)
			(stroke
				(width 0.1)
				(type default)
			)
			(layer "B.SilkS")
		)
		(fp_line
			(start -1.143 0.5588)
			(end -1.143 -0.5588)
			(stroke
				(width 0.1)
				(type default)
			)
			(layer "B.SilkS")
		)
		(fp_poly
			(pts
				(xy 1.143 0.5588) (xy -1.143 0.5588) (xy -1.143 -0.5588) (xy 1.143 -0.5588)
			)
			(stroke
				(width 0)
				(type default)
			)
			(fill no)
			(layer "B.CrtYd")
		)
		(fp_line
			(start 0.508 -0.3048)
			(end 0.508 0.3048)
			(stroke
				(width 0.1)
				(type default)
			)
			(layer "B.Fab")
		)
		(fp_line
			(start -0.508 -0.3048)
			(end 0.508 -0.3048)
			(stroke
				(width 0.1)
				(type default)
			)
			(layer "B.Fab")
		)
		(fp_line
			(start 0.508 0.3048)
			(end -0.508 0.3048)
			(stroke
				(width 0.1)
				(type default)
			)
			(layer "B.Fab")
		)
		(fp_line
			(start -0.508 0.3048)
			(end -0.508 -0.3048)
			(stroke
				(width 0.1)
				(type default)
			)
			(layer "B.Fab")
		)
		(pad "1" smd rect
			(at 0.5334 0 270)
			(size 0.7112 0.6096)
			(layers "B.Cu" "B.Mask" "B.Paste")
			(net "SG")
		)
		(pad "2" smd rect
			(at -0.5334 0 270)
			(size 0.7112 0.6096)
			(layers "B.Cu" "B.Mask" "B.Paste")
			(net "FPGA_IO_7")
		)
		(zone
			(layer "B.Cu")
			(hatch none 0.5)
			(connect_pads
				(clearance 0)
			)
			(min_thickness 0.25)
			(keepout
				(tracks allowed)
				(vias not_allowed)
				(pads allowed)
				(copperpour not_allowed)
				(footprints allowed)
			)
			(placement
				(enabled no)
				(sheetname "")
			)
			(fill
				(thermal_gap 0.5)
				(thermal_bridge_width 0.5)
				(island_removal_mode 0)
			)
			(polygon
				(pts
					(xy 105.7148 -64.3636) (xy 105.1052 -64.3636) (xy 105.1052 -64.2112) (xy 105.7148 -64.2112)
				)
			)
		)
		(zone
			(layer "B.Cu")
			(hatch none 0.5)
			(connect_pads
				(clearance 0)
			)
			(min_thickness 0.25)
			(keepout
				(tracks not_allowed)
				(vias allowed)
				(pads allowed)
				(copperpour not_allowed)
				(footprints allowed)
			)
			(placement
				(enabled no)
				(sheetname "")
			)
			(fill
				(thermal_gap 0.5)
				(thermal_bridge_width 0.5)
				(island_removal_mode 0)
			)
			(polygon
				(pts
					(xy 105.7148 -64.3636) (xy 105.1052 -64.3636) (xy 105.1052 -64.2112) (xy 105.7148 -64.2112)
				)
			)
		)
	)
	(footprint ""
		(layer "B.Cu")
		(at 125.349 -89.535 -90)
		(property "Reference" "R110"
			(at -3.683 -0.08763 270)
			(unlocked yes)
			(layer "B.SilkS")
			(effects
				(font
					(size 0.7874 0.5842)
					(thickness 0.1524)
				)
				(justify mirror)
			)
		)
		(property "Value" "VAL*"
			(at -0.02032 2.13233 270)
			(unlocked yes)
			(layer "B.Fab")
			(hide yes)
			(effects
				(font
					(size 0.7874 0.5842)
					(thickness 0.1524)
				)
				(justify mirror)
			)
		)
		(property "Device Type" "RESISTOR-G155-133R0-01,33OHM,1%"
			(at -0.008382 1.210564 270)
			(unlocked yes)
			(layer "B.Fab")
			(hide yes)
			(effects
				(font
					(size 0.7874 0.5842)
					(thickness 0.1524)
				)
				(justify mirror)
			)
		)
		(property "User Part Number" "PARTNUM*"
			(at -0.02032 4.024884 270)
			(unlocked yes)
			(layer "Cmts.User")
			(hide yes)
			(effects
				(font
					(size 0.7874 0.5842)
					(thickness 0.1524)
				)
				(justify mirror)
			)
		)
		(property "Tolerance" "TOL*"
			(at -0.044704 3.05435 270)
			(unlocked yes)
			(layer "Cmts.User")
			(hide yes)
			(effects
				(font
					(size 0.7874 0.5842)
					(thickness 0.1524)
				)
				(justify mirror)
			)
		)
		(duplicate_pad_numbers_are_jumpers no)
		(fp_line
			(start -1.143 0.5588)
			(end -1.143 -0.5588)
			(stroke
				(width 0.1)
				(type default)
			)
			(layer "B.SilkS")
		)
		(fp_line
			(start 1.143 0.5588)
			(end -1.143 0.5588)
			(stroke
				(width 0.1)
				(type default)
			)
			(layer "B.SilkS")
		)
		(fp_line
			(start -1.143 -0.5588)
			(end 1.143 -0.5588)
			(stroke
				(width 0.1)
				(type default)
			)
			(layer "B.SilkS")
		)
		(fp_line
			(start 1.143 -0.5588)
			(end 1.143 0.5588)
			(stroke
				(width 0.1)
				(type default)
			)
			(layer "B.SilkS")
		)
		(fp_rect
			(start -1.143 -0.5588)
			(end 1.143 0.5588)
			(stroke
				(width 0)
				(type default)
			)
			(fill no)
			(layer "B.CrtYd")
		)
		(fp_line
			(start -0.508 0.3048)
			(end -0.508 -0.3048)
			(stroke
				(width 0.1)
				(type default)
			)
			(layer "B.Fab")
		)
		(fp_line
			(start 0.508 0.3048)
			(end -0.508 0.3048)
			(stroke
				(width 0.1)
				(type default)
			)
			(layer "B.Fab")
		)
		(fp_line
			(start -0.508 -0.3048)
			(end 0.508 -0.3048)
			(stroke
				(width 0.1)
				(type default)
			)
			(layer "B.Fab")
		)
		(fp_line
			(start 0.508 -0.3048)
			(end 0.508 0.3048)
			(stroke
				(width 0.1)
				(type default)
			)
			(layer "B.Fab")
		)
		(pad "1" smd rect
			(at 0.5334 0 90)
			(size 0.7112 0.6096)
			(layers "B.Cu" "B.Mask" "B.Paste")
			(net "UART_GPS_RX_FPGA_TX")
		)
		(pad "2" smd rect
			(at -0.5334 0 90)
			(size 0.7112 0.6096)
			(layers "B.Cu" "B.Mask" "B.Paste")
			(net "GPS_UART_RXD")
		)
		(zone
			(layer "B.Cu")
			(hatch none 0.5)
			(connect_pads
				(clearance 0)
			)
			(min_thickness 0.25)
			(keepout
				(tracks allowed)
				(vias not_allowed)
				(pads allowed)
				(copperpour not_allowed)
				(footprints allowed)
			)
			(placement
				(enabled no)
				(sheetname "")
			)
			(fill
				(thermal_gap 0.5)
				(thermal_bridge_width 0.5)
				(island_removal_mode 0)
			)
			(polygon
				(pts
					(xy 125.6538 -89.6112) (xy 125.0442 -89.6112) (xy 125.0442 -89.4588) (xy 125.6538 -89.4588)
				)
			)
		)
	)
	(footprint ""
		(layer "B.Cu")
		(at 70.993 -47.2186 -90)
		(property "Reference" "R90"
			(at -0.0254 1.05537 270)
			(unlocked yes)
			(layer "B.SilkS")
			(effects
				(font
					(size 0.7874 0.5842)
					(thickness 0.1524)
				)
				(justify mirror)
			)
		)
		(property "Value" "VAL*"
			(at -0.02032 2.13233 270)
			(unlocked yes)
			(layer "B.Fab")
			(hide yes)
			(effects
				(font
					(size 0.7874 0.5842)
					(thickness 0.1524)
				)
				(justify mirror)
			)
		)
		(property "Device Type" "RESISTOR-G155-11000-01,100OHM,A"
			(at -0.008382 1.210564 270)
			(unlocked yes)
			(layer "B.Fab")
			(hide yes)
			(effects
				(font
					(size 0.7874 0.5842)
					(thickness 0.1524)
				)
				(justify mirror)
			)
		)
		(property "User Part Number" "PARTNUM*"
			(at -0.02032 4.024884 270)
			(unlocked yes)
			(layer "Cmts.User")
			(hide yes)
			(effects
				(font
					(size 0.7874 0.5842)
					(thickness 0.1524)
				)
				(justify mirror)
			)
		)
		(property "Tolerance" "TOL*"
			(at -0.044704 3.05435 270)
			(unlocked yes)
			(layer "Cmts.User")
			(hide yes)
			(effects
				(font
					(size 0.7874 0.5842)
					(thickness 0.1524)
				)
				(justify mirror)
			)
		)
		(duplicate_pad_numbers_are_jumpers no)
		(fp_line
			(start -1.143 0.5588)
			(end -1.143 -0.5588)
			(stroke
				(width 0.1)
				(type default)
			)
			(layer "B.SilkS")
		)
		(fp_line
			(start 1.143 0.5588)
			(end -1.143 0.5588)
			(stroke
				(width 0.1)
				(type default)
			)
			(layer "B.SilkS")
		)
		(fp_line
			(start -1.143 -0.5588)
			(end 1.143 -0.5588)
			(stroke
				(width 0.1)
				(type default)
			)
			(layer "B.SilkS")
		)
		(fp_line
			(start 1.143 -0.5588)
			(end 1.143 0.5588)
			(stroke
				(width 0.1)
				(type default)
			)
			(layer "B.SilkS")
		)
		(fp_rect
			(start 1.143 -0.5588)
			(end -1.143 0.5588)
			(stroke
				(width 0)
				(type default)
			)
			(fill no)
			(layer "B.CrtYd")
		)
		(fp_line
			(start -0.508 0.3048)
			(end -0.508 -0.3048)
			(stroke
				(width 0.1)
				(type default)
			)
			(layer "B.Fab")
		)
		(fp_line
			(start 0.508 0.3048)
			(end -0.508 0.3048)
			(stroke
				(width 0.1)
				(type default)
			)
			(layer "B.Fab")
		)
		(fp_line
			(start -0.508 -0.3048)
			(end 0.508 -0.3048)
			(stroke
				(width 0.1)
				(type default)
			)
			(layer "B.Fab")
		)
		(fp_line
			(start 0.508 -0.3048)
			(end 0.508 0.3048)
			(stroke
				(width 0.1)
				(type default)
			)
			(layer "B.Fab")
		)
		(pad "1" smd rect
			(at 0.5334 0 90)
			(size 0.7112 0.6096)
			(layers "B.Cu" "B.Mask" "B.Paste")
			(net "R_MAC_PPS_IN0N")
		)
		(pad "2" smd rect
			(at -0.5334 0 90)
			(size 0.7112 0.6096)
			(layers "B.Cu" "B.Mask" "B.Paste")
			(net "R_MAC_PPS_IN0P")
		)
		(zone
			(layer "B.Cu")
			(hatch none 0.5)
			(connect_pads
				(clearance 0)
			)
			(min_thickness 0.25)
			(keepout
				(tracks allowed)
				(vias not_allowed)
				(pads allowed)
				(copperpour not_allowed)
				(footprints allowed)
			)
			(placement
				(enabled no)
				(sheetname "")
			)
			(fill
				(thermal_gap 0.5)
				(thermal_bridge_width 0.5)
				(island_removal_mode 0)
			)
			(polygon
				(pts
					(xy 71.2978 -47.1424) (xy 71.2978 -47.2948) (xy 70.6882 -47.2948) (xy 70.6882 -47.1424)
				)
			)
		)
	)
	(footprint ""
		(layer "B.Cu")
		(at 5.588 -78.105 180)
		(property "Reference" "C39"
			(at 3.048 0.08763 0)
			(unlocked yes)
			(layer "B.SilkS")
			(effects
				(font
					(size 0.7874 0.5842)
					(thickness 0.1524)
				)
				(justify mirror)
			)
		)
		(property "Value" "VAL*"
			(at -0.0762 2.067306 180)
			(unlocked yes)
			(layer "B.Fab")
			(hide yes)
			(effects
				(font
					(size 0.7874 0.5842)
					(thickness 0.1524)
				)
				(justify mirror)
			)
		)
		(property "Tolerance" "TOL*"
			(at -0.0762 3.032506 180)
			(unlocked yes)
			(layer "Cmts.User")
			(hide yes)
			(effects
				(font
					(size 0.7874 0.5842)
					(thickness 0.1524)
				)
				(justify mirror)
			)
		)
		(property "User Part Number" "PARTNUM*"
			(at -0.1016 4.023106 180)
			(unlocked yes)
			(layer "Cmts.User")
			(hide yes)
			(effects
				(font
					(size 0.7874 0.5842)
					(thickness 0.1524)
				)
				(justify mirror)
			)
		)
		(property "Device Type" "CAPACITOR-G105-0B104-EK,0.1UF,A"
			(at -0.0508 1.127506 180)
			(unlocked yes)
			(layer "B.Fab")
			(hide yes)
			(effects
				(font
					(size 0.7874 0.5842)
					(thickness 0.1524)
				)
				(justify mirror)
			)
		)
		(duplicate_pad_numbers_are_jumpers no)
		(fp_line
			(start 1.143 0.5588)
			(end -1.143 0.5588)
			(stroke
				(width 0.1)
				(type default)
			)
			(layer "B.SilkS")
		)
		(fp_line
			(start 1.143 -0.5588)
			(end 1.143 0.5588)
			(stroke
				(width 0.1)
				(type default)
			)
			(layer "B.SilkS")
		)
		(fp_line
			(start -1.143 0.5588)
			(end -1.143 -0.5588)
			(stroke
				(width 0.1)
				(type default)
			)
			(layer "B.SilkS")
		)
		(fp_line
			(start -1.143 -0.5588)
			(end 1.143 -0.5588)
			(stroke
				(width 0.1)
				(type default)
			)
			(layer "B.SilkS")
		)
		(fp_rect
			(start -1.143 0.5588)
			(end 1.143 -0.5588)
			(stroke
				(width 0)
				(type default)
			)
			(fill no)
			(layer "B.CrtYd")
		)
		(fp_line
			(start 0.508 0.3048)
			(end -0.508 0.3048)
			(stroke
				(width 0.1)
				(type default)
			)
			(layer "B.Fab")
		)
		(fp_line
			(start 0.508 -0.3048)
			(end 0.508 0.3048)
			(stroke
				(width 0.1)
				(type default)
			)
			(layer "B.Fab")
		)
		(fp_line
			(start -0.508 0.3048)
			(end -0.508 -0.3048)
			(stroke
				(width 0.1)
				(type default)
			)
			(layer "B.Fab")
		)
		(fp_line
			(start -0.508 -0.3048)
			(end 0.508 -0.3048)
			(stroke
				(width 0.1)
				(type default)
			)
			(layer "B.Fab")
		)
		(pad "1" smd rect
			(at 0.5334 0)
			(size 0.7112 0.6096)
			(layers "B.Cu" "B.Mask" "B.Paste")
			(net "SG")
		)
		(pad "2" smd rect
			(at -0.5334 0)
			(size 0.7112 0.6096)
			(layers "B.Cu" "B.Mask" "B.Paste")
			(net "XP3R3V_FPGA")
		)
		(zone
			(layer "B.Cu")
			(hatch none 0.5)
			(connect_pads
				(clearance 0)
			)
			(min_thickness 0.25)
			(keepout
				(tracks allowed)
				(vias not_allowed)
				(pads allowed)
				(copperpour not_allowed)
				(footprints allowed)
			)
			(placement
				(enabled no)
				(sheetname "")
			)
			(fill
				(thermal_gap 0.5)
				(thermal_bridge_width 0.5)
				(island_removal_mode 0)
			)
			(polygon
				(pts
					(xy 5.6642 -78.4098) (xy 5.5118 -78.4098) (xy 5.5118 -77.8002) (xy 5.6642 -77.8002)
				)
			)
		)
	)
	(footprint ""
		(layer "B.Cu")
		(at 126.1364 -32.0802)
		(property "Reference" "C168"
			(at -0.127 2.07137 0)
			(unlocked yes)
			(layer "B.SilkS")
			(effects
				(font
					(size 0.7874 0.5842)
					(thickness 0.1524)
				)
				(justify mirror)
			)
		)
		(property "Value" "VAL*"
			(at -0.0762 3.134106 0)
			(unlocked yes)
			(layer "B.Fab")
			(hide yes)
			(effects
				(font
					(size 0.7874 0.5842)
					(thickness 0.1524)
				)
				(justify mirror)
			)
		)
		(property "Tolerance" "TOL*"
			(at -0.0762 4.048506 0)
			(unlocked yes)
			(layer "Cmts.User")
			(hide yes)
			(effects
				(font
					(size 0.7874 0.5842)
					(thickness 0.1524)
				)
				(justify mirror)
			)
		)
		(property "User Part Number" "PARTNUM*"
			(at -0.1016 5.013706 0)
			(unlocked yes)
			(layer "Cmts.User")
			(hide yes)
			(effects
				(font
					(size 0.7874 0.5842)
					(thickness 0.1524)
				)
				(justify mirror)
			)
		)
		(property "Device Type" "CAPACITOR-G107-0F226-CM,22UF,2A"
			(at -0.0508 2.194306 0)
			(unlocked yes)
			(layer "B.Fab")
			(hide yes)
			(effects
				(font
					(size 0.7874 0.5842)
					(thickness 0.1524)
				)
				(justify mirror)
			)
		)
		(duplicate_pad_numbers_are_jumpers no)
		(fp_line
			(start -1.5748 -0.9398)
			(end 1.5748 -0.9398)
			(stroke
				(width 0.1)
				(type default)
			)
			(layer "B.SilkS")
		)
		(fp_line
			(start -1.5748 0.9398)
			(end -1.5748 -0.9398)
			(stroke
				(width 0.1)
				(type default)
			)
			(layer "B.SilkS")
		)
		(fp_line
			(start 1.5748 -0.9398)
			(end 1.5748 0.9398)
			(stroke
				(width 0.1)
				(type default)
			)
			(layer "B.SilkS")
		)
		(fp_line
			(start 1.5748 0.9398)
			(end -1.5748 0.9398)
			(stroke
				(width 0.1)
				(type default)
			)
			(layer "B.SilkS")
		)
		(fp_rect
			(start -1.5748 -0.9398)
			(end 1.5748 0.9398)
			(stroke
				(width 0)
				(type default)
			)
			(fill no)
			(layer "B.CrtYd")
		)
		(fp_line
			(start -1.016 -0.635)
			(end 1.016 -0.635)
			(stroke
				(width 0.1)
				(type default)
			)
			(layer "B.Fab")
		)
		(fp_line
			(start -1.016 0.635)
			(end -1.016 -0.635)
			(stroke
				(width 0.1)
				(type default)
			)
			(layer "B.Fab")
		)
		(fp_line
			(start 1.016 -0.635)
			(end 1.016 0.635)
			(stroke
				(width 0.1)
				(type default)
			)
			(layer "B.Fab")
		)
		(fp_line
			(start 1.016 0.635)
			(end -1.016 0.635)
			(stroke
				(width 0.1)
				(type default)
			)
			(layer "B.Fab")
		)
		(pad "1" smd rect
			(at 0.8382 0 180)
			(size 0.9652 1.3716)
			(layers "B.Cu" "B.Mask" "B.Paste")
			(net "XP2R5V_FPGA")
		)
		(pad "2" smd rect
			(at -0.8382 0 180)
			(size 0.9652 1.3716)
			(layers "B.Cu" "B.Mask" "B.Paste")
			(net "SG")
		)
		(zone
			(layer "B.Cu")
			(hatch none 0.5)
			(connect_pads
				(clearance 0)
			)
			(min_thickness 0.25)
			(keepout
				(tracks allowed)
				(vias not_allowed)
				(pads allowed)
				(copperpour not_allowed)
				(footprints allowed)
			)
			(placement
				(enabled no)
				(sheetname "")
			)
			(fill
				(thermal_gap 0.5)
				(thermal_bridge_width 0.5)
				(island_removal_mode 0)
			)
			(polygon
				(pts
					(xy 125.9078 -32.7152) (xy 125.9078 -31.4452) (xy 126.365 -31.4452) (xy 126.365 -32.7152)
				)
			)
		)
	)
	(footprint ""
		(layer "B.Cu")
		(at 94.615 -43.688 180)
		(property "Reference" "R196"
			(at 3.556 0.08763 0)
			(unlocked yes)
			(layer "B.SilkS")
			(effects
				(font
					(size 0.7874 0.5842)
					(thickness 0.1524)
				)
				(justify mirror)
			)
		)
		(property "Value" "VAL*"
			(at -0.02032 2.13233 180)
			(unlocked yes)
			(layer "B.Fab")
			(hide yes)
			(effects
				(font
					(size 0.7874 0.5842)
					(thickness 0.1524)
				)
				(justify mirror)
			)
		)
		(property "Tolerance" "TOL*"
			(at -0.044704 3.05435 180)
			(unlocked yes)
			(layer "Cmts.User")
			(hide yes)
			(effects
				(font
					(size 0.7874 0.5842)
					(thickness 0.1524)
				)
				(justify mirror)
			)
		)
		(property "User Part Number" "PARTNUM*"
			(at -0.02032 4.024884 180)
			(unlocked yes)
			(layer "Cmts.User")
			(hide yes)
			(effects
				(font
					(size 0.7874 0.5842)
					(thickness 0.1524)
				)
				(justify mirror)
			)
		)
		(property "Device Type" "RESISTOR-G155-11000-01,100OHM,A"
			(at -0.008382 1.210564 180)
			(unlocked yes)
			(layer "B.Fab")
			(hide yes)
			(effects
				(font
					(size 0.7874 0.5842)
					(thickness 0.1524)
				)
				(justify mirror)
			)
		)
		(duplicate_pad_numbers_are_jumpers no)
		(fp_line
			(start 1.143 0.5588)
			(end -1.143 0.5588)
			(stroke
				(width 0.1)
				(type default)
			)
			(layer "B.SilkS")
		)
		(fp_line
			(start 1.143 -0.5588)
			(end 1.143 0.5588)
			(stroke
				(width 0.1)
				(type default)
			)
			(layer "B.SilkS")
		)
		(fp_line
			(start -1.143 0.5588)
			(end -1.143 -0.5588)
			(stroke
				(width 0.1)
				(type default)
			)
			(layer "B.SilkS")
		)
		(fp_line
			(start -1.143 -0.5588)
			(end 1.143 -0.5588)
			(stroke
				(width 0.1)
				(type default)
			)
			(layer "B.SilkS")
		)
		(fp_rect
			(start 1.143 -0.5588)
			(end -1.143 0.5588)
			(stroke
				(width 0)
				(type default)
			)
			(fill no)
			(layer "B.CrtYd")
		)
		(fp_line
			(start 0.508 0.3048)
			(end -0.508 0.3048)
			(stroke
				(width 0.1)
				(type default)
			)
			(layer "B.Fab")
		)
		(fp_line
			(start 0.508 -0.3048)
			(end 0.508 0.3048)
			(stroke
				(width 0.1)
				(type default)
			)
			(layer "B.Fab")
		)
		(fp_line
			(start -0.508 0.3048)
			(end -0.508 -0.3048)
			(stroke
				(width 0.1)
				(type default)
			)
			(layer "B.Fab")
		)
		(fp_line
			(start -0.508 -0.3048)
			(end 0.508 -0.3048)
			(stroke
				(width 0.1)
				(type default)
			)
			(layer "B.Fab")
		)
		(pad "1" smd rect
			(at 0.5334 0)
			(size 0.7112 0.6096)
			(layers "B.Cu" "B.Mask" "B.Paste")
			(net "FPGA_MGTAVTT")
		)
		(pad "2" smd rect
			(at -0.5334 0)
			(size 0.7112 0.6096)
			(layers "B.Cu" "B.Mask" "B.Paste")
			(net "FPGA_MGTRREF")
		)
		(zone
			(layer "B.Cu")
			(hatch none 0.5)
			(connect_pads
				(clearance 0)
			)
			(min_thickness 0.25)
			(keepout
				(tracks allowed)
				(vias not_allowed)
				(pads allowed)
				(copperpour not_allowed)
				(footprints allowed)
			)
			(placement
				(enabled no)
				(sheetname "")
			)
			(fill
				(thermal_gap 0.5)
				(thermal_bridge_width 0.5)
				(island_removal_mode 0)
			)
			(polygon
				(pts
					(xy 94.5388 -43.3832) (xy 94.6912 -43.3832) (xy 94.6912 -43.9928) (xy 94.5388 -43.9928)
				)
			)
		)
	)
	(footprint ""
		(layer "B.Cu")
		(at 70.866 -58.8518 90)
		(property "Reference" "C70"
			(at 2.6162 7.70763 270)
			(unlocked yes)
			(layer "B.SilkS")
			(effects
				(font
					(size 0.7874 0.5842)
					(thickness 0.1524)
				)
				(justify mirror)
			)
		)
		(property "Value" "VAL*"
			(at -0.0762 2.067306 90)
			(unlocked yes)
			(layer "B.Fab")
			(hide yes)
			(effects
				(font
					(size 0.7874 0.5842)
					(thickness 0.1524)
				)
				(justify mirror)
			)
		)
		(property "Tolerance" "TOL*"
			(at -0.0762 3.032506 90)
			(unlocked yes)
			(layer "Cmts.User")
			(hide yes)
			(effects
				(font
					(size 0.7874 0.5842)
					(thickness 0.1524)
				)
				(justify mirror)
			)
		)
		(property "User Part Number" "PARTNUM*"
			(at -0.1016 4.023106 90)
			(unlocked yes)
			(layer "Cmts.User")
			(hide yes)
			(effects
				(font
					(size 0.7874 0.5842)
					(thickness 0.1524)
				)
				(justify mirror)
			)
		)
		(property "Device Type" "CAPACITOR-G105-0B104-EK,0.1UF,A"
			(at -0.0508 1.127506 90)
			(unlocked yes)
			(layer "B.Fab")
			(hide yes)
			(effects
				(font
					(size 0.7874 0.5842)
					(thickness 0.1524)
				)
				(justify mirror)
			)
		)
		(duplicate_pad_numbers_are_jumpers no)
		(fp_line
			(start 1.143 -0.5588)
			(end 1.143 0.5588)
			(stroke
				(width 0.1)
				(type default)
			)
			(layer "B.SilkS")
		)
		(fp_line
			(start -1.143 -0.5588)
			(end 1.143 -0.5588)
			(stroke
				(width 0.1)
				(type default)
			)
			(layer "B.SilkS")
		)
		(fp_line
			(start 1.143 0.5588)
			(end -1.143 0.5588)
			(stroke
				(width 0.1)
				(type default)
			)
			(layer "B.SilkS")
		)
		(fp_line
			(start -1.143 0.5588)
			(end -1.143 -0.5588)
			(stroke
				(width 0.1)
				(type default)
			)
			(layer "B.SilkS")
		)
		(fp_rect
			(start -1.143 -0.5588)
			(end 1.143 0.5588)
			(stroke
				(width 0)
				(type default)
			)
			(fill no)
			(layer "B.CrtYd")
		)
		(fp_line
			(start 0.508 -0.3048)
			(end 0.508 0.3048)
			(stroke
				(width 0.1)
				(type default)
			)
			(layer "B.Fab")
		)
		(fp_line
			(start -0.508 -0.3048)
			(end 0.508 -0.3048)
			(stroke
				(width 0.1)
				(type default)
			)
			(layer "B.Fab")
		)
		(fp_line
			(start 0.508 0.3048)
			(end -0.508 0.3048)
			(stroke
				(width 0.1)
				(type default)
			)
			(layer "B.Fab")
		)
		(fp_line
			(start -0.508 0.3048)
			(end -0.508 -0.3048)
			(stroke
				(width 0.1)
				(type default)
			)
			(layer "B.Fab")
		)
		(pad "1" smd rect
			(at 0.5334 0 270)
			(size 0.7112 0.6096)
			(layers "B.Cu" "B.Mask" "B.Paste")
			(net "XP5R0V_MAC")
		)
		(pad "2" smd rect
			(at -0.5334 0 270)
			(size 0.7112 0.6096)
			(layers "B.Cu" "B.Mask" "B.Paste")
			(net "SG")
		)
		(zone
			(layer "B.Cu")
			(hatch none 0.5)
			(connect_pads
				(clearance 0)
			)
			(min_thickness 0.25)
			(keepout
				(tracks allowed)
				(vias not_allowed)
				(pads allowed)
				(copperpour not_allowed)
				(footprints allowed)
			)
			(placement
				(enabled no)
				(sheetname "")
			)
			(fill
				(thermal_gap 0.5)
				(thermal_bridge_width 0.5)
				(island_removal_mode 0)
			)
			(polygon
				(pts
					(xy 70.5612 -58.7756) (xy 71.1708 -58.7756) (xy 71.1708 -58.928) (xy 70.5612 -58.928)
				)
			)
		)
	)
	(footprint ""
		(layer "B.Cu")
		(at 89.9922 -102.4128 180)
		(property "Reference" "C286"
			(at -3.3528 -0.09017 0)
			(unlocked yes)
			(layer "B.SilkS")
			(effects
				(font
					(size 0.7874 0.5842)
					(thickness 0.1524)
				)
				(justify mirror)
			)
		)
		(property "Value" "VAL*"
			(at -0.0762 2.067306 180)
			(unlocked yes)
			(layer "B.Fab")
			(hide yes)
			(effects
				(font
					(size 0.7874 0.5842)
					(thickness 0.1524)
				)
				(justify mirror)
			)
		)
		(property "Tolerance" "TOL*"
			(at -0.0762 3.032506 180)
			(unlocked yes)
			(layer "Cmts.User")
			(hide yes)
			(effects
				(font
					(size 0.7874 0.5842)
					(thickness 0.1524)
				)
				(justify mirror)
			)
		)
		(property "User Part Number" "PARTNUM*"
			(at -0.1016 4.023106 180)
			(unlocked yes)
			(layer "Cmts.User")
			(hide yes)
			(effects
				(font
					(size 0.7874 0.5842)
					(thickness 0.1524)
				)
				(justify mirror)
			)
		)
		(property "Device Type" "CAPACITOR-G105-0B224-DK,0.22UFA"
			(at -0.0508 1.127506 180)
			(unlocked yes)
			(layer "B.Fab")
			(hide yes)
			(effects
				(font
					(size 0.7874 0.5842)
					(thickness 0.1524)
				)
				(justify mirror)
			)
		)
		(duplicate_pad_numbers_are_jumpers no)
		(fp_line
			(start 1.143 0.5588)
			(end -1.143 0.5588)
			(stroke
				(width 0.1)
				(type default)
			)
			(layer "B.SilkS")
		)
		(fp_line
			(start 1.143 -0.5588)
			(end 1.143 0.5588)
			(stroke
				(width 0.1)
				(type default)
			)
			(layer "B.SilkS")
		)
		(fp_line
			(start -1.143 0.5588)
			(end -1.143 -0.5588)
			(stroke
				(width 0.1)
				(type default)
			)
			(layer "B.SilkS")
		)
		(fp_line
			(start -1.143 -0.5588)
			(end 1.143 -0.5588)
			(stroke
				(width 0.1)
				(type default)
			)
			(layer "B.SilkS")
		)
		(fp_rect
			(start 1.143 -0.5588)
			(end -1.143 0.5588)
			(stroke
				(width 0)
				(type default)
			)
			(fill no)
			(layer "B.CrtYd")
		)
		(fp_line
			(start 0.508 0.3048)
			(end -0.508 0.3048)
			(stroke
				(width 0.1)
				(type default)
			)
			(layer "B.Fab")
		)
		(fp_line
			(start 0.508 -0.3048)
			(end 0.508 0.3048)
			(stroke
				(width 0.1)
				(type default)
			)
			(layer "B.Fab")
		)
		(fp_line
			(start -0.508 0.3048)
			(end -0.508 -0.3048)
			(stroke
				(width 0.1)
				(type default)
			)
			(layer "B.Fab")
		)
		(fp_line
			(start -0.508 -0.3048)
			(end 0.508 -0.3048)
			(stroke
				(width 0.1)
				(type default)
			)
			(layer "B.Fab")
		)
		(pad "1" smd rect
			(at 0.5334 0)
			(size 0.7112 0.6096)
			(layers "B.Cu" "B.Mask" "B.Paste")
			(net "XP3R3V_EN")
		)
		(pad "2" smd rect
			(at -0.5334 0)
			(size 0.7112 0.6096)
			(layers "B.Cu" "B.Mask" "B.Paste")
			(net "SG")
		)
		(zone
			(layer "B.Cu")
			(hatch none 0.5)
			(connect_pads
				(clearance 0)
			)
			(min_thickness 0.25)
			(keepout
				(tracks allowed)
				(vias not_allowed)
				(pads allowed)
				(copperpour not_allowed)
				(footprints allowed)
			)
			(placement
				(enabled no)
				(sheetname "")
			)
			(fill
				(thermal_gap 0.5)
				(thermal_bridge_width 0.5)
				(island_removal_mode 0)
			)
			(polygon
				(pts
					(xy 89.916 -102.108) (xy 90.0684 -102.108) (xy 90.0684 -102.7176) (xy 89.916 -102.7176)
				)
			)
		)
		(zone
			(layer "B.Cu")
			(hatch none 0.5)
			(connect_pads
				(clearance 0)
			)
			(min_thickness 0.25)
			(keepout
				(tracks not_allowed)
				(vias allowed)
				(pads allowed)
				(copperpour not_allowed)
				(footprints allowed)
			)
			(placement
				(enabled no)
				(sheetname "")
			)
			(fill
				(thermal_gap 0.5)
				(thermal_bridge_width 0.5)
				(island_removal_mode 0)
			)
			(polygon
				(pts
					(xy 89.916 -102.108) (xy 90.0684 -102.108) (xy 90.0684 -102.7176) (xy 89.916 -102.7176)
				)
			)
		)
	)
	(footprint ""
		(layer "B.Cu")
		(at 153.035 -104.394 90)
		(property "Reference" "R119"
			(at -1.27 1.10363 270)
			(unlocked yes)
			(layer "B.SilkS")
			(effects
				(font
					(size 0.7874 0.5842)
					(thickness 0.1524)
				)
				(justify mirror)
			)
		)
		(property "Value" "VAL*"
			(at -0.02032 2.13233 90)
			(unlocked yes)
			(layer "B.Fab")
			(hide yes)
			(effects
				(font
					(size 0.7874 0.5842)
					(thickness 0.1524)
				)
				(justify mirror)
			)
		)
		(property "Tolerance" "TOL*"
			(at -0.044704 3.05435 90)
			(unlocked yes)
			(layer "Cmts.User")
			(hide yes)
			(effects
				(font
					(size 0.7874 0.5842)
					(thickness 0.1524)
				)
				(justify mirror)
			)
		)
		(property "User Part Number" "PARTNUM*"
			(at -0.02032 4.024884 90)
			(unlocked yes)
			(layer "Cmts.User")
			(hide yes)
			(effects
				(font
					(size 0.7874 0.5842)
					(thickness 0.1524)
				)
				(justify mirror)
			)
		)
		(property "Device Type" "RESISTOR-G155-13300-01,330OHM,A"
			(at -0.008382 1.210564 90)
			(unlocked yes)
			(layer "B.Fab")
			(hide yes)
			(effects
				(font
					(size 0.7874 0.5842)
					(thickness 0.1524)
				)
				(justify mirror)
			)
		)
		(duplicate_pad_numbers_are_jumpers no)
		(fp_line
			(start 1.143 -0.5588)
			(end 1.143 0.5588)
			(stroke
				(width 0.1)
				(type default)
			)
			(layer "B.SilkS")
		)
		(fp_line
			(start -1.143 -0.5588)
			(end 1.143 -0.5588)
			(stroke
				(width 0.1)
				(type default)
			)
			(layer "B.SilkS")
		)
		(fp_line
			(start 1.143 0.5588)
			(end -1.143 0.5588)
			(stroke
				(width 0.1)
				(type default)
			)
			(layer "B.SilkS")
		)
		(fp_line
			(start -1.143 0.5588)
			(end -1.143 -0.5588)
			(stroke
				(width 0.1)
				(type default)
			)
			(layer "B.SilkS")
		)
		(fp_poly
			(pts
				(xy 1.143 0.5588) (xy -1.143 0.5588) (xy -1.143 -0.5588) (xy 1.143 -0.5588)
			)
			(stroke
				(width 0)
				(type default)
			)
			(fill no)
			(layer "B.CrtYd")
		)
		(fp_line
			(start 0.508 -0.3048)
			(end 0.508 0.3048)
			(stroke
				(width 0.1)
				(type default)
			)
			(layer "B.Fab")
		)
		(fp_line
			(start -0.508 -0.3048)
			(end 0.508 -0.3048)
			(stroke
				(width 0.1)
				(type default)
			)
			(layer "B.Fab")
		)
		(fp_line
			(start 0.508 0.3048)
			(end -0.508 0.3048)
			(stroke
				(width 0.1)
				(type default)
			)
			(layer "B.Fab")
		)
		(fp_line
			(start -0.508 0.3048)
			(end -0.508 -0.3048)
			(stroke
				(width 0.1)
				(type default)
			)
			(layer "B.Fab")
		)
		(pad "1" smd rect
			(at 0.5334 0 270)
			(size 0.7112 0.6096)
			(layers "B.Cu" "B.Mask" "B.Paste")
			(net "UNNAMED_14_OPTICAL_I194_A")
		)
		(pad "2" smd rect
			(at -0.5334 0 270)
			(size 0.7112 0.6096)
			(layers "B.Cu" "B.Mask" "B.Paste")
			(net "XP3R3V_AUX_PCIE")
		)
		(zone
			(layer "B.Cu")
			(hatch none 0.5)
			(connect_pads
				(clearance 0)
			)
			(min_thickness 0.25)
			(keepout
				(tracks allowed)
				(vias not_allowed)
				(pads allowed)
				(copperpour not_allowed)
				(footprints allowed)
			)
			(placement
				(enabled no)
				(sheetname "")
			)
			(fill
				(thermal_gap 0.5)
				(thermal_bridge_width 0.5)
				(island_removal_mode 0)
			)
			(polygon
				(pts
					(xy 153.3398 -104.4702) (xy 152.7302 -104.4702) (xy 152.7302 -104.3178) (xy 153.3398 -104.3178)
				)
			)
		)
		(zone
			(layer "B.Cu")
			(hatch none 0.5)
			(connect_pads
				(clearance 0)
			)
			(min_thickness 0.25)
			(keepout
				(tracks not_allowed)
				(vias allowed)
				(pads allowed)
				(copperpour not_allowed)
				(footprints allowed)
			)
			(placement
				(enabled no)
				(sheetname "")
			)
			(fill
				(thermal_gap 0.5)
				(thermal_bridge_width 0.5)
				(island_removal_mode 0)
			)
			(polygon
				(pts
					(xy 153.3398 -104.4702) (xy 152.7302 -104.4702) (xy 152.7302 -104.3178) (xy 153.3398 -104.3178)
				)
			)
		)
	)
	(footprint ""
		(layer "B.Cu")
		(at 21.0566 -39.3446)
		(property "Reference" "R148"
			(at -0.3556 4.71297 0)
			(unlocked yes)
			(layer "B.SilkS")
			(effects
				(font
					(size 0.7874 0.5842)
					(thickness 0.1524)
				)
				(justify mirror)
			)
		)
		(property "Value" "VAL*"
			(at -0.02032 2.13233 0)
			(unlocked yes)
			(layer "B.Fab")
			(hide yes)
			(effects
				(font
					(size 0.7874 0.5842)
					(thickness 0.1524)
				)
				(justify mirror)
			)
		)
		(property "Device Type" "RESISTOR-G155-11002-01,10KOHM,A"
			(at -0.008382 1.210564 0)
			(unlocked yes)
			(layer "B.Fab")
			(hide yes)
			(effects
				(font
					(size 0.7874 0.5842)
					(thickness 0.1524)
				)
				(justify mirror)
			)
		)
		(property "User Part Number" "PARTNUM*"
			(at -0.02032 4.024884 0)
			(unlocked yes)
			(layer "Cmts.User")
			(hide yes)
			(effects
				(font
					(size 0.7874 0.5842)
					(thickness 0.1524)
				)
				(justify mirror)
			)
		)
		(property "Tolerance" "TOL*"
			(at -0.044704 3.05435 0)
			(unlocked yes)
			(layer "Cmts.User")
			(hide yes)
			(effects
				(font
					(size 0.7874 0.5842)
					(thickness 0.1524)
				)
				(justify mirror)
			)
		)
		(duplicate_pad_numbers_are_jumpers no)
		(fp_line
			(start -1.143 -0.5588)
			(end 1.143 -0.5588)
			(stroke
				(width 0.1)
				(type default)
			)
			(layer "B.SilkS")
		)
		(fp_line
			(start -1.143 0.5588)
			(end -1.143 -0.5588)
			(stroke
				(width 0.1)
				(type default)
			)
			(layer "B.SilkS")
		)
		(fp_line
			(start 1.143 -0.5588)
			(end 1.143 0.5588)
			(stroke
				(width 0.1)
				(type default)
			)
			(layer "B.SilkS")
		)
		(fp_line
			(start 1.143 0.5588)
			(end -1.143 0.5588)
			(stroke
				(width 0.1)
				(type default)
			)
			(layer "B.SilkS")
		)
		(fp_rect
			(start 1.143 0.5588)
			(end -1.143 -0.5588)
			(stroke
				(width 0)
				(type default)
			)
			(fill no)
			(layer "B.CrtYd")
		)
		(fp_line
			(start -0.508 -0.3048)
			(end 0.508 -0.3048)
			(stroke
				(width 0.1)
				(type default)
			)
			(layer "B.Fab")
		)
		(fp_line
			(start -0.508 0.3048)
			(end -0.508 -0.3048)
			(stroke
				(width 0.1)
				(type default)
			)
			(layer "B.Fab")
		)
		(fp_line
			(start 0.508 -0.3048)
			(end 0.508 0.3048)
			(stroke
				(width 0.1)
				(type default)
			)
			(layer "B.Fab")
		)
		(fp_line
			(start 0.508 0.3048)
			(end -0.508 0.3048)
			(stroke
				(width 0.1)
				(type default)
			)
			(layer "B.Fab")
		)
		(pad "1" smd rect
			(at 0.5334 0 180)
			(size 0.7112 0.6096)
			(layers "B.Cu" "B.Mask" "B.Paste")
			(net "XP3R3V_FPGA")
		)
		(pad "2" smd rect
			(at -0.5334 0 180)
			(size 0.7112 0.6096)
			(layers "B.Cu" "B.Mask" "B.Paste")
			(net "R_PCA9546_I2C_SCL")
		)
		(zone
			(layer "B.Cu")
			(hatch none 0.5)
			(connect_pads
				(clearance 0)
			)
			(min_thickness 0.25)
			(keepout
				(tracks allowed)
				(vias not_allowed)
				(pads allowed)
				(copperpour not_allowed)
				(footprints allowed)
			)
			(placement
				(enabled no)
				(sheetname "")
			)
			(fill
				(thermal_gap 0.5)
				(thermal_bridge_width 0.5)
				(island_removal_mode 0)
			)
			(polygon
				(pts
					(xy 21.1328 -39.0398) (xy 21.1328 -39.6494) (xy 20.9804 -39.6494) (xy 20.9804 -39.0398)
				)
			)
		)
	)
	(footprint ""
		(layer "B.Cu")
		(at 68.326 -57.15 -90)
		(property "Reference" "U12"
			(at 3.97637 -1.143 0)
			(unlocked yes)
			(layer "B.SilkS")
			(effects
				(font
					(size 0.7874 0.5842)
					(thickness 0.1524)
				)
				(justify mirror)
			)
		)
		(property "Value" ""
			(at 0 0 90)
			(layer "B.Fab")
			(effects
				(font
					(size 1.27 1.27)
				)
				(justify mirror)
			)
		)
		(property "Device Type" "TPS2051BDBVT_SOT23_5-G220-1033A"
			(at -0.0508 2.549906 270)
			(unlocked yes)
			(layer "B.Fab")
			(hide yes)
			(effects
				(font
					(size 0.7874 0.5842)
					(thickness 0.1524)
				)
				(justify mirror)
			)
		)
		(property "User Part Number" "PARTNUM*"
			(at -0.0508 3.515106 270)
			(unlocked yes)
			(layer "Cmts.User")
			(hide yes)
			(effects
				(font
					(size 0.7874 0.5842)
					(thickness 0.1524)
				)
				(justify mirror)
			)
		)
		(duplicate_pad_numbers_are_jumpers no)
		(fp_line
			(start -1.0541 1.704086)
			(end 1.0541 1.704086)
			(stroke
				(width 0.1)
				(type default)
			)
			(layer "B.SilkS")
		)
		(fp_line
			(start 1.0541 1.704086)
			(end 1.0541 1.45796)
			(stroke
				(width 0.1)
				(type default)
			)
			(layer "B.SilkS")
		)
		(fp_line
			(start -2.286 1.45796)
			(end -1.0541 1.45796)
			(stroke
				(width 0.1)
				(type default)
			)
			(layer "B.SilkS")
		)
		(fp_line
			(start -1.0541 1.45796)
			(end -1.0541 1.704086)
			(stroke
				(width 0.1)
				(type default)
			)
			(layer "B.SilkS")
		)
		(fp_line
			(start 1.0541 1.45796)
			(end 2.286 1.45796)
			(stroke
				(width 0.1)
				(type default)
			)
			(layer "B.SilkS")
		)
		(fp_line
			(start 2.286 1.45796)
			(end 2.286 -1.45796)
			(stroke
				(width 0.1)
				(type default)
			)
			(layer "B.SilkS")
		)
		(fp_line
			(start -2.286 0.44196)
			(end -2.286 1.45796)
			(stroke
				(width 0.1)
				(type default)
			)
			(layer "B.SilkS")
		)
		(fp_line
			(start -1.0541 0.44196)
			(end -2.286 0.44196)
			(stroke
				(width 0.1)
				(type default)
			)
			(layer "B.SilkS")
		)
		(fp_line
			(start -2.286 -0.44196)
			(end -1.0541 -0.44196)
			(stroke
				(width 0.1)
				(type default)
			)
			(layer "B.SilkS")
		)
		(fp_line
			(start -1.0541 -0.44196)
			(end -1.0541 0.44196)
			(stroke
				(width 0.1)
				(type default)
			)
			(layer "B.SilkS")
		)
		(fp_line
			(start -2.286 -1.45796)
			(end -2.286 -0.44196)
			(stroke
				(width 0.1)
				(type default)
			)
			(layer "B.SilkS")
		)
		(fp_line
			(start -1.0541 -1.45796)
			(end -2.286 -1.45796)
			(stroke
				(width 0.1)
				(type default)
			)
			(layer "B.SilkS")
		)
		(fp_line
			(start 1.0541 -1.45796)
			(end 1.0541 -1.704086)
			(stroke
				(width 0.1)
				(type default)
			)
			(layer "B.SilkS")
		)
		(fp_line
			(start 2.286 -1.45796)
			(end 1.0541 -1.45796)
			(stroke
				(width 0.1)
				(type default)
			)
			(layer "B.SilkS")
		)
		(fp_line
			(start -1.0541 -1.704086)
			(end -1.0541 -1.45796)
			(stroke
				(width 0.1)
				(type default)
			)
			(layer "B.SilkS")
		)
		(fp_line
			(start 1.0541 -1.704086)
			(end -1.0541 -1.704086)
			(stroke
				(width 0.1)
				(type default)
			)
			(layer "B.SilkS")
		)
		(fp_poly
			(pts
				(arc
					(start 2.8956 -1.5494)
					(mid 2.8956 -0.7874)
					(end 2.8956 -1.5494)
				)
			)
			(stroke
				(width 0)
				(type default)
			)
			(fill yes)
			(layer "B.SilkS")
		)
		(fp_rect
			(start 2.54 -1.9558)
			(end -2.54 1.9558)
			(stroke
				(width 0)
				(type default)
			)
			(fill no)
			(layer "B.CrtYd")
		)
		(fp_line
			(start -0.8001 1.450086)
			(end -0.599948 1.249934)
			(stroke
				(width 0.1)
				(type default)
			)
			(layer "B.Fab")
		)
		(fp_line
			(start -0.8001 1.450086)
			(end -0.8001 1.199896)
			(stroke
				(width 0.1)
				(type default)
			)
			(layer "B.Fab")
		)
		(fp_line
			(start 0.8001 1.450086)
			(end -0.8001 1.450086)
			(stroke
				(width 0.1)
				(type default)
			)
			(layer "B.Fab")
		)
		(fp_line
			(start 0.8001 1.450086)
			(end 0.599948 1.249934)
			(stroke
				(width 0.1)
				(type default)
			)
			(layer "B.Fab")
		)
		(fp_line
			(start -0.599948 1.249934)
			(end 0.599948 1.249934)
			(stroke
				(width 0.1)
				(type default)
			)
			(layer "B.Fab")
		)
		(fp_line
			(start 0.599948 1.249934)
			(end 0.599948 -1.249934)
			(stroke
				(width 0.1)
				(type default)
			)
			(layer "B.Fab")
		)
		(fp_line
			(start -1.500124 1.199896)
			(end -0.700024 1.199896)
			(stroke
				(width 0.1)
				(type default)
			)
			(layer "B.Fab")
		)
		(fp_line
			(start -0.700024 1.199896)
			(end -0.700024 0.700024)
			(stroke
				(width 0.1)
				(type default)
			)
			(layer "B.Fab")
		)
		(fp_line
			(start 0.700024 1.199896)
			(end 1.500124 1.199896)
			(stroke
				(width 0.1)
				(type default)
			)
			(layer "B.Fab")
		)
		(fp_line
			(start 0.8001 1.199896)
			(end 0.8001 1.450086)
			(stroke
				(width 0.1)
				(type default)
			)
			(layer "B.Fab")
		)
		(fp_line
			(start 1.500124 1.199896)
			(end 1.500124 0.700024)
			(stroke
				(width 0.1)
				(type default)
			)
			(layer "B.Fab")
		)
		(fp_line
			(start -1.500124 0.700024)
			(end -1.500124 1.199896)
			(stroke
				(width 0.1)
				(type default)
			)
			(layer "B.Fab")
		)
		(fp_line
			(start -0.700024 0.700024)
			(end -1.500124 0.700024)
			(stroke
				(width 0.1)
				(type default)
			)
			(layer "B.Fab")
		)
		(fp_line
			(start 0.700024 0.700024)
			(end 0.700024 1.199896)
			(stroke
				(width 0.1)
				(type default)
			)
			(layer "B.Fab")
		)
		(fp_line
			(start 1.500124 0.700024)
			(end 0.700024 0.700024)
			(stroke
				(width 0.1)
				(type default)
			)
			(layer "B.Fab")
		)
		(fp_line
			(start 0.700024 0.249936)
			(end 1.500124 0.249936)
			(stroke
				(width 0.1)
				(type default)
			)
			(layer "B.Fab")
		)
		(fp_line
			(start 0.8001 0.249936)
			(end 0.8001 0.700024)
			(stroke
				(width 0.1)
				(type default)
			)
			(layer "B.Fab")
		)
		(fp_line
			(start 1.500124 0.249936)
			(end 1.500124 -0.249936)
			(stroke
				(width 0.1)
				(type default)
			)
			(layer "B.Fab")
		)
		(fp_line
			(start 0.700024 -0.249936)
			(end 0.700024 0.249936)
			(stroke
				(width 0.1)
				(type default)
			)
			(layer "B.Fab")
		)
		(fp_line
			(start 1.500124 -0.249936)
			(end 0.700024 -0.249936)
			(stroke
				(width 0.1)
				(type default)
			)
			(layer "B.Fab")
		)
		(fp_line
			(start -1.500124 -0.700024)
			(end -0.700024 -0.700024)
			(stroke
				(width 0.1)
				(type default)
			)
			(layer "B.Fab")
		)
		(fp_line
			(start -0.8001 -0.700024)
			(end -0.8001 0.700024)
			(stroke
				(width 0.1)
				(type default)
			)
			(layer "B.Fab")
		)
		(fp_line
			(start -0.700024 -0.700024)
			(end -0.700024 -1.199896)
			(stroke
				(width 0.1)
				(type default)
			)
			(layer "B.Fab")
		)
		(fp_line
			(start 0.700024 -0.700024)
			(end 1.500124 -0.700024)
			(stroke
				(width 0.1)
				(type default)
			)
			(layer "B.Fab")
		)
		(fp_line
			(start 0.8001 -0.700024)
			(end 0.8001 -0.249936)
			(stroke
				(width 0.1)
				(type default)
			)
			(layer "B.Fab")
		)
		(fp_line
			(start 1.500124 -0.700024)
			(end 1.500124 -1.199896)
			(stroke
				(width 0.1)
				(type default)
			)
			(layer "B.Fab")
		)
		(fp_line
			(start -1.500124 -1.199896)
			(end -1.500124 -0.700024)
			(stroke
				(width 0.1)
				(type default)
			)
			(layer "B.Fab")
		)
		(fp_line
			(start -0.700024 -1.199896)
			(end -1.500124 -1.199896)
			(stroke
				(width 0.1)
				(type default)
			)
			(layer "B.Fab")
		)
		(fp_line
			(start 0.700024 -1.199896)
			(end 0.700024 -0.700024)
			(stroke
				(width 0.1)
				(type default)
			)
			(layer "B.Fab")
		)
		(fp_line
			(start 0.8001 -1.199896)
			(end 0.8001 -1.450086)
			(stroke
				(width 0.1)
				(type default)
			)
			(layer "B.Fab")
		)
		(fp_line
			(start 1.500124 -1.199896)
			(end 0.700024 -1.199896)
			(stroke
				(width 0.1)
				(type default)
			)
			(layer "B.Fab")
		)
		(fp_line
			(start -0.599948 -1.249934)
			(end -0.599948 1.249934)
			(stroke
				(width 0.1)
				(type default)
			)
			(layer "B.Fab")
		)
		(fp_line
			(start -0.599948 -1.249934)
			(end -0.8001 -1.450086)
			(stroke
				(width 0.1)
				(type default)
			)
			(layer "B.Fab")
		)
		(fp_line
			(start 0.599948 -1.249934)
			(end -0.599948 -1.249934)
			(stroke
				(width 0.1)
				(type default)
			)
			(layer "B.Fab")
		)
		(fp_line
			(start 0.599948 -1.249934)
			(end 0.8001 -1.450086)
			(stroke
				(width 0.1)
				(type default)
			)
			(layer "B.Fab")
		)
		(fp_line
			(start -0.8001 -1.450086)
			(end -0.8001 -1.199896)
			(stroke
				(width 0.1)
				(type default)
			)
			(layer "B.Fab")
		)
		(fp_line
			(start 0.8001 -1.450086)
			(end -0.8001 -1.450086)
			(stroke
				(width 0.1)
				(type default)
			)
			(layer "B.Fab")
		)
		(fp_poly
			(pts
				(arc
					(start 0.350012 -1.09982)
					(mid 0.350012 -0.8001)
					(end 0.350012 -1.09982)
				)
			)
			(stroke
				(width 0)
				(type default)
			)
			(fill yes)
			(layer "B.Fab")
		)
		(fp_text user "4"
			(at -2.286 2.44475 270)
			(unlocked yes)
			(layer "B.SilkS")
			(effects
				(font
					(size 0.635 0.4064)
					(thickness 0.1524)
				)
				(justify mirror)
			)
		)
		(fp_text user "3"
			(at 3.58775 1.651 0)
			(unlocked yes)
			(layer "B.SilkS")
			(effects
				(font
					(size 0.635 0.4064)
					(thickness 0.1524)
				)
				(justify mirror)
			)
		)
		(fp_text user "5"
			(at -2.88925 -1.524 0)
			(unlocked yes)
			(layer "B.SilkS")
			(effects
				(font
					(size 0.635 0.4064)
					(thickness 0.1524)
				)
				(justify mirror)
			)
		)
		(fp_text user "3"
			(at 2.794 0.91567 270)
			(unlocked yes)
			(layer "B.Fab")
			(effects
				(font
					(size 0.7874 0.5842)
					(thickness 0.1524)
				)
				(justify mirror)
			)
		)
		(fp_text user "4"
			(at -2.13233 0.762 0)
			(unlocked yes)
			(layer "B.Fab")
			(effects
				(font
					(size 0.7874 0.5842)
					(thickness 0.1524)
				)
				(justify mirror)
			)
		)
		(fp_text user "5"
			(at -2.13233 -1.143 0)
			(unlocked yes)
			(layer "B.Fab")
			(effects
				(font
					(size 0.7874 0.5842)
					(thickness 0.1524)
				)
				(justify mirror)
			)
		)
		(pad "1" smd rect
			(at 1.4351 -0.94996)
			(size 0.508 1.1938)
			(layers "B.Cu" "B.Mask" "B.Paste")
			(net "XP5R0V_MAC_USB")
		)
		(pad "2" smd rect
			(at 1.4351 0)
			(size 0.508 1.1938)
			(layers "B.Cu" "B.Mask" "B.Paste")
			(net "SG")
		)
		(pad "3" smd rect
			(at 1.4351 0.94996)
			(size 0.508 1.1938)
			(layers "B.Cu" "B.Mask" "B.Paste")
			(net "UNNAMED_527_RESISTOR_I206_1")
		)
		(pad "4" smd rect
			(at -1.4351 0.94996)
			(size 0.508 1.1938)
			(layers "B.Cu" "B.Mask" "B.Paste")
			(net "USB_PWR_EN")
		)
		(pad "5" smd rect
			(at -1.4351 -0.94996)
			(size 0.508 1.1938)
			(layers "B.Cu" "B.Mask" "B.Paste")
			(net "XP5R0V_MAC")
		)
	)
	(footprint ""
		(layer "B.Cu")
		(at 151.613108 -49.01311 90)
		(property "Reference" "R69"
			(at 3.81889 -1.030478 270)
			(unlocked yes)
			(layer "B.SilkS")
			(effects
				(font
					(size 0.7874 0.5842)
					(thickness 0.1524)
				)
				(justify mirror)
			)
		)
		(property "Value" "VAL*"
			(at -0.02032 2.13233 90)
			(unlocked yes)
			(layer "B.Fab")
			(hide yes)
			(effects
				(font
					(size 0.7874 0.5842)
					(thickness 0.1524)
				)
				(justify mirror)
			)
		)
		(property "Device Type" "RESISTOR-G155-11001-01,1KOHM,1%"
			(at -0.008382 1.210564 90)
			(unlocked yes)
			(layer "B.Fab")
			(hide yes)
			(effects
				(font
					(size 0.7874 0.5842)
					(thickness 0.1524)
				)
				(justify mirror)
			)
		)
		(property "User Part Number" "PARTNUM*"
			(at -0.02032 4.024884 90)
			(unlocked yes)
			(layer "Cmts.User")
			(hide yes)
			(effects
				(font
					(size 0.7874 0.5842)
					(thickness 0.1524)
				)
				(justify mirror)
			)
		)
		(property "Tolerance" "TOL*"
			(at -0.044704 3.05435 90)
			(unlocked yes)
			(layer "Cmts.User")
			(hide yes)
			(effects
				(font
					(size 0.7874 0.5842)
					(thickness 0.1524)
				)
				(justify mirror)
			)
		)
		(duplicate_pad_numbers_are_jumpers no)
		(fp_line
			(start 1.143 -0.5588)
			(end 1.143 0.5588)
			(stroke
				(width 0.1)
				(type default)
			)
			(layer "B.SilkS")
		)
		(fp_line
			(start -1.143 -0.5588)
			(end 1.143 -0.5588)
			(stroke
				(width 0.1)
				(type default)
			)
			(layer "B.SilkS")
		)
		(fp_line
			(start 1.143 0.5588)
			(end -1.143 0.5588)
			(stroke
				(width 0.1)
				(type default)
			)
			(layer "B.SilkS")
		)
		(fp_line
			(start -1.143 0.5588)
			(end -1.143 -0.5588)
			(stroke
				(width 0.1)
				(type default)
			)
			(layer "B.SilkS")
		)
		(fp_rect
			(start 1.143 0.5588)
			(end -1.143 -0.5588)
			(stroke
				(width 0)
				(type default)
			)
			(fill no)
			(layer "B.CrtYd")
		)
		(fp_line
			(start 0.508 -0.3048)
			(end 0.508 0.3048)
			(stroke
				(width 0.1)
				(type default)
			)
			(layer "B.Fab")
		)
		(fp_line
			(start -0.508 -0.3048)
			(end 0.508 -0.3048)
			(stroke
				(width 0.1)
				(type default)
			)
			(layer "B.Fab")
		)
		(fp_line
			(start 0.508 0.3048)
			(end -0.508 0.3048)
			(stroke
				(width 0.1)
				(type default)
			)
			(layer "B.Fab")
		)
		(fp_line
			(start -0.508 0.3048)
			(end -0.508 -0.3048)
			(stroke
				(width 0.1)
				(type default)
			)
			(layer "B.Fab")
		)
		(pad "1" smd rect
			(at 0.5334 0 270)
			(size 0.7112 0.6096)
			(layers "B.Cu" "B.Mask" "B.Paste")
			(net "SHT3X_ADDR")
		)
		(pad "2" smd rect
			(at -0.5334 0 270)
			(size 0.7112 0.6096)
			(layers "B.Cu" "B.Mask" "B.Paste")
			(net "SG")
		)
		(zone
			(layer "B.Cu")
			(hatch none 0.5)
			(connect_pads
				(clearance 0)
			)
			(min_thickness 0.25)
			(keepout
				(tracks allowed)
				(vias not_allowed)
				(pads allowed)
				(copperpour not_allowed)
				(footprints allowed)
			)
			(placement
				(enabled no)
				(sheetname "")
			)
			(fill
				(thermal_gap 0.5)
				(thermal_bridge_width 0.5)
				(island_removal_mode 0)
			)
			(polygon
				(pts
					(xy 151.917908 -49.08931) (xy 151.308308 -49.08931) (xy 151.308308 -48.93691) (xy 151.917908 -48.93691)
				)
			)
		)
	)
	(footprint ""
		(layer "B.Cu")
		(at 101.847142 -37.323014 90)
		(property "Reference" "C124"
			(at -1.524254 -42.018712 270)
			(unlocked yes)
			(layer "B.SilkS")
			(effects
				(font
					(size 0.635 0.4064)
					(thickness 0.1524)
				)
				(justify mirror)
			)
		)
		(property "Value" "VAL*"
			(at 0 3.718306 90)
			(unlocked yes)
			(layer "B.Fab")
			(hide yes)
			(effects
				(font
					(size 0.7874 0.5842)
					(thickness 0.127)
				)
				(justify mirror)
			)
		)
		(property "Tolerance" "TOL*"
			(at 0 4.861306 90)
			(unlocked yes)
			(layer "Cmts.User")
			(hide yes)
			(effects
				(font
					(size 0.7874 0.5842)
					(thickness 0.127)
				)
				(justify mirror)
			)
		)
		(property "User Part Number" "PARTNUM*"
			(at 0 2.575306 90)
			(unlocked yes)
			(layer "Cmts.User")
			(hide yes)
			(effects
				(font
					(size 0.7874 0.5842)
					(thickness 0.127)
				)
				(justify mirror)
			)
		)
		(property "Device Type" "CAPACITOR-G105-0B104-CK,0.1UF,A"
			(at 0 1.432306 90)
			(unlocked yes)
			(layer "B.Fab")
			(hide yes)
			(effects
				(font
					(size 0.7874 0.5842)
					(thickness 0.127)
				)
				(justify mirror)
			)
		)
		(duplicate_pad_numbers_are_jumpers no)
		(fp_line
			(start 0.970026 -0.4699)
			(end -0.970026 -0.4699)
			(stroke
				(width 0.1)
				(type default)
			)
			(layer "B.SilkS")
		)
		(fp_line
			(start -0.970026 -0.4699)
			(end -0.970026 0.4699)
			(stroke
				(width 0.1)
				(type default)
			)
			(layer "B.SilkS")
		)
		(fp_line
			(start 0.970026 0.4699)
			(end 0.970026 -0.4699)
			(stroke
				(width 0.1)
				(type default)
			)
			(layer "B.SilkS")
		)
		(fp_line
			(start -0.970026 0.4699)
			(end 0.970026 0.4699)
			(stroke
				(width 0.1)
				(type default)
			)
			(layer "B.SilkS")
		)
		(fp_poly
			(pts
				(xy 0.970026 0.4699) (xy -0.970026 0.4699) (xy -0.970026 -0.4699) (xy 0.970026 -0.4699)
			)
			(stroke
				(width 0)
				(type default)
			)
			(fill no)
			(layer "B.CrtYd")
		)
		(fp_line
			(start 0.508 -0.3048)
			(end -0.508 -0.3048)
			(stroke
				(width 0.1)
				(type default)
			)
			(layer "B.Fab")
		)
		(fp_line
			(start -0.508 -0.3048)
			(end -0.508 0.3048)
			(stroke
				(width 0.1)
				(type default)
			)
			(layer "B.Fab")
		)
		(fp_line
			(start 0.508 0.3048)
			(end 0.508 -0.3048)
			(stroke
				(width 0.1)
				(type default)
			)
			(layer "B.Fab")
		)
		(fp_line
			(start -0.508 0.3048)
			(end 0.508 0.3048)
			(stroke
				(width 0.1)
				(type default)
			)
			(layer "B.Fab")
		)
		(pad "1" smd circle
			(at 0.500126 0 270)
			(size 0.635 0.635)
			(layers "B.Cu" "B.Mask" "B.Paste")
			(net "XP1R0V_FPGA_MGTAVCC")
		)
		(pad "2" smd circle
			(at -0.500126 0 270)
			(size 0.635 0.635)
			(layers "B.Cu" "B.Mask" "B.Paste")
			(net "SG")
		)
	)
	(footprint ""
		(layer "B.Cu")
		(at 151.892 -39.624 90)
		(property "Reference" "R432"
			(at -7.02437 0.635 0)
			(unlocked yes)
			(layer "B.SilkS")
			(effects
				(font
					(size 0.7874 0.5842)
					(thickness 0.1524)
				)
				(justify mirror)
			)
		)
		(property "Value" "VAL*"
			(at -0.02032 2.13233 90)
			(unlocked yes)
			(layer "B.Fab")
			(hide yes)
			(effects
				(font
					(size 0.7874 0.5842)
					(thickness 0.1524)
				)
				(justify mirror)
			)
		)
		(property "Tolerance" "TOL*"
			(at -0.044704 3.05435 90)
			(unlocked yes)
			(layer "Cmts.User")
			(hide yes)
			(effects
				(font
					(size 0.7874 0.5842)
					(thickness 0.1524)
				)
				(justify mirror)
			)
		)
		(property "User Part Number" "PARTNUM*"
			(at -0.02032 4.024884 90)
			(unlocked yes)
			(layer "Cmts.User")
			(hide yes)
			(effects
				(font
					(size 0.7874 0.5842)
					(thickness 0.1524)
				)
				(justify mirror)
			)
		)
		(property "Device Type" "RESISTOR-G155-133R0-01,33OHM,1%"
			(at -0.008382 1.210564 90)
			(unlocked yes)
			(layer "B.Fab")
			(hide yes)
			(effects
				(font
					(size 0.7874 0.5842)
					(thickness 0.1524)
				)
				(justify mirror)
			)
		)
		(duplicate_pad_numbers_are_jumpers no)
		(fp_line
			(start 1.143 -0.5588)
			(end 1.143 0.5588)
			(stroke
				(width 0.1)
				(type default)
			)
			(layer "B.SilkS")
		)
		(fp_line
			(start -1.143 -0.5588)
			(end 1.143 -0.5588)
			(stroke
				(width 0.1)
				(type default)
			)
			(layer "B.SilkS")
		)
		(fp_line
			(start 1.143 0.5588)
			(end -1.143 0.5588)
			(stroke
				(width 0.1)
				(type default)
			)
			(layer "B.SilkS")
		)
		(fp_line
			(start -1.143 0.5588)
			(end -1.143 -0.5588)
			(stroke
				(width 0.1)
				(type default)
			)
			(layer "B.SilkS")
		)
		(fp_poly
			(pts
				(xy 1.143 0.5588) (xy -1.143 0.5588) (xy -1.143 -0.5588) (xy 1.143 -0.5588)
			)
			(stroke
				(width 0)
				(type default)
			)
			(fill no)
			(layer "B.CrtYd")
		)
		(fp_line
			(start 0.508 -0.3048)
			(end 0.508 0.3048)
			(stroke
				(width 0.1)
				(type default)
			)
			(layer "B.Fab")
		)
		(fp_line
			(start -0.508 -0.3048)
			(end 0.508 -0.3048)
			(stroke
				(width 0.1)
				(type default)
			)
			(layer "B.Fab")
		)
		(fp_line
			(start 0.508 0.3048)
			(end -0.508 0.3048)
			(stroke
				(width 0.1)
				(type default)
			)
			(layer "B.Fab")
		)
		(fp_line
			(start -0.508 0.3048)
			(end -0.508 -0.3048)
			(stroke
				(width 0.1)
				(type default)
			)
			(layer "B.Fab")
		)
		(pad "1" smd rect
			(at 0.5334 0 270)
			(size 0.7112 0.6096)
			(layers "B.Cu" "B.Mask" "B.Paste")
			(net "UNNAMED_16_CONNHDR2X6FSSMT_I1_7")
		)
		(pad "2" smd rect
			(at -0.5334 0 270)
			(size 0.7112 0.6096)
			(layers "B.Cu" "B.Mask" "B.Paste")
			(net "FPGA_IO_2")
		)
		(zone
			(layer "B.Cu")
			(hatch none 0.5)
			(connect_pads
				(clearance 0)
			)
			(min_thickness 0.25)
			(keepout
				(tracks not_allowed)
				(vias allowed)
				(pads allowed)
				(copperpour not_allowed)
				(footprints allowed)
			)
			(placement
				(enabled no)
				(sheetname "")
			)
			(fill
				(thermal_gap 0.5)
				(thermal_bridge_width 0.5)
				(island_removal_mode 0)
			)
			(polygon
				(pts
					(xy 152.1968 -39.7002) (xy 151.5872 -39.7002) (xy 151.5872 -39.5478) (xy 152.1968 -39.5478)
				)
			)
		)
		(zone
			(layer "B.Cu")
			(hatch none 0.5)
			(connect_pads
				(clearance 0)
			)
			(min_thickness 0.25)
			(keepout
				(tracks allowed)
				(vias not_allowed)
				(pads allowed)
				(copperpour not_allowed)
				(footprints allowed)
			)
			(placement
				(enabled no)
				(sheetname "")
			)
			(fill
				(thermal_gap 0.5)
				(thermal_bridge_width 0.5)
				(island_removal_mode 0)
			)
			(polygon
				(pts
					(xy 152.1968 -39.7002) (xy 151.5872 -39.7002) (xy 151.5872 -39.5478) (xy 152.1968 -39.5478)
				)
			)
		)
	)
	(footprint ""
		(layer "B.Cu")
		(at 120.347232 -50.823114 180)
		(property "Reference" "C103"
			(at -0.175768 0.961136 0)
			(unlocked yes)
			(layer "B.SilkS")
			(effects
				(font
					(size 0.635 0.4064)
					(thickness 0.1524)
				)
				(justify mirror)
			)
		)
		(property "Value" "VAL*"
			(at 0 3.718306 180)
			(unlocked yes)
			(layer "B.Fab")
			(hide yes)
			(effects
				(font
					(size 0.7874 0.5842)
					(thickness 0.127)
				)
				(justify mirror)
			)
		)
		(property "Tolerance" "TOL*"
			(at 0 4.861306 180)
			(unlocked yes)
			(layer "Cmts.User")
			(hide yes)
			(effects
				(font
					(size 0.7874 0.5842)
					(thickness 0.127)
				)
				(justify mirror)
			)
		)
		(property "User Part Number" "PARTNUM*"
			(at 0 2.575306 180)
			(unlocked yes)
			(layer "Cmts.User")
			(hide yes)
			(effects
				(font
					(size 0.7874 0.5842)
					(thickness 0.127)
				)
				(justify mirror)
			)
		)
		(property "Device Type" "CAPACITOR-G105-0B104-CK,0.1UF,A"
			(at 0 1.432306 180)
			(unlocked yes)
			(layer "B.Fab")
			(hide yes)
			(effects
				(font
					(size 0.7874 0.5842)
					(thickness 0.127)
				)
				(justify mirror)
			)
		)
		(duplicate_pad_numbers_are_jumpers no)
		(fp_line
			(start 0.970026 0.4699)
			(end 0.970026 -0.4699)
			(stroke
				(width 0.1)
				(type default)
			)
			(layer "B.SilkS")
		)
		(fp_line
			(start 0.970026 -0.4699)
			(end -0.970026 -0.4699)
			(stroke
				(width 0.1)
				(type default)
			)
			(layer "B.SilkS")
		)
		(fp_line
			(start -0.970026 0.4699)
			(end 0.970026 0.4699)
			(stroke
				(width 0.1)
				(type default)
			)
			(layer "B.SilkS")
		)
		(fp_line
			(start -0.970026 -0.4699)
			(end -0.970026 0.4699)
			(stroke
				(width 0.1)
				(type default)
			)
			(layer "B.SilkS")
		)
		(fp_poly
			(pts
				(xy 0.970026 0.4699) (xy -0.970026 0.4699) (xy -0.970026 -0.4699) (xy 0.970026 -0.4699)
			)
			(stroke
				(width 0)
				(type default)
			)
			(fill no)
			(layer "B.CrtYd")
		)
		(fp_line
			(start 0.508 0.3048)
			(end 0.508 -0.3048)
			(stroke
				(width 0.1)
				(type default)
			)
			(layer "B.Fab")
		)
		(fp_line
			(start 0.508 -0.3048)
			(end -0.508 -0.3048)
			(stroke
				(width 0.1)
				(type default)
			)
			(layer "B.Fab")
		)
		(fp_line
			(start -0.508 0.3048)
			(end 0.508 0.3048)
			(stroke
				(width 0.1)
				(type default)
			)
			(layer "B.Fab")
		)
		(fp_line
			(start -0.508 -0.3048)
			(end -0.508 0.3048)
			(stroke
				(width 0.1)
				(type default)
			)
			(layer "B.Fab")
		)
		(pad "1" smd circle
			(at 0.500126 0)
			(size 0.635 0.635)
			(layers "B.Cu" "B.Mask" "B.Paste")
			(net "XP3R3V_FPGA")
		)
		(pad "2" smd circle
			(at -0.500126 0)
			(size 0.635 0.635)
			(layers "B.Cu" "B.Mask" "B.Paste")
			(net "SG")
		)
	)
	(footprint ""
		(layer "B.Cu")
		(at 141.1478 -18.4404 90)
		(property "Reference" "R232"
			(at 6.4516 -0.21717 270)
			(unlocked yes)
			(layer "B.SilkS")
			(effects
				(font
					(size 0.7874 0.5842)
					(thickness 0.1524)
				)
				(justify mirror)
			)
		)
		(property "Value" "VAL*"
			(at -0.0508 2.245106 90)
			(unlocked yes)
			(layer "B.Fab")
			(hide yes)
			(effects
				(font
					(size 0.7874 0.5842)
					(thickness 0.1524)
				)
				(justify mirror)
			)
		)
		(property "Tolerance" "TOL*"
			(at -0.0508 3.261106 90)
			(unlocked yes)
			(layer "Cmts.User")
			(hide yes)
			(effects
				(font
					(size 0.7874 0.5842)
					(thickness 0.1524)
				)
				(justify mirror)
			)
		)
		(property "Device Type" "RESISTOR-G155-02101-01,2.1KOHMA"
			(at -0.0762 1.254506 90)
			(unlocked yes)
			(layer "B.Fab")
			(hide yes)
			(effects
				(font
					(size 0.7874 0.5842)
					(thickness 0.1524)
				)
				(justify mirror)
			)
		)
		(property "User Part Number" "PARTNUM*"
			(at -0.0762 4.302506 90)
			(unlocked yes)
			(layer "Cmts.User")
			(hide yes)
			(effects
				(font
					(size 0.7874 0.5842)
					(thickness 0.1524)
				)
				(justify mirror)
			)
		)
		(duplicate_pad_numbers_are_jumpers no)
		(fp_line
			(start 1.143 -0.5588)
			(end 1.143 0.5588)
			(stroke
				(width 0.1)
				(type default)
			)
			(layer "B.SilkS")
		)
		(fp_line
			(start -1.143 -0.5588)
			(end 1.143 -0.5588)
			(stroke
				(width 0.1)
				(type default)
			)
			(layer "B.SilkS")
		)
		(fp_line
			(start 1.143 0.5588)
			(end -1.143 0.5588)
			(stroke
				(width 0.1)
				(type default)
			)
			(layer "B.SilkS")
		)
		(fp_line
			(start -1.143 0.5588)
			(end -1.143 -0.5588)
			(stroke
				(width 0.1)
				(type default)
			)
			(layer "B.SilkS")
		)
		(fp_rect
			(start 1.143 0.5588)
			(end -1.143 -0.5588)
			(stroke
				(width 0)
				(type default)
			)
			(fill no)
			(layer "B.CrtYd")
		)
		(fp_line
			(start 0.508 -0.3048)
			(end 0.508 0.3048)
			(stroke
				(width 0.1)
				(type default)
			)
			(layer "B.Fab")
		)
		(fp_line
			(start -0.508 -0.3048)
			(end 0.508 -0.3048)
			(stroke
				(width 0.1)
				(type default)
			)
			(layer "B.Fab")
		)
		(fp_line
			(start 0.508 0.3048)
			(end -0.508 0.3048)
			(stroke
				(width 0.1)
				(type default)
			)
			(layer "B.Fab")
		)
		(fp_line
			(start -0.508 0.3048)
			(end -0.508 -0.3048)
			(stroke
				(width 0.1)
				(type default)
			)
			(layer "B.Fab")
		)
		(pad "1" smd rect
			(at 0.5334 0 270)
			(size 0.7112 0.6096)
			(layers "B.Cu" "B.Mask" "B.Paste")
			(net "SG")
		)
		(pad "2" smd rect
			(at -0.5334 0 270)
			(size 0.7112 0.6096)
			(layers "B.Cu" "B.Mask" "B.Paste")
			(net "UNNAMED_515_ISL80101IRAJZDFN10_")
		)
		(zone
			(layer "B.Cu")
			(hatch none 0.5)
			(connect_pads
				(clearance 0)
			)
			(min_thickness 0.25)
			(keepout
				(tracks allowed)
				(vias not_allowed)
				(pads allowed)
				(copperpour not_allowed)
				(footprints allowed)
			)
			(placement
				(enabled no)
				(sheetname "")
			)
			(fill
				(thermal_gap 0.5)
				(thermal_bridge_width 0.5)
				(island_removal_mode 0)
			)
			(polygon
				(pts
					(xy 141.4526 -18.5166) (xy 140.843 -18.5166) (xy 140.843 -18.3642) (xy 141.4526 -18.3642)
				)
			)
		)
	)
	(footprint ""
		(layer "B.Cu")
		(at 106.847132 -41.323006 90)
		(property "Reference" "C120"
			(at -1.015746 -41.382442 270)
			(unlocked yes)
			(layer "B.SilkS")
			(effects
				(font
					(size 0.635 0.4064)
					(thickness 0.1524)
				)
				(justify mirror)
			)
		)
		(property "Value" "VAL*"
			(at 0 3.718306 90)
			(unlocked yes)
			(layer "B.Fab")
			(hide yes)
			(effects
				(font
					(size 0.7874 0.5842)
					(thickness 0.127)
				)
				(justify mirror)
			)
		)
		(property "Device Type" "CAPACITOR-G105-0F475-BM,4.7UF,A"
			(at 0 1.432306 90)
			(unlocked yes)
			(layer "B.Fab")
			(hide yes)
			(effects
				(font
					(size 0.7874 0.5842)
					(thickness 0.127)
				)
				(justify mirror)
			)
		)
		(property "User Part Number" "PARTNUM*"
			(at 0 2.575306 90)
			(unlocked yes)
			(layer "Cmts.User")
			(hide yes)
			(effects
				(font
					(size 0.7874 0.5842)
					(thickness 0.127)
				)
				(justify mirror)
			)
		)
		(property "Tolerance" "TOL*"
			(at 0 4.861306 90)
			(unlocked yes)
			(layer "Cmts.User")
			(hide yes)
			(effects
				(font
					(size 0.7874 0.5842)
					(thickness 0.127)
				)
				(justify mirror)
			)
		)
		(duplicate_pad_numbers_are_jumpers no)
		(fp_line
			(start 0.970026 -0.4699)
			(end -0.970026 -0.4699)
			(stroke
				(width 0.1)
				(type default)
			)
			(layer "B.SilkS")
		)
		(fp_line
			(start -0.970026 -0.4699)
			(end -0.970026 0.4699)
			(stroke
				(width 0.1)
				(type default)
			)
			(layer "B.SilkS")
		)
		(fp_line
			(start 0.970026 0.4699)
			(end 0.970026 -0.4699)
			(stroke
				(width 0.1)
				(type default)
			)
			(layer "B.SilkS")
		)
		(fp_line
			(start -0.970026 0.4699)
			(end 0.970026 0.4699)
			(stroke
				(width 0.1)
				(type default)
			)
			(layer "B.SilkS")
		)
		(fp_poly
			(pts
				(xy 0.970026 0.4699) (xy -0.970026 0.4699) (xy -0.970026 -0.4699) (xy 0.970026 -0.4699)
			)
			(stroke
				(width 0)
				(type default)
			)
			(fill no)
			(layer "B.CrtYd")
		)
		(fp_line
			(start 0.508 -0.3048)
			(end -0.508 -0.3048)
			(stroke
				(width 0.1)
				(type default)
			)
			(layer "B.Fab")
		)
		(fp_line
			(start -0.508 -0.3048)
			(end -0.508 0.3048)
			(stroke
				(width 0.1)
				(type default)
			)
			(layer "B.Fab")
		)
		(fp_line
			(start 0.508 0.3048)
			(end 0.508 -0.3048)
			(stroke
				(width 0.1)
				(type default)
			)
			(layer "B.Fab")
		)
		(fp_line
			(start -0.508 0.3048)
			(end 0.508 0.3048)
			(stroke
				(width 0.1)
				(type default)
			)
			(layer "B.Fab")
		)
		(pad "1" smd circle
			(at 0.500126 0 270)
			(size 0.635 0.635)
			(layers "B.Cu" "B.Mask" "B.Paste")
			(net "XP1R8V_FPGA_VCCAUX")
		)
		(pad "2" smd circle
			(at -0.500126 0 270)
			(size 0.635 0.635)
			(layers "B.Cu" "B.Mask" "B.Paste")
			(net "SG")
		)
	)
	(footprint ""
		(layer "B.Cu")
		(at 118.347236 -45.823124 180)
		(property "Reference" "C139"
			(at -2.302764 -1.277874 0)
			(unlocked yes)
			(layer "B.SilkS")
			(effects
				(font
					(size 0.635 0.4064)
					(thickness 0.1524)
				)
				(justify mirror)
			)
		)
		(property "Value" "VAL*"
			(at 0 3.718306 180)
			(unlocked yes)
			(layer "B.Fab")
			(hide yes)
			(effects
				(font
					(size 0.7874 0.5842)
					(thickness 0.127)
				)
				(justify mirror)
			)
		)
		(property "Tolerance" "TOL*"
			(at 0 4.861306 180)
			(unlocked yes)
			(layer "Cmts.User")
			(hide yes)
			(effects
				(font
					(size 0.7874 0.5842)
					(thickness 0.127)
				)
				(justify mirror)
			)
		)
		(property "User Part Number" "PARTNUM*"
			(at 0 2.575306 180)
			(unlocked yes)
			(layer "Cmts.User")
			(hide yes)
			(effects
				(font
					(size 0.7874 0.5842)
					(thickness 0.127)
				)
				(justify mirror)
			)
		)
		(property "Device Type" "CAPACITOR-G105-0B104-CK,0.1UF,A"
			(at 0 1.432306 180)
			(unlocked yes)
			(layer "B.Fab")
			(hide yes)
			(effects
				(font
					(size 0.7874 0.5842)
					(thickness 0.127)
				)
				(justify mirror)
			)
		)
		(duplicate_pad_numbers_are_jumpers no)
		(fp_line
			(start 0.970026 0.4699)
			(end 0.970026 -0.4699)
			(stroke
				(width 0.1)
				(type default)
			)
			(layer "B.SilkS")
		)
		(fp_line
			(start 0.970026 -0.4699)
			(end -0.970026 -0.4699)
			(stroke
				(width 0.1)
				(type default)
			)
			(layer "B.SilkS")
		)
		(fp_line
			(start -0.970026 0.4699)
			(end 0.970026 0.4699)
			(stroke
				(width 0.1)
				(type default)
			)
			(layer "B.SilkS")
		)
		(fp_line
			(start -0.970026 -0.4699)
			(end -0.970026 0.4699)
			(stroke
				(width 0.1)
				(type default)
			)
			(layer "B.SilkS")
		)
		(fp_poly
			(pts
				(xy 0.970026 0.4699) (xy -0.970026 0.4699) (xy -0.970026 -0.4699) (xy 0.970026 -0.4699)
			)
			(stroke
				(width 0)
				(type default)
			)
			(fill no)
			(layer "B.CrtYd")
		)
		(fp_line
			(start 0.508 0.3048)
			(end 0.508 -0.3048)
			(stroke
				(width 0.1)
				(type default)
			)
			(layer "B.Fab")
		)
		(fp_line
			(start 0.508 -0.3048)
			(end -0.508 -0.3048)
			(stroke
				(width 0.1)
				(type default)
			)
			(layer "B.Fab")
		)
		(fp_line
			(start -0.508 0.3048)
			(end 0.508 0.3048)
			(stroke
				(width 0.1)
				(type default)
			)
			(layer "B.Fab")
		)
		(fp_line
			(start -0.508 -0.3048)
			(end -0.508 0.3048)
			(stroke
				(width 0.1)
				(type default)
			)
			(layer "B.Fab")
		)
		(pad "1" smd circle
			(at 0.500126 0)
			(size 0.635 0.635)
			(layers "B.Cu" "B.Mask" "B.Paste")
			(net "XP3R3V_FPGA")
		)
		(pad "2" smd circle
			(at -0.500126 0)
			(size 0.635 0.635)
			(layers "B.Cu" "B.Mask" "B.Paste")
			(net "SG")
		)
	)
	(footprint ""
		(layer "B.Cu")
		(at 156.718 -36.957 -90)
		(property "Reference" "R329"
			(at 5.24637 0.635 0)
			(unlocked yes)
			(layer "B.SilkS")
			(effects
				(font
					(size 0.7874 0.5842)
					(thickness 0.1524)
				)
				(justify mirror)
			)
		)
		(property "Value" "VAL*"
			(at -0.02032 2.13233 270)
			(unlocked yes)
			(layer "B.Fab")
			(hide yes)
			(effects
				(font
					(size 0.7874 0.5842)
					(thickness 0.1524)
				)
				(justify mirror)
			)
		)
		(property "Tolerance" "TOL*"
			(at -0.044704 3.05435 270)
			(unlocked yes)
			(layer "Cmts.User")
			(hide yes)
			(effects
				(font
					(size 0.7874 0.5842)
					(thickness 0.1524)
				)
				(justify mirror)
			)
		)
		(property "User Part Number" "PARTNUM*"
			(at -0.02032 4.024884 270)
			(unlocked yes)
			(layer "Cmts.User")
			(hide yes)
			(effects
				(font
					(size 0.7874 0.5842)
					(thickness 0.1524)
				)
				(justify mirror)
			)
		)
		(property "Device Type" "RESISTOR-G155-133R0-01,33OHM,1%"
			(at -0.008382 1.210564 270)
			(unlocked yes)
			(layer "B.Fab")
			(hide yes)
			(effects
				(font
					(size 0.7874 0.5842)
					(thickness 0.1524)
				)
				(justify mirror)
			)
		)
		(duplicate_pad_numbers_are_jumpers no)
		(fp_line
			(start -1.143 0.5588)
			(end -1.143 -0.5588)
			(stroke
				(width 0.1)
				(type default)
			)
			(layer "B.SilkS")
		)
		(fp_line
			(start 1.143 0.5588)
			(end -1.143 0.5588)
			(stroke
				(width 0.1)
				(type default)
			)
			(layer "B.SilkS")
		)
		(fp_line
			(start -1.143 -0.5588)
			(end 1.143 -0.5588)
			(stroke
				(width 0.1)
				(type default)
			)
			(layer "B.SilkS")
		)
		(fp_line
			(start 1.143 -0.5588)
			(end 1.143 0.5588)
			(stroke
				(width 0.1)
				(type default)
			)
			(layer "B.SilkS")
		)
		(fp_poly
			(pts
				(xy 1.143 0.5588) (xy -1.143 0.5588) (xy -1.143 -0.5588) (xy 1.143 -0.5588)
			)
			(stroke
				(width 0)
				(type default)
			)
			(fill no)
			(layer "B.CrtYd")
		)
		(fp_line
			(start -0.508 0.3048)
			(end -0.508 -0.3048)
			(stroke
				(width 0.1)
				(type default)
			)
			(layer "B.Fab")
		)
		(fp_line
			(start 0.508 0.3048)
			(end -0.508 0.3048)
			(stroke
				(width 0.1)
				(type default)
			)
			(layer "B.Fab")
		)
		(fp_line
			(start -0.508 -0.3048)
			(end 0.508 -0.3048)
			(stroke
				(width 0.1)
				(type default)
			)
			(layer "B.Fab")
		)
		(fp_line
			(start 0.508 -0.3048)
			(end 0.508 0.3048)
			(stroke
				(width 0.1)
				(type default)
			)
			(layer "B.Fab")
		)
		(pad "1" smd rect
			(at 0.5334 0 90)
			(size 0.7112 0.6096)
			(layers "B.Cu" "B.Mask" "B.Paste")
			(net "FPGA_IO_7")
		)
		(pad "2" smd rect
			(at -0.5334 0 90)
			(size 0.7112 0.6096)
			(layers "B.Cu" "B.Mask" "B.Paste")
			(net "UNNAMED_16_CONNHDR2X6FSSMT_I1_4")
		)
		(zone
			(layer "B.Cu")
			(hatch none 0.5)
			(connect_pads
				(clearance 0)
			)
			(min_thickness 0.25)
			(keepout
				(tracks not_allowed)
				(vias allowed)
				(pads allowed)
				(copperpour not_allowed)
				(footprints allowed)
			)
			(placement
				(enabled no)
				(sheetname "")
			)
			(fill
				(thermal_gap 0.5)
				(thermal_bridge_width 0.5)
				(island_removal_mode 0)
			)
			(polygon
				(pts
					(xy 156.4132 -36.8808) (xy 157.0228 -36.8808) (xy 157.0228 -37.0332) (xy 156.4132 -37.0332)
				)
			)
		)
		(zone
			(layer "B.Cu")
			(hatch none 0.5)
			(connect_pads
				(clearance 0)
			)
			(min_thickness 0.25)
			(keepout
				(tracks allowed)
				(vias not_allowed)
				(pads allowed)
				(copperpour not_allowed)
				(footprints allowed)
			)
			(placement
				(enabled no)
				(sheetname "")
			)
			(fill
				(thermal_gap 0.5)
				(thermal_bridge_width 0.5)
				(island_removal_mode 0)
			)
			(polygon
				(pts
					(xy 156.4132 -36.8808) (xy 157.0228 -36.8808) (xy 157.0228 -37.0332) (xy 156.4132 -37.0332)
				)
			)
		)
	)
	(footprint ""
		(layer "B.Cu")
		(at 80.899 -99.06 90)
		(property "Reference" "C57"
			(at 0.127 -1.43637 270)
			(unlocked yes)
			(layer "B.SilkS")
			(effects
				(font
					(size 0.7874 0.5842)
					(thickness 0.1524)
				)
				(justify mirror)
			)
		)
		(property "Value" "VAL*"
			(at -0.0762 2.067306 90)
			(unlocked yes)
			(layer "B.Fab")
			(hide yes)
			(effects
				(font
					(size 0.7874 0.5842)
					(thickness 0.1524)
				)
				(justify mirror)
			)
		)
		(property "Tolerance" "TOL*"
			(at -0.0762 3.032506 90)
			(unlocked yes)
			(layer "Cmts.User")
			(hide yes)
			(effects
				(font
					(size 0.7874 0.5842)
					(thickness 0.1524)
				)
				(justify mirror)
			)
		)
		(property "User Part Number" "PARTNUM*"
			(at -0.1016 4.023106 90)
			(unlocked yes)
			(layer "Cmts.User")
			(hide yes)
			(effects
				(font
					(size 0.7874 0.5842)
					(thickness 0.1524)
				)
				(justify mirror)
			)
		)
		(property "Device Type" "CAPACITOR-G105-0A102-FJ,1000PFA"
			(at -0.0508 1.127506 90)
			(unlocked yes)
			(layer "B.Fab")
			(hide yes)
			(effects
				(font
					(size 0.7874 0.5842)
					(thickness 0.1524)
				)
				(justify mirror)
			)
		)
		(duplicate_pad_numbers_are_jumpers no)
		(fp_line
			(start 1.143 -0.5588)
			(end 1.143 0.5588)
			(stroke
				(width 0.1)
				(type default)
			)
			(layer "B.SilkS")
		)
		(fp_line
			(start -1.143 -0.5588)
			(end 1.143 -0.5588)
			(stroke
				(width 0.1)
				(type default)
			)
			(layer "B.SilkS")
		)
		(fp_line
			(start 1.143 0.5588)
			(end -1.143 0.5588)
			(stroke
				(width 0.1)
				(type default)
			)
			(layer "B.SilkS")
		)
		(fp_line
			(start -1.143 0.5588)
			(end -1.143 -0.5588)
			(stroke
				(width 0.1)
				(type default)
			)
			(layer "B.SilkS")
		)
		(fp_rect
			(start -1.143 -0.5588)
			(end 1.143 0.5588)
			(stroke
				(width 0)
				(type default)
			)
			(fill no)
			(layer "B.CrtYd")
		)
		(fp_line
			(start 0.508 -0.3048)
			(end 0.508 0.3048)
			(stroke
				(width 0.1)
				(type default)
			)
			(layer "B.Fab")
		)
		(fp_line
			(start -0.508 -0.3048)
			(end 0.508 -0.3048)
			(stroke
				(width 0.1)
				(type default)
			)
			(layer "B.Fab")
		)
		(fp_line
			(start 0.508 0.3048)
			(end -0.508 0.3048)
			(stroke
				(width 0.1)
				(type default)
			)
			(layer "B.Fab")
		)
		(fp_line
			(start -0.508 0.3048)
			(end -0.508 -0.3048)
			(stroke
				(width 0.1)
				(type default)
			)
			(layer "B.Fab")
		)
		(pad "1" smd rect
			(at 0.5334 0 270)
			(size 0.7112 0.6096)
			(layers "B.Cu" "B.Mask" "B.Paste")
			(net "XP3R3V_SW")
		)
		(pad "2" smd rect
			(at -0.5334 0 270)
			(size 0.7112 0.6096)
			(layers "B.Cu" "B.Mask" "B.Paste")
			(net "UNNAMED_517_CAPACITOR_I29_2")
		)
		(zone
			(layer "B.Cu")
			(hatch none 0.5)
			(connect_pads
				(clearance 0)
			)
			(min_thickness 0.25)
			(keepout
				(tracks allowed)
				(vias not_allowed)
				(pads allowed)
				(copperpour not_allowed)
				(footprints allowed)
			)
			(placement
				(enabled no)
				(sheetname "")
			)
			(fill
				(thermal_gap 0.5)
				(thermal_bridge_width 0.5)
				(island_removal_mode 0)
			)
			(polygon
				(pts
					(xy 80.5942 -98.9838) (xy 81.2038 -98.9838) (xy 81.2038 -99.1362) (xy 80.5942 -99.1362)
				)
			)
		)
	)
	(footprint ""
		(layer "B.Cu")
		(at 70.866 -55.499 -90)
		(property "Reference" "C71"
			(at 2.159 -0.21463 270)
			(unlocked yes)
			(layer "B.SilkS")
			(effects
				(font
					(size 0.7874 0.5842)
					(thickness 0.1524)
				)
				(justify mirror)
			)
		)
		(property "Value" "VAL*"
			(at -0.0762 2.067306 270)
			(unlocked yes)
			(layer "B.Fab")
			(hide yes)
			(effects
				(font
					(size 0.7874 0.5842)
					(thickness 0.1524)
				)
				(justify mirror)
			)
		)
		(property "Device Type" "CAPACITOR-G105-0B104-EK,0.1UF,A"
			(at -0.0508 1.127506 270)
			(unlocked yes)
			(layer "B.Fab")
			(hide yes)
			(effects
				(font
					(size 0.7874 0.5842)
					(thickness 0.1524)
				)
				(justify mirror)
			)
		)
		(property "User Part Number" "PARTNUM*"
			(at -0.1016 4.023106 270)
			(unlocked yes)
			(layer "Cmts.User")
			(hide yes)
			(effects
				(font
					(size 0.7874 0.5842)
					(thickness 0.1524)
				)
				(justify mirror)
			)
		)
		(property "Tolerance" "TOL*"
			(at -0.0762 3.032506 270)
			(unlocked yes)
			(layer "Cmts.User")
			(hide yes)
			(effects
				(font
					(size 0.7874 0.5842)
					(thickness 0.1524)
				)
				(justify mirror)
			)
		)
		(duplicate_pad_numbers_are_jumpers no)
		(fp_line
			(start -1.143 0.5588)
			(end -1.143 -0.5588)
			(stroke
				(width 0.1)
				(type default)
			)
			(layer "B.SilkS")
		)
		(fp_line
			(start 1.143 0.5588)
			(end -1.143 0.5588)
			(stroke
				(width 0.1)
				(type default)
			)
			(layer "B.SilkS")
		)
		(fp_line
			(start -1.143 -0.5588)
			(end 1.143 -0.5588)
			(stroke
				(width 0.1)
				(type default)
			)
			(layer "B.SilkS")
		)
		(fp_line
			(start 1.143 -0.5588)
			(end 1.143 0.5588)
			(stroke
				(width 0.1)
				(type default)
			)
			(layer "B.SilkS")
		)
		(fp_rect
			(start 1.143 0.5588)
			(end -1.143 -0.5588)
			(stroke
				(width 0)
				(type default)
			)
			(fill no)
			(layer "B.CrtYd")
		)
		(fp_line
			(start -0.508 0.3048)
			(end -0.508 -0.3048)
			(stroke
				(width 0.1)
				(type default)
			)
			(layer "B.Fab")
		)
		(fp_line
			(start 0.508 0.3048)
			(end -0.508 0.3048)
			(stroke
				(width 0.1)
				(type default)
			)
			(layer "B.Fab")
		)
		(fp_line
			(start -0.508 -0.3048)
			(end 0.508 -0.3048)
			(stroke
				(width 0.1)
				(type default)
			)
			(layer "B.Fab")
		)
		(fp_line
			(start 0.508 -0.3048)
			(end 0.508 0.3048)
			(stroke
				(width 0.1)
				(type default)
			)
			(layer "B.Fab")
		)
		(pad "1" smd rect
			(at 0.5334 0 90)
			(size 0.7112 0.6096)
			(layers "B.Cu" "B.Mask" "B.Paste")
			(net "XP5R0V_MAC_USB")
		)
		(pad "2" smd rect
			(at -0.5334 0 90)
			(size 0.7112 0.6096)
			(layers "B.Cu" "B.Mask" "B.Paste")
			(net "SG")
		)
		(zone
			(layer "B.Cu")
			(hatch none 0.5)
			(connect_pads
				(clearance 0)
			)
			(min_thickness 0.25)
			(keepout
				(tracks allowed)
				(vias not_allowed)
				(pads allowed)
				(copperpour not_allowed)
				(footprints allowed)
			)
			(placement
				(enabled no)
				(sheetname "")
			)
			(fill
				(thermal_gap 0.5)
				(thermal_bridge_width 0.5)
				(island_removal_mode 0)
			)
			(polygon
				(pts
					(xy 70.5612 -55.4228) (xy 71.1708 -55.4228) (xy 71.1708 -55.5752) (xy 70.5612 -55.5752)
				)
			)
		)
	)
	(footprint ""
		(layer "B.Cu")
		(at 102.489 -59.055)
		(property "Reference" "C172"
			(at -0.254 -2.11963 0)
			(unlocked yes)
			(layer "B.SilkS")
			(effects
				(font
					(size 0.7874 0.5842)
					(thickness 0.1524)
				)
				(justify mirror)
			)
		)
		(property "Value" "VAL*"
			(at -0.1016 3.769106 0)
			(unlocked yes)
			(layer "B.Fab")
			(hide yes)
			(effects
				(font
					(size 0.7874 0.5842)
					(thickness 0.1524)
				)
				(justify mirror)
			)
		)
		(property "Device Type" "CAPACITOR-G109-0G107-BM,100UF,A"
			(at -0.0762 2.829306 0)
			(unlocked yes)
			(layer "B.Fab")
			(hide yes)
			(effects
				(font
					(size 0.7874 0.5842)
					(thickness 0.1524)
				)
				(justify mirror)
			)
		)
		(property "User Part Number" "PARTNUM*"
			(at -0.2032 5.801106 0)
			(unlocked yes)
			(layer "Cmts.User")
			(hide yes)
			(effects
				(font
					(size 0.7874 0.5842)
					(thickness 0.1524)
				)
				(justify mirror)
			)
		)
		(property "Tolerance" "TOL*"
			(at -0.127 4.734306 0)
			(unlocked yes)
			(layer "Cmts.User")
			(hide yes)
			(effects
				(font
					(size 0.7874 0.5842)
					(thickness 0.1524)
				)
				(justify mirror)
			)
		)
		(duplicate_pad_numbers_are_jumpers no)
		(fp_line
			(start -2.159 -1.5748)
			(end -2.159 1.5748)
			(stroke
				(width 0.1)
				(type default)
			)
			(layer "B.SilkS")
		)
		(fp_line
			(start -2.159 1.5748)
			(end 2.159 1.5748)
			(stroke
				(width 0.1)
				(type default)
			)
			(layer "B.SilkS")
		)
		(fp_line
			(start 2.159 -1.5748)
			(end -2.159 -1.5748)
			(stroke
				(width 0.1)
				(type default)
			)
			(layer "B.SilkS")
		)
		(fp_line
			(start 2.159 1.5748)
			(end 2.159 -1.5748)
			(stroke
				(width 0.1)
				(type default)
			)
			(layer "B.SilkS")
		)
		(fp_rect
			(start 2.159 -1.5748)
			(end -2.159 1.5748)
			(stroke
				(width 0)
				(type default)
			)
			(fill no)
			(layer "B.CrtYd")
		)
		(fp_line
			(start -1.6002 -1.2446)
			(end 1.6002 -1.2446)
			(stroke
				(width 0.1)
				(type default)
			)
			(layer "B.Fab")
		)
		(fp_line
			(start -1.6002 1.2446)
			(end -1.6002 -1.2446)
			(stroke
				(width 0.1)
				(type default)
			)
			(layer "B.Fab")
		)
		(fp_line
			(start 1.6002 -1.2446)
			(end 1.6002 1.2446)
			(stroke
				(width 0.1)
				(type default)
			)
			(layer "B.Fab")
		)
		(fp_line
			(start 1.6002 1.2446)
			(end -1.6002 1.2446)
			(stroke
				(width 0.1)
				(type default)
			)
			(layer "B.Fab")
		)
		(pad "1" smd rect
			(at 1.3335 0 180)
			(size 1.143 2.6416)
			(layers "B.Cu" "B.Mask" "B.Paste")
			(net "XP3R3V_FPGA")
		)
		(pad "2" smd rect
			(at -1.3335 0 180)
			(size 1.143 2.6416)
			(layers "B.Cu" "B.Mask" "B.Paste")
			(net "SG")
		)
		(zone
			(layer "B.Cu")
			(hatch none 0.5)
			(connect_pads
				(clearance 0)
			)
			(min_thickness 0.25)
			(keepout
				(tracks allowed)
				(vias not_allowed)
				(pads allowed)
				(copperpour not_allowed)
				(footprints allowed)
			)
			(placement
				(enabled no)
				(sheetname "")
			)
			(fill
				(thermal_gap 0.5)
				(thermal_bridge_width 0.5)
				(island_removal_mode 0)
			)
			(polygon
				(pts
					(xy 103.1748 -60.452) (xy 101.8032 -60.452) (xy 101.8032 -57.658) (xy 103.1748 -57.658)
				)
			)
		)
	)
	(footprint ""
		(layer "B.Cu")
		(at 45.72 -102.743 -90)
		(property "Reference" "C45"
			(at 0.1524 -1.38303 270)
			(unlocked yes)
			(layer "B.SilkS")
			(effects
				(font
					(size 0.7874 0.5842)
					(thickness 0.1524)
				)
				(justify mirror)
			)
		)
		(property "Value" "VAL*"
			(at -0.0762 2.067306 270)
			(unlocked yes)
			(layer "B.Fab")
			(hide yes)
			(effects
				(font
					(size 0.7874 0.5842)
					(thickness 0.1524)
				)
				(justify mirror)
			)
		)
		(property "Tolerance" "TOL*"
			(at -0.0762 3.032506 270)
			(unlocked yes)
			(layer "Cmts.User")
			(hide yes)
			(effects
				(font
					(size 0.7874 0.5842)
					(thickness 0.1524)
				)
				(justify mirror)
			)
		)
		(property "User Part Number" "PARTNUM*"
			(at -0.1016 4.023106 270)
			(unlocked yes)
			(layer "Cmts.User")
			(hide yes)
			(effects
				(font
					(size 0.7874 0.5842)
					(thickness 0.1524)
				)
				(justify mirror)
			)
		)
		(property "Device Type" "CAPACITOR-G105-0A102-FJ,1000PFA"
			(at -0.0508 1.127506 270)
			(unlocked yes)
			(layer "B.Fab")
			(hide yes)
			(effects
				(font
					(size 0.7874 0.5842)
					(thickness 0.1524)
				)
				(justify mirror)
			)
		)
		(duplicate_pad_numbers_are_jumpers no)
		(fp_line
			(start -1.143 0.5588)
			(end -1.143 -0.5588)
			(stroke
				(width 0.1)
				(type default)
			)
			(layer "B.SilkS")
		)
		(fp_line
			(start 1.143 0.5588)
			(end -1.143 0.5588)
			(stroke
				(width 0.1)
				(type default)
			)
			(layer "B.SilkS")
		)
		(fp_line
			(start -1.143 -0.5588)
			(end 1.143 -0.5588)
			(stroke
				(width 0.1)
				(type default)
			)
			(layer "B.SilkS")
		)
		(fp_line
			(start 1.143 -0.5588)
			(end 1.143 0.5588)
			(stroke
				(width 0.1)
				(type default)
			)
			(layer "B.SilkS")
		)
		(fp_rect
			(start -1.143 -0.5588)
			(end 1.143 0.5588)
			(stroke
				(width 0)
				(type default)
			)
			(fill no)
			(layer "B.CrtYd")
		)
		(fp_line
			(start -0.508 0.3048)
			(end -0.508 -0.3048)
			(stroke
				(width 0.1)
				(type default)
			)
			(layer "B.Fab")
		)
		(fp_line
			(start 0.508 0.3048)
			(end -0.508 0.3048)
			(stroke
				(width 0.1)
				(type default)
			)
			(layer "B.Fab")
		)
		(fp_line
			(start -0.508 -0.3048)
			(end 0.508 -0.3048)
			(stroke
				(width 0.1)
				(type default)
			)
			(layer "B.Fab")
		)
		(fp_line
			(start 0.508 -0.3048)
			(end 0.508 0.3048)
			(stroke
				(width 0.1)
				(type default)
			)
			(layer "B.Fab")
		)
		(pad "1" smd rect
			(at 0.5334 0 90)
			(size 0.7112 0.6096)
			(layers "B.Cu" "B.Mask" "B.Paste")
			(net "XP5R0V_SW")
		)
		(pad "2" smd rect
			(at -0.5334 0 90)
			(size 0.7112 0.6096)
			(layers "B.Cu" "B.Mask" "B.Paste")
			(net "UNNAMED_516_CAPACITOR_I37_2")
		)
		(zone
			(layer "B.Cu")
			(hatch none 0.5)
			(connect_pads
				(clearance 0)
			)
			(min_thickness 0.25)
			(keepout
				(tracks allowed)
				(vias not_allowed)
				(pads allowed)
				(copperpour not_allowed)
				(footprints allowed)
			)
			(placement
				(enabled no)
				(sheetname "")
			)
			(fill
				(thermal_gap 0.5)
				(thermal_bridge_width 0.5)
				(island_removal_mode 0)
			)
			(polygon
				(pts
					(xy 46.0248 -102.8192) (xy 45.4152 -102.8192) (xy 45.4152 -102.6668) (xy 46.0248 -102.6668)
				)
			)
		)
	)
	(footprint ""
		(layer "B.Cu")
		(at 137.795 -16.256)
		(property "Reference" "R230"
			(at -1.397 1.43637 0)
			(unlocked yes)
			(layer "B.SilkS")
			(effects
				(font
					(size 0.7874 0.5842)
					(thickness 0.1524)
				)
				(justify mirror)
			)
		)
		(property "Value" "VAL*"
			(at -0.02032 2.13233 0)
			(unlocked yes)
			(layer "B.Fab")
			(hide yes)
			(effects
				(font
					(size 0.7874 0.5842)
					(thickness 0.1524)
				)
				(justify mirror)
			)
		)
		(property "Tolerance" "TOL*"
			(at -0.044704 3.05435 0)
			(unlocked yes)
			(layer "Cmts.User")
			(hide yes)
			(effects
				(font
					(size 0.7874 0.5842)
					(thickness 0.1524)
				)
				(justify mirror)
			)
		)
		(property "User Part Number" "PARTNUM*"
			(at -0.02032 4.024884 0)
			(unlocked yes)
			(layer "Cmts.User")
			(hide yes)
			(effects
				(font
					(size 0.7874 0.5842)
					(thickness 0.1524)
				)
				(justify mirror)
			)
		)
		(property "Device Type" "RESISTOR-G155-100R0-J0,0OHM,-"
			(at -0.008382 1.210564 0)
			(unlocked yes)
			(layer "B.Fab")
			(hide yes)
			(effects
				(font
					(size 0.7874 0.5842)
					(thickness 0.1524)
				)
				(justify mirror)
			)
		)
		(duplicate_pad_numbers_are_jumpers no)
		(fp_line
			(start -1.143 -0.5588)
			(end 1.143 -0.5588)
			(stroke
				(width 0.1)
				(type default)
			)
			(layer "B.SilkS")
		)
		(fp_line
			(start -1.143 0.5588)
			(end -1.143 -0.5588)
			(stroke
				(width 0.1)
				(type default)
			)
			(layer "B.SilkS")
		)
		(fp_line
			(start 1.143 -0.5588)
			(end 1.143 0.5588)
			(stroke
				(width 0.1)
				(type default)
			)
			(layer "B.SilkS")
		)
		(fp_line
			(start 1.143 0.5588)
			(end -1.143 0.5588)
			(stroke
				(width 0.1)
				(type default)
			)
			(layer "B.SilkS")
		)
		(fp_rect
			(start 1.143 -0.5588)
			(end -1.143 0.5588)
			(stroke
				(width 0)
				(type default)
			)
			(fill no)
			(layer "B.CrtYd")
		)
		(fp_line
			(start -0.508 -0.3048)
			(end 0.508 -0.3048)
			(stroke
				(width 0.1)
				(type default)
			)
			(layer "B.Fab")
		)
		(fp_line
			(start -0.508 0.3048)
			(end -0.508 -0.3048)
			(stroke
				(width 0.1)
				(type default)
			)
			(layer "B.Fab")
		)
		(fp_line
			(start 0.508 -0.3048)
			(end 0.508 0.3048)
			(stroke
				(width 0.1)
				(type default)
			)
			(layer "B.Fab")
		)
		(fp_line
			(start 0.508 0.3048)
			(end -0.508 0.3048)
			(stroke
				(width 0.1)
				(type default)
			)
			(layer "B.Fab")
		)
		(pad "1" smd rect
			(at 0.5334 0 180)
			(size 0.7112 0.6096)
			(layers "B.Cu" "B.Mask" "B.Paste")
			(net "UNNAMED_515_CAPACITOR_I138_1")
		)
		(pad "2" smd rect
			(at -0.5334 0 180)
			(size 0.7112 0.6096)
			(layers "B.Cu" "B.Mask" "B.Paste")
			(net "FPGA_CFG_INIT_N")
		)
		(zone
			(layer "B.Cu")
			(hatch none 0.5)
			(connect_pads
				(clearance 0)
			)
			(min_thickness 0.25)
			(keepout
				(tracks allowed)
				(vias not_allowed)
				(pads allowed)
				(copperpour not_allowed)
				(footprints allowed)
			)
			(placement
				(enabled no)
				(sheetname "")
			)
			(fill
				(thermal_gap 0.5)
				(thermal_bridge_width 0.5)
				(island_removal_mode 0)
			)
			(polygon
				(pts
					(xy 137.8712 -16.5608) (xy 137.7188 -16.5608) (xy 137.7188 -15.9512) (xy 137.8712 -15.9512)
				)
			)
		)
	)
	(footprint ""
		(layer "B.Cu")
		(at 88.519 -84.455 180)
		(property "Reference" "R192"
			(at -0.254 5.54863 0)
			(unlocked yes)
			(layer "B.SilkS")
			(effects
				(font
					(size 0.7874 0.5842)
					(thickness 0.1524)
				)
				(justify mirror)
			)
		)
		(property "Value" "VAL*"
			(at -0.02032 2.13233 180)
			(unlocked yes)
			(layer "B.Fab")
			(hide yes)
			(effects
				(font
					(size 0.7874 0.5842)
					(thickness 0.1524)
				)
				(justify mirror)
			)
		)
		(property "Tolerance" "TOL*"
			(at -0.044704 3.05435 180)
			(unlocked yes)
			(layer "Cmts.User")
			(hide yes)
			(effects
				(font
					(size 0.7874 0.5842)
					(thickness 0.1524)
				)
				(justify mirror)
			)
		)
		(property "User Part Number" "PARTNUM*"
			(at -0.02032 4.024884 180)
			(unlocked yes)
			(layer "Cmts.User")
			(hide yes)
			(effects
				(font
					(size 0.7874 0.5842)
					(thickness 0.1524)
				)
				(justify mirror)
			)
		)
		(property "Device Type" "RESISTOR-G155-14701-01,4.7KOHMA"
			(at -0.008382 1.210564 180)
			(unlocked yes)
			(layer "B.Fab")
			(hide yes)
			(effects
				(font
					(size 0.7874 0.5842)
					(thickness 0.1524)
				)
				(justify mirror)
			)
		)
		(duplicate_pad_numbers_are_jumpers no)
		(fp_line
			(start 1.143 0.5588)
			(end -1.143 0.5588)
			(stroke
				(width 0.1)
				(type default)
			)
			(layer "B.SilkS")
		)
		(fp_line
			(start 1.143 -0.5588)
			(end 1.143 0.5588)
			(stroke
				(width 0.1)
				(type default)
			)
			(layer "B.SilkS")
		)
		(fp_line
			(start -1.143 0.5588)
			(end -1.143 -0.5588)
			(stroke
				(width 0.1)
				(type default)
			)
			(layer "B.SilkS")
		)
		(fp_line
			(start -1.143 -0.5588)
			(end 1.143 -0.5588)
			(stroke
				(width 0.1)
				(type default)
			)
			(layer "B.SilkS")
		)
		(fp_rect
			(start 1.143 -0.5588)
			(end -1.143 0.5588)
			(stroke
				(width 0)
				(type default)
			)
			(fill no)
			(layer "B.CrtYd")
		)
		(fp_line
			(start 0.508 0.3048)
			(end -0.508 0.3048)
			(stroke
				(width 0.1)
				(type default)
			)
			(layer "B.Fab")
		)
		(fp_line
			(start 0.508 -0.3048)
			(end 0.508 0.3048)
			(stroke
				(width 0.1)
				(type default)
			)
			(layer "B.Fab")
		)
		(fp_line
			(start -0.508 0.3048)
			(end -0.508 -0.3048)
			(stroke
				(width 0.1)
				(type default)
			)
			(layer "B.Fab")
		)
		(fp_line
			(start -0.508 -0.3048)
			(end 0.508 -0.3048)
			(stroke
				(width 0.1)
				(type default)
			)
			(layer "B.Fab")
		)
		(pad "1" smd rect
			(at 0.5334 0)
			(size 0.7112 0.6096)
			(layers "B.Cu" "B.Mask" "B.Paste")
			(net "FLASH_CLK")
		)
		(pad "2" smd rect
			(at -0.5334 0)
			(size 0.7112 0.6096)
			(layers "B.Cu" "B.Mask" "B.Paste")
			(net "SG")
		)
		(zone
			(layer "B.Cu")
			(hatch none 0.5)
			(connect_pads
				(clearance 0)
			)
			(min_thickness 0.25)
			(keepout
				(tracks allowed)
				(vias not_allowed)
				(pads allowed)
				(copperpour not_allowed)
				(footprints allowed)
			)
			(placement
				(enabled no)
				(sheetname "")
			)
			(fill
				(thermal_gap 0.5)
				(thermal_bridge_width 0.5)
				(island_removal_mode 0)
			)
			(polygon
				(pts
					(xy 88.4428 -84.1502) (xy 88.5952 -84.1502) (xy 88.5952 -84.7598) (xy 88.4428 -84.7598)
				)
			)
		)
	)
	(footprint ""
		(layer "B.Cu")
		(at 144.018 -107.696 90)
		(property "Reference" "R259"
			(at -0.762 1.16205 270)
			(unlocked yes)
			(layer "B.SilkS")
			(effects
				(font
					(size 0.635 0.4064)
					(thickness 0.1524)
				)
				(justify mirror)
			)
		)
		(property "Value" "VAL*"
			(at -0.02032 2.13233 90)
			(unlocked yes)
			(layer "B.Fab")
			(hide yes)
			(effects
				(font
					(size 0.7874 0.5842)
					(thickness 0.1524)
				)
				(justify mirror)
			)
		)
		(property "Device Type" "RESISTOR-G155-13300-01,330OHM,A"
			(at -0.008382 1.210564 90)
			(unlocked yes)
			(layer "B.Fab")
			(hide yes)
			(effects
				(font
					(size 0.7874 0.5842)
					(thickness 0.1524)
				)
				(justify mirror)
			)
		)
		(property "User Part Number" "PARTNUM*"
			(at -0.02032 4.024884 90)
			(unlocked yes)
			(layer "Cmts.User")
			(hide yes)
			(effects
				(font
					(size 0.7874 0.5842)
					(thickness 0.1524)
				)
				(justify mirror)
			)
		)
		(property "Tolerance" "TOL*"
			(at -0.044704 3.05435 90)
			(unlocked yes)
			(layer "Cmts.User")
			(hide yes)
			(effects
				(font
					(size 0.7874 0.5842)
					(thickness 0.1524)
				)
				(justify mirror)
			)
		)
		(duplicate_pad_numbers_are_jumpers no)
		(fp_line
			(start 1.143 -0.5588)
			(end 1.143 0.5588)
			(stroke
				(width 0.1)
				(type default)
			)
			(layer "B.SilkS")
		)
		(fp_line
			(start -1.143 -0.5588)
			(end 1.143 -0.5588)
			(stroke
				(width 0.1)
				(type default)
			)
			(layer "B.SilkS")
		)
		(fp_line
			(start 1.143 0.5588)
			(end -1.143 0.5588)
			(stroke
				(width 0.1)
				(type default)
			)
			(layer "B.SilkS")
		)
		(fp_line
			(start -1.143 0.5588)
			(end -1.143 -0.5588)
			(stroke
				(width 0.1)
				(type default)
			)
			(layer "B.SilkS")
		)
		(fp_rect
			(start -1.143 -0.5588)
			(end 1.143 0.5588)
			(stroke
				(width 0)
				(type default)
			)
			(fill no)
			(layer "B.CrtYd")
		)
		(fp_line
			(start 0.508 -0.3048)
			(end 0.508 0.3048)
			(stroke
				(width 0.1)
				(type default)
			)
			(layer "B.Fab")
		)
		(fp_line
			(start -0.508 -0.3048)
			(end 0.508 -0.3048)
			(stroke
				(width 0.1)
				(type default)
			)
			(layer "B.Fab")
		)
		(fp_line
			(start 0.508 0.3048)
			(end -0.508 0.3048)
			(stroke
				(width 0.1)
				(type default)
			)
			(layer "B.Fab")
		)
		(fp_line
			(start -0.508 0.3048)
			(end -0.508 -0.3048)
			(stroke
				(width 0.1)
				(type default)
			)
			(layer "B.Fab")
		)
		(pad "1" smd rect
			(at 0.5334 0 270)
			(size 0.7112 0.6096)
			(layers "B.Cu" "B.Mask" "B.Paste")
			(net "UNNAMED_14_OPTICAL_I136_A")
		)
		(pad "2" smd rect
			(at -0.5334 0 270)
			(size 0.7112 0.6096)
			(layers "B.Cu" "B.Mask" "B.Paste")
			(net "XP3R3V_FPGA")
		)
		(zone
			(layer "B.Cu")
			(hatch none 0.5)
			(connect_pads
				(clearance 0)
			)
			(min_thickness 0.25)
			(keepout
				(tracks allowed)
				(vias not_allowed)
				(pads allowed)
				(copperpour not_allowed)
				(footprints allowed)
			)
			(placement
				(enabled no)
				(sheetname "")
			)
			(fill
				(thermal_gap 0.5)
				(thermal_bridge_width 0.5)
				(island_removal_mode 0)
			)
			(polygon
				(pts
					(xy 143.7132 -107.6198) (xy 144.3228 -107.6198) (xy 144.3228 -107.7722) (xy 143.7132 -107.7722)
				)
			)
		)
	)
	(footprint ""
		(layer "B.Cu")
		(at 38.1 -76.2)
		(property "Reference" "R491"
			(at -0.508 -1.10363 0)
			(unlocked yes)
			(layer "B.SilkS")
			(effects
				(font
					(size 0.7874 0.5842)
					(thickness 0.1524)
				)
				(justify mirror)
			)
		)
		(property "Value" "VAL*"
			(at -0.02032 2.13233 0)
			(unlocked yes)
			(layer "B.Fab")
			(hide yes)
			(effects
				(font
					(size 0.7874 0.5842)
					(thickness 0.1524)
				)
				(justify mirror)
			)
		)
		(property "Tolerance" "TOL*"
			(at -0.044704 3.05435 0)
			(unlocked yes)
			(layer "Cmts.User")
			(hide yes)
			(effects
				(font
					(size 0.7874 0.5842)
					(thickness 0.1524)
				)
				(justify mirror)
			)
		)
		(property "User Part Number" "PARTNUM*"
			(at -0.02032 4.024884 0)
			(unlocked yes)
			(layer "Cmts.User")
			(hide yes)
			(effects
				(font
					(size 0.7874 0.5842)
					(thickness 0.1524)
				)
				(justify mirror)
			)
		)
		(property "Device Type" "RESISTOR-G155-03241-01,3.24KOHA"
			(at -0.008382 1.210564 0)
			(unlocked yes)
			(layer "B.Fab")
			(hide yes)
			(effects
				(font
					(size 0.7874 0.5842)
					(thickness 0.1524)
				)
				(justify mirror)
			)
		)
		(duplicate_pad_numbers_are_jumpers no)
		(fp_line
			(start -1.143 -0.5588)
			(end 1.143 -0.5588)
			(stroke
				(width 0.1)
				(type default)
			)
			(layer "B.SilkS")
		)
		(fp_line
			(start -1.143 0.5588)
			(end -1.143 -0.5588)
			(stroke
				(width 0.1)
				(type default)
			)
			(layer "B.SilkS")
		)
		(fp_line
			(start 1.143 -0.5588)
			(end 1.143 0.5588)
			(stroke
				(width 0.1)
				(type default)
			)
			(layer "B.SilkS")
		)
		(fp_line
			(start 1.143 0.5588)
			(end -1.143 0.5588)
			(stroke
				(width 0.1)
				(type default)
			)
			(layer "B.SilkS")
		)
		(fp_poly
			(pts
				(xy 1.143 0.5588) (xy -1.143 0.5588) (xy -1.143 -0.5588) (xy 1.143 -0.5588)
			)
			(stroke
				(width 0)
				(type default)
			)
			(fill no)
			(layer "B.CrtYd")
		)
		(fp_line
			(start -0.508 -0.3048)
			(end 0.508 -0.3048)
			(stroke
				(width 0.1)
				(type default)
			)
			(layer "B.Fab")
		)
		(fp_line
			(start -0.508 0.3048)
			(end -0.508 -0.3048)
			(stroke
				(width 0.1)
				(type default)
			)
			(layer "B.Fab")
		)
		(fp_line
			(start 0.508 -0.3048)
			(end 0.508 0.3048)
			(stroke
				(width 0.1)
				(type default)
			)
			(layer "B.Fab")
		)
		(fp_line
			(start 0.508 0.3048)
			(end -0.508 0.3048)
			(stroke
				(width 0.1)
				(type default)
			)
			(layer "B.Fab")
		)
		(pad "1" smd rect
			(at 0.5334 0 180)
			(size 0.7112 0.6096)
			(layers "B.Cu" "B.Mask" "B.Paste")
			(net "UNNAMED_525_ISL80101IRAJZDFN10_")
		)
		(pad "2" smd rect
			(at -0.5334 0 180)
			(size 0.7112 0.6096)
			(layers "B.Cu" "B.Mask" "B.Paste")
			(net "SG")
		)
		(zone
			(layer "B.Cu")
			(hatch none 0.5)
			(connect_pads
				(clearance 0)
			)
			(min_thickness 0.25)
			(keepout
				(tracks allowed)
				(vias not_allowed)
				(pads allowed)
				(copperpour not_allowed)
				(footprints allowed)
			)
			(placement
				(enabled no)
				(sheetname "")
			)
			(fill
				(thermal_gap 0.5)
				(thermal_bridge_width 0.5)
				(island_removal_mode 0)
			)
			(polygon
				(pts
					(xy 38.1762 -75.8952) (xy 38.1762 -76.5048) (xy 38.0238 -76.5048) (xy 38.0238 -75.8952)
				)
			)
		)
		(zone
			(layer "B.Cu")
			(hatch none 0.5)
			(connect_pads
				(clearance 0)
			)
			(min_thickness 0.25)
			(keepout
				(tracks not_allowed)
				(vias allowed)
				(pads allowed)
				(copperpour not_allowed)
				(footprints allowed)
			)
			(placement
				(enabled no)
				(sheetname "")
			)
			(fill
				(thermal_gap 0.5)
				(thermal_bridge_width 0.5)
				(island_removal_mode 0)
			)
			(polygon
				(pts
					(xy 38.1762 -75.8952) (xy 38.1762 -76.5048) (xy 38.0238 -76.5048) (xy 38.0238 -75.8952)
				)
			)
		)
	)
	(footprint ""
		(layer "B.Cu")
		(at 66.548 -60.325)
		(property "Reference" "R267"
			(at -1.143 -1.10363 0)
			(unlocked yes)
			(layer "B.SilkS")
			(effects
				(font
					(size 0.7874 0.5842)
					(thickness 0.1524)
				)
				(justify mirror)
			)
		)
		(property "Value" "VAL*"
			(at -0.02032 2.13233 0)
			(unlocked yes)
			(layer "B.Fab")
			(hide yes)
			(effects
				(font
					(size 0.7874 0.5842)
					(thickness 0.1524)
				)
				(justify mirror)
			)
		)
		(property "Device Type" "RESISTOR-G155-133R0-01,33OHM,1%"
			(at -0.008382 1.210564 0)
			(unlocked yes)
			(layer "B.Fab")
			(hide yes)
			(effects
				(font
					(size 0.7874 0.5842)
					(thickness 0.1524)
				)
				(justify mirror)
			)
		)
		(property "User Part Number" "PARTNUM*"
			(at -0.02032 4.024884 0)
			(unlocked yes)
			(layer "Cmts.User")
			(hide yes)
			(effects
				(font
					(size 0.7874 0.5842)
					(thickness 0.1524)
				)
				(justify mirror)
			)
		)
		(property "Tolerance" "TOL*"
			(at -0.044704 3.05435 0)
			(unlocked yes)
			(layer "Cmts.User")
			(hide yes)
			(effects
				(font
					(size 0.7874 0.5842)
					(thickness 0.1524)
				)
				(justify mirror)
			)
		)
		(duplicate_pad_numbers_are_jumpers no)
		(fp_line
			(start -1.143 -0.5588)
			(end 1.143 -0.5588)
			(stroke
				(width 0.1)
				(type default)
			)
			(layer "B.SilkS")
		)
		(fp_line
			(start -1.143 0.5588)
			(end -1.143 -0.5588)
			(stroke
				(width 0.1)
				(type default)
			)
			(layer "B.SilkS")
		)
		(fp_line
			(start 1.143 -0.5588)
			(end 1.143 0.5588)
			(stroke
				(width 0.1)
				(type default)
			)
			(layer "B.SilkS")
		)
		(fp_line
			(start 1.143 0.5588)
			(end -1.143 0.5588)
			(stroke
				(width 0.1)
				(type default)
			)
			(layer "B.SilkS")
		)
		(fp_rect
			(start -1.143 0.5588)
			(end 1.143 -0.5588)
			(stroke
				(width 0)
				(type default)
			)
			(fill no)
			(layer "B.CrtYd")
		)
		(fp_line
			(start -0.508 -0.3048)
			(end 0.508 -0.3048)
			(stroke
				(width 0.1)
				(type default)
			)
			(layer "B.Fab")
		)
		(fp_line
			(start -0.508 0.3048)
			(end -0.508 -0.3048)
			(stroke
				(width 0.1)
				(type default)
			)
			(layer "B.Fab")
		)
		(fp_line
			(start 0.508 -0.3048)
			(end 0.508 0.3048)
			(stroke
				(width 0.1)
				(type default)
			)
			(layer "B.Fab")
		)
		(fp_line
			(start 0.508 0.3048)
			(end -0.508 0.3048)
			(stroke
				(width 0.1)
				(type default)
			)
			(layer "B.Fab")
		)
		(pad "1" smd rect
			(at 0.5334 0 180)
			(size 0.7112 0.6096)
			(layers "B.Cu" "B.Mask" "B.Paste")
			(net "UNNAMED_527_RESISTOR_I206_1")
		)
		(pad "2" smd rect
			(at -0.5334 0 180)
			(size 0.7112 0.6096)
			(layers "B.Cu" "B.Mask" "B.Paste")
			(net "FPGA_IN_MAC_USB_OC_N")
		)
		(zone
			(layer "B.Cu")
			(hatch none 0.5)
			(connect_pads
				(clearance 0)
			)
			(min_thickness 0.25)
			(keepout
				(tracks allowed)
				(vias not_allowed)
				(pads allowed)
				(copperpour not_allowed)
				(footprints allowed)
			)
			(placement
				(enabled no)
				(sheetname "")
			)
			(fill
				(thermal_gap 0.5)
				(thermal_bridge_width 0.5)
				(island_removal_mode 0)
			)
			(polygon
				(pts
					(xy 66.4718 -60.0202) (xy 66.6242 -60.0202) (xy 66.6242 -60.6298) (xy 66.4718 -60.6298)
				)
			)
		)
	)
	(footprint ""
		(layer "B.Cu")
		(at 18.8722 -23.6728 -90)
		(property "Reference" "R162"
			(at -3.2512 1.00457 270)
			(unlocked yes)
			(layer "B.SilkS")
			(effects
				(font
					(size 0.7874 0.5842)
					(thickness 0.1524)
				)
				(justify mirror)
			)
		)
		(property "Value" "VAL*"
			(at -0.02032 2.13233 270)
			(unlocked yes)
			(layer "B.Fab")
			(hide yes)
			(effects
				(font
					(size 0.7874 0.5842)
					(thickness 0.1524)
				)
				(justify mirror)
			)
		)
		(property "Tolerance" "TOL*"
			(at -0.044704 3.05435 270)
			(unlocked yes)
			(layer "Cmts.User")
			(hide yes)
			(effects
				(font
					(size 0.7874 0.5842)
					(thickness 0.1524)
				)
				(justify mirror)
			)
		)
		(property "User Part Number" "PARTNUM*"
			(at -0.02032 4.024884 270)
			(unlocked yes)
			(layer "Cmts.User")
			(hide yes)
			(effects
				(font
					(size 0.7874 0.5842)
					(thickness 0.1524)
				)
				(justify mirror)
			)
		)
		(property "Device Type" "RESISTOR-G155-14701-01,4.7KOHMA"
			(at -0.008382 1.210564 270)
			(unlocked yes)
			(layer "B.Fab")
			(hide yes)
			(effects
				(font
					(size 0.7874 0.5842)
					(thickness 0.1524)
				)
				(justify mirror)
			)
		)
		(duplicate_pad_numbers_are_jumpers no)
		(fp_line
			(start -1.143 0.5588)
			(end -1.143 -0.5588)
			(stroke
				(width 0.1)
				(type default)
			)
			(layer "B.SilkS")
		)
		(fp_line
			(start 1.143 0.5588)
			(end -1.143 0.5588)
			(stroke
				(width 0.1)
				(type default)
			)
			(layer "B.SilkS")
		)
		(fp_line
			(start -1.143 -0.5588)
			(end 1.143 -0.5588)
			(stroke
				(width 0.1)
				(type default)
			)
			(layer "B.SilkS")
		)
		(fp_line
			(start 1.143 -0.5588)
			(end 1.143 0.5588)
			(stroke
				(width 0.1)
				(type default)
			)
			(layer "B.SilkS")
		)
		(fp_rect
			(start -1.143 0.5588)
			(end 1.143 -0.5588)
			(stroke
				(width 0)
				(type default)
			)
			(fill no)
			(layer "B.CrtYd")
		)
		(fp_line
			(start -0.508 0.3048)
			(end -0.508 -0.3048)
			(stroke
				(width 0.1)
				(type default)
			)
			(layer "B.Fab")
		)
		(fp_line
			(start 0.508 0.3048)
			(end -0.508 0.3048)
			(stroke
				(width 0.1)
				(type default)
			)
			(layer "B.Fab")
		)
		(fp_line
			(start -0.508 -0.3048)
			(end 0.508 -0.3048)
			(stroke
				(width 0.1)
				(type default)
			)
			(layer "B.Fab")
		)
		(fp_line
			(start 0.508 -0.3048)
			(end 0.508 0.3048)
			(stroke
				(width 0.1)
				(type default)
			)
			(layer "B.Fab")
		)
		(pad "1" smd rect
			(at 0.5334 0 90)
			(size 0.7112 0.6096)
			(layers "B.Cu" "B.Mask" "B.Paste")
			(net "XP3R3V_FPGA")
		)
		(pad "2" smd rect
			(at -0.5334 0 90)
			(size 0.7112 0.6096)
			(layers "B.Cu" "B.Mask" "B.Paste")
			(net "UNNAMED_5_24LC16BTISTTSSOP8_I_2")
		)
		(zone
			(layer "B.Cu")
			(hatch none 0.5)
			(connect_pads
				(clearance 0)
			)
			(min_thickness 0.25)
			(keepout
				(tracks allowed)
				(vias not_allowed)
				(pads allowed)
				(copperpour not_allowed)
				(footprints allowed)
			)
			(placement
				(enabled no)
				(sheetname "")
			)
			(fill
				(thermal_gap 0.5)
				(thermal_bridge_width 0.5)
				(island_removal_mode 0)
			)
			(polygon
				(pts
					(xy 18.5674 -23.749) (xy 18.5674 -23.5966) (xy 19.177 -23.5966) (xy 19.177 -23.749)
				)
			)
		)
	)
	(footprint ""
		(layer "B.Cu")
		(at 86.233 -73.279 -90)
		(property "Reference" "R342"
			(at 3.556 0.16637 270)
			(unlocked yes)
			(layer "B.SilkS")
			(effects
				(font
					(size 0.7874 0.5842)
					(thickness 0.1524)
				)
				(justify mirror)
			)
		)
		(property "Value" "VAL*"
			(at -0.02032 2.13233 270)
			(unlocked yes)
			(layer "B.Fab")
			(hide yes)
			(effects
				(font
					(size 0.7874 0.5842)
					(thickness 0.1524)
				)
				(justify mirror)
			)
		)
		(property "Tolerance" "TOL*"
			(at -0.044704 3.05435 270)
			(unlocked yes)
			(layer "Cmts.User")
			(hide yes)
			(effects
				(font
					(size 0.7874 0.5842)
					(thickness 0.1524)
				)
				(justify mirror)
			)
		)
		(property "User Part Number" "PARTNUM*"
			(at -0.02032 4.024884 270)
			(unlocked yes)
			(layer "Cmts.User")
			(hide yes)
			(effects
				(font
					(size 0.7874 0.5842)
					(thickness 0.1524)
				)
				(justify mirror)
			)
		)
		(property "Device Type" "RESISTOR-G155-14701-01,4.7KOHMA"
			(at -0.008382 1.210564 270)
			(unlocked yes)
			(layer "B.Fab")
			(hide yes)
			(effects
				(font
					(size 0.7874 0.5842)
					(thickness 0.1524)
				)
				(justify mirror)
			)
		)
		(duplicate_pad_numbers_are_jumpers no)
		(fp_line
			(start -1.143 0.5588)
			(end -1.143 -0.5588)
			(stroke
				(width 0.1)
				(type default)
			)
			(layer "B.SilkS")
		)
		(fp_line
			(start 1.143 0.5588)
			(end -1.143 0.5588)
			(stroke
				(width 0.1)
				(type default)
			)
			(layer "B.SilkS")
		)
		(fp_line
			(start -1.143 -0.5588)
			(end 1.143 -0.5588)
			(stroke
				(width 0.1)
				(type default)
			)
			(layer "B.SilkS")
		)
		(fp_line
			(start 1.143 -0.5588)
			(end 1.143 0.5588)
			(stroke
				(width 0.1)
				(type default)
			)
			(layer "B.SilkS")
		)
		(fp_rect
			(start -1.143 0.5588)
			(end 1.143 -0.5588)
			(stroke
				(width 0)
				(type default)
			)
			(fill no)
			(layer "B.CrtYd")
		)
		(fp_line
			(start -0.508 0.3048)
			(end -0.508 -0.3048)
			(stroke
				(width 0.1)
				(type default)
			)
			(layer "B.Fab")
		)
		(fp_line
			(start 0.508 0.3048)
			(end -0.508 0.3048)
			(stroke
				(width 0.1)
				(type default)
			)
			(layer "B.Fab")
		)
		(fp_line
			(start -0.508 -0.3048)
			(end 0.508 -0.3048)
			(stroke
				(width 0.1)
				(type default)
			)
			(layer "B.Fab")
		)
		(fp_line
			(start 0.508 -0.3048)
			(end 0.508 0.3048)
			(stroke
				(width 0.1)
				(type default)
			)
			(layer "B.Fab")
		)
		(pad "1" smd rect
			(at 0.5334 0 90)
			(size 0.7112 0.6096)
			(layers "B.Cu" "B.Mask" "B.Paste")
			(net "XP3R3V_FPGA")
		)
		(pad "2" smd rect
			(at -0.5334 0 90)
			(size 0.7112 0.6096)
			(layers "B.Cu" "B.Mask" "B.Paste")
			(net "BNO080_EVN_SCL")
		)
		(zone
			(layer "B.Cu")
			(hatch none 0.5)
			(connect_pads
				(clearance 0)
			)
			(min_thickness 0.25)
			(keepout
				(tracks allowed)
				(vias not_allowed)
				(pads allowed)
				(copperpour not_allowed)
				(footprints allowed)
			)
			(placement
				(enabled no)
				(sheetname "")
			)
			(fill
				(thermal_gap 0.5)
				(thermal_bridge_width 0.5)
				(island_removal_mode 0)
			)
			(polygon
				(pts
					(xy 85.9282 -73.3552) (xy 85.9282 -73.2028) (xy 86.5378 -73.2028) (xy 86.5378 -73.3552)
				)
			)
		)
	)
	(footprint ""
		(layer "B.Cu")
		(at 32.131 -91.059 -90)
		(property "Reference" "C101"
			(at -3.175 -0.08763 270)
			(unlocked yes)
			(layer "B.SilkS")
			(effects
				(font
					(size 0.7874 0.5842)
					(thickness 0.1524)
				)
				(justify mirror)
			)
		)
		(property "Value" "VAL*"
			(at -0.0762 2.067306 270)
			(unlocked yes)
			(layer "B.Fab")
			(hide yes)
			(effects
				(font
					(size 0.7874 0.5842)
					(thickness 0.1524)
				)
				(justify mirror)
			)
		)
		(property "Tolerance" "TOL*"
			(at -0.0762 3.032506 270)
			(unlocked yes)
			(layer "Cmts.User")
			(hide yes)
			(effects
				(font
					(size 0.7874 0.5842)
					(thickness 0.1524)
				)
				(justify mirror)
			)
		)
		(property "User Part Number" "PARTNUM*"
			(at -0.1016 4.023106 270)
			(unlocked yes)
			(layer "Cmts.User")
			(hide yes)
			(effects
				(font
					(size 0.7874 0.5842)
					(thickness 0.1524)
				)
				(justify mirror)
			)
		)
		(property "Device Type" "CAPACITOR-G105-0B104-EK,0.1UF,A"
			(at -0.0508 1.127506 270)
			(unlocked yes)
			(layer "B.Fab")
			(hide yes)
			(effects
				(font
					(size 0.7874 0.5842)
					(thickness 0.1524)
				)
				(justify mirror)
			)
		)
		(duplicate_pad_numbers_are_jumpers no)
		(fp_line
			(start -1.143 0.5588)
			(end -1.143 -0.5588)
			(stroke
				(width 0.1)
				(type default)
			)
			(layer "B.SilkS")
		)
		(fp_line
			(start 1.143 0.5588)
			(end -1.143 0.5588)
			(stroke
				(width 0.1)
				(type default)
			)
			(layer "B.SilkS")
		)
		(fp_line
			(start -1.143 -0.5588)
			(end 1.143 -0.5588)
			(stroke
				(width 0.1)
				(type default)
			)
			(layer "B.SilkS")
		)
		(fp_line
			(start 1.143 -0.5588)
			(end 1.143 0.5588)
			(stroke
				(width 0.1)
				(type default)
			)
			(layer "B.SilkS")
		)
		(fp_poly
			(pts
				(xy 1.143 0.5588) (xy -1.143 0.5588) (xy -1.143 -0.5588) (xy 1.143 -0.5588)
			)
			(stroke
				(width 0)
				(type default)
			)
			(fill no)
			(layer "B.CrtYd")
		)
		(fp_line
			(start -0.508 0.3048)
			(end -0.508 -0.3048)
			(stroke
				(width 0.1)
				(type default)
			)
			(layer "B.Fab")
		)
		(fp_line
			(start 0.508 0.3048)
			(end -0.508 0.3048)
			(stroke
				(width 0.1)
				(type default)
			)
			(layer "B.Fab")
		)
		(fp_line
			(start -0.508 -0.3048)
			(end 0.508 -0.3048)
			(stroke
				(width 0.1)
				(type default)
			)
			(layer "B.Fab")
		)
		(fp_line
			(start 0.508 -0.3048)
			(end 0.508 0.3048)
			(stroke
				(width 0.1)
				(type default)
			)
			(layer "B.Fab")
		)
		(pad "1" smd rect
			(at 0.5334 0 90)
			(size 0.7112 0.6096)
			(layers "B.Cu" "B.Mask" "B.Paste")
			(net "XP3R3V_VPHY")
		)
		(pad "2" smd rect
			(at -0.5334 0 90)
			(size 0.7112 0.6096)
			(layers "B.Cu" "B.Mask" "B.Paste")
			(net "SG")
		)
		(zone
			(layer "B.Cu")
			(hatch none 0.5)
			(connect_pads
				(clearance 0)
			)
			(min_thickness 0.25)
			(keepout
				(tracks allowed)
				(vias not_allowed)
				(pads allowed)
				(copperpour not_allowed)
				(footprints allowed)
			)
			(placement
				(enabled no)
				(sheetname "")
			)
			(fill
				(thermal_gap 0.5)
				(thermal_bridge_width 0.5)
				(island_removal_mode 0)
			)
			(polygon
				(pts
					(xy 31.8262 -90.9828) (xy 32.4358 -90.9828) (xy 32.4358 -91.1352) (xy 31.8262 -91.1352)
				)
			)
		)
		(zone
			(layer "B.Cu")
			(hatch none 0.5)
			(connect_pads
				(clearance 0)
			)
			(min_thickness 0.25)
			(keepout
				(tracks not_allowed)
				(vias allowed)
				(pads allowed)
				(copperpour not_allowed)
				(footprints allowed)
			)
			(placement
				(enabled no)
				(sheetname "")
			)
			(fill
				(thermal_gap 0.5)
				(thermal_bridge_width 0.5)
				(island_removal_mode 0)
			)
			(polygon
				(pts
					(xy 31.8262 -90.9828) (xy 32.4358 -90.9828) (xy 32.4358 -91.1352) (xy 31.8262 -91.1352)
				)
			)
		)
	)
	(footprint ""
		(layer "B.Cu")
		(at 11.684 -75.946)
		(property "Reference" "U8"
			(at 1.27 2.83337 0)
			(unlocked yes)
			(layer "B.SilkS")
			(effects
				(font
					(size 0.7874 0.5842)
					(thickness 0.1524)
				)
				(justify mirror)
			)
		)
		(property "Value" ""
			(at 0 0 0)
			(layer "B.Fab")
			(effects
				(font
					(size 1.27 1.27)
				)
				(justify mirror)
			)
		)
		(property "Device Type" "LM75BDP_TSSOP8-G220-10215-01"
			(at 0.03175 2.55651 0)
			(unlocked yes)
			(layer "B.Fab")
			(hide yes)
			(effects
				(font
					(size 0.7874 0.5842)
					(thickness 0.1524)
				)
				(justify mirror)
			)
		)
		(property "User Part Number" "PARTNUM*"
			(at 0.037592 3.488182 0)
			(unlocked yes)
			(layer "Cmts.User")
			(hide yes)
			(effects
				(font
					(size 0.7874 0.5842)
					(thickness 0.1524)
				)
				(justify mirror)
			)
		)
		(duplicate_pad_numbers_are_jumpers no)
		(fp_line
			(start -3.3147 -1.45796)
			(end -1.778 -1.45796)
			(stroke
				(width 0.1)
				(type default)
			)
			(layer "B.SilkS")
		)
		(fp_line
			(start -3.3147 1.45796)
			(end -3.3147 -1.45796)
			(stroke
				(width 0.1)
				(type default)
			)
			(layer "B.SilkS")
		)
		(fp_line
			(start -1.778 -1.778)
			(end 1.778 -1.778)
			(stroke
				(width 0.1)
				(type default)
			)
			(layer "B.SilkS")
		)
		(fp_line
			(start -1.778 -1.45796)
			(end -1.778 -1.778)
			(stroke
				(width 0.1)
				(type default)
			)
			(layer "B.SilkS")
		)
		(fp_line
			(start -1.778 1.45796)
			(end -3.3147 1.45796)
			(stroke
				(width 0.1)
				(type default)
			)
			(layer "B.SilkS")
		)
		(fp_line
			(start -1.778 1.778)
			(end -1.778 1.45796)
			(stroke
				(width 0.1)
				(type default)
			)
			(layer "B.SilkS")
		)
		(fp_line
			(start 1.778 -1.778)
			(end 1.778 -1.45796)
			(stroke
				(width 0.1)
				(type default)
			)
			(layer "B.SilkS")
		)
		(fp_line
			(start 1.778 -1.45796)
			(end 3.3147 -1.45796)
			(stroke
				(width 0.1)
				(type default)
			)
			(layer "B.SilkS")
		)
		(fp_line
			(start 1.778 1.45796)
			(end 1.778 1.778)
			(stroke
				(width 0.1)
				(type default)
			)
			(layer "B.SilkS")
		)
		(fp_line
			(start 1.778 1.778)
			(end -1.778 1.778)
			(stroke
				(width 0.1)
				(type default)
			)
			(layer "B.SilkS")
		)
		(fp_line
			(start 3.3147 -1.45796)
			(end 3.3147 1.45796)
			(stroke
				(width 0.1)
				(type default)
			)
			(layer "B.SilkS")
		)
		(fp_line
			(start 3.3147 1.45796)
			(end 1.778 1.45796)
			(stroke
				(width 0.1)
				(type default)
			)
			(layer "B.SilkS")
		)
		(fp_poly
			(pts
				(arc
					(start 3.77952 -2.15392)
					(mid 3.01752 -2.15392)
					(end 3.77952 -2.15392)
				)
			)
			(stroke
				(width 0)
				(type default)
			)
			(fill yes)
			(layer "B.SilkS")
		)
		(fp_rect
			(start 3.5687 -2.032)
			(end -3.5687 2.032)
			(stroke
				(width 0)
				(type default)
			)
			(fill no)
			(layer "B.CrtYd")
		)
		(fp_line
			(start -1.524 -1.524)
			(end -1.524 1.524)
			(stroke
				(width 0.1)
				(type default)
			)
			(layer "B.Fab")
		)
		(fp_line
			(start -1.524 1.524)
			(end 1.524 1.524)
			(stroke
				(width 0.1)
				(type default)
			)
			(layer "B.Fab")
		)
		(fp_line
			(start 1.524 -1.524)
			(end -1.524 -1.524)
			(stroke
				(width 0.1)
				(type default)
			)
			(layer "B.Fab")
		)
		(fp_line
			(start 1.524 1.524)
			(end 1.524 -1.524)
			(stroke
				(width 0.1)
				(type default)
			)
			(layer "B.Fab")
		)
		(fp_poly
			(pts
				(arc
					(start 1.3716 -0.9398)
					(mid 0.6096 -0.9398)
					(end 1.3716 -0.9398)
				)
			)
			(stroke
				(width 0)
				(type default)
			)
			(fill yes)
			(layer "B.Fab")
		)
		(fp_text user "8"
			(at -3.81 -1.35763 0)
			(unlocked yes)
			(layer "B.SilkS")
			(effects
				(font
					(size 0.7874 0.5842)
					(thickness 0.1524)
				)
				(justify mirror)
			)
		)
		(fp_text user "5"
			(at -3.683 1.05537 0)
			(unlocked yes)
			(layer "B.SilkS")
			(effects
				(font
					(size 0.7874 0.5842)
					(thickness 0.1524)
				)
				(justify mirror)
			)
		)
		(fp_text user "4"
			(at 3.81 0.80137 0)
			(unlocked yes)
			(layer "B.SilkS")
			(effects
				(font
					(size 0.7874 0.5842)
					(thickness 0.1524)
				)
				(justify mirror)
			)
		)
		(fp_text user "8"
			(at -2.3368 -1.429258 0)
			(unlocked yes)
			(layer "B.Fab")
			(effects
				(font
					(size 0.7874 0.5842)
					(thickness 0.1524)
				)
				(justify mirror)
			)
		)
		(fp_text user "5"
			(at -2.0828 1.237742 0)
			(unlocked yes)
			(layer "B.Fab")
			(effects
				(font
					(size 0.7874 0.5842)
					(thickness 0.1524)
				)
				(justify mirror)
			)
		)
		(fp_text user "4"
			(at 2.1082 1.110742 0)
			(unlocked yes)
			(layer "B.Fab")
			(effects
				(font
					(size 0.7874 0.5842)
					(thickness 0.1524)
				)
				(justify mirror)
			)
		)
		(pad "1" smd rect
			(at 2.2987 -0.97536 90)
			(size 0.4572 1.524)
			(layers "B.Cu" "B.Mask" "B.Paste")
			(net "R_LM75B_1_I2C_SDA")
		)
		(pad "2" smd rect
			(at 2.2987 -0.32512 90)
			(size 0.4572 1.524)
			(layers "B.Cu" "B.Mask" "B.Paste")
			(net "LM75B_I2C_SCL")
		)
		(pad "3" smd rect
			(at 2.2987 0.32512 90)
			(size 0.4572 1.524)
			(layers "B.Cu" "B.Mask" "B.Paste")
			(net "FPGA_IN_LM75B_INT1_N")
		)
		(pad "4" smd rect
			(at 2.2987 0.97536 90)
			(size 0.4572 1.524)
			(layers "B.Cu" "B.Mask" "B.Paste")
			(net "SG")
		)
		(pad "5" smd rect
			(at -2.2987 0.97536 90)
			(size 0.4572 1.524)
			(layers "B.Cu" "B.Mask" "B.Paste")
			(net "UNNAMED_6_LM75BDPTSSOP8_I34_A2")
		)
		(pad "6" smd rect
			(at -2.2987 0.32512 90)
			(size 0.4572 1.524)
			(layers "B.Cu" "B.Mask" "B.Paste")
			(net "UNNAMED_6_LM75BDPTSSOP8_I34_A1")
		)
		(pad "7" smd rect
			(at -2.2987 -0.32512 90)
			(size 0.4572 1.524)
			(layers "B.Cu" "B.Mask" "B.Paste")
			(net "UNNAMED_6_LM75BDPTSSOP8_I34_A0")
		)
		(pad "8" smd rect
			(at -2.2987 -0.97536 90)
			(size 0.4572 1.524)
			(layers "B.Cu" "B.Mask" "B.Paste")
			(net "XP3R3V_FPGA")
		)
	)
	(footprint ""
		(layer "B.Cu")
		(at 83.2358 -81.407 180)
		(property "Reference" "R149"
			(at 0.1778 -2.19837 0)
			(unlocked yes)
			(layer "B.SilkS")
			(effects
				(font
					(size 0.7874 0.5842)
					(thickness 0.1524)
				)
				(justify mirror)
			)
		)
		(property "Value" "VAL*"
			(at -0.02032 2.13233 180)
			(unlocked yes)
			(layer "B.Fab")
			(hide yes)
			(effects
				(font
					(size 0.7874 0.5842)
					(thickness 0.1524)
				)
				(justify mirror)
			)
		)
		(property "Tolerance" "TOL*"
			(at -0.044704 3.05435 180)
			(unlocked yes)
			(layer "Cmts.User")
			(hide yes)
			(effects
				(font
					(size 0.7874 0.5842)
					(thickness 0.1524)
				)
				(justify mirror)
			)
		)
		(property "User Part Number" "PARTNUM*"
			(at -0.02032 4.024884 180)
			(unlocked yes)
			(layer "Cmts.User")
			(hide yes)
			(effects
				(font
					(size 0.7874 0.5842)
					(thickness 0.1524)
				)
				(justify mirror)
			)
		)
		(property "Device Type" "RESISTOR-G155-14701-01,4.7KOHMA"
			(at -0.008382 1.210564 180)
			(unlocked yes)
			(layer "B.Fab")
			(hide yes)
			(effects
				(font
					(size 0.7874 0.5842)
					(thickness 0.1524)
				)
				(justify mirror)
			)
		)
		(duplicate_pad_numbers_are_jumpers no)
		(fp_line
			(start 1.143 0.5588)
			(end -1.143 0.5588)
			(stroke
				(width 0.1)
				(type default)
			)
			(layer "B.SilkS")
		)
		(fp_line
			(start 1.143 -0.5588)
			(end 1.143 0.5588)
			(stroke
				(width 0.1)
				(type default)
			)
			(layer "B.SilkS")
		)
		(fp_line
			(start -1.143 0.5588)
			(end -1.143 -0.5588)
			(stroke
				(width 0.1)
				(type default)
			)
			(layer "B.SilkS")
		)
		(fp_line
			(start -1.143 -0.5588)
			(end 1.143 -0.5588)
			(stroke
				(width 0.1)
				(type default)
			)
			(layer "B.SilkS")
		)
		(fp_rect
			(start -1.143 0.5588)
			(end 1.143 -0.5588)
			(stroke
				(width 0)
				(type default)
			)
			(fill no)
			(layer "B.CrtYd")
		)
		(fp_line
			(start 0.508 0.3048)
			(end -0.508 0.3048)
			(stroke
				(width 0.1)
				(type default)
			)
			(layer "B.Fab")
		)
		(fp_line
			(start 0.508 -0.3048)
			(end 0.508 0.3048)
			(stroke
				(width 0.1)
				(type default)
			)
			(layer "B.Fab")
		)
		(fp_line
			(start -0.508 0.3048)
			(end -0.508 -0.3048)
			(stroke
				(width 0.1)
				(type default)
			)
			(layer "B.Fab")
		)
		(fp_line
			(start -0.508 -0.3048)
			(end 0.508 -0.3048)
			(stroke
				(width 0.1)
				(type default)
			)
			(layer "B.Fab")
		)
		(pad "1" smd rect
			(at 0.5334 0)
			(size 0.7112 0.6096)
			(layers "B.Cu" "B.Mask" "B.Paste")
			(net "XP3R3V_FPGA")
		)
		(pad "2" smd rect
			(at -0.5334 0)
			(size 0.7112 0.6096)
			(layers "B.Cu" "B.Mask" "B.Paste")
			(net "UNNAMED_5_PCA9546APWTSSOP16_I33")
		)
		(zone
			(layer "B.Cu")
			(hatch none 0.5)
			(connect_pads
				(clearance 0)
			)
			(min_thickness 0.25)
			(keepout
				(tracks allowed)
				(vias not_allowed)
				(pads allowed)
				(copperpour not_allowed)
				(footprints allowed)
			)
			(placement
				(enabled no)
				(sheetname "")
			)
			(fill
				(thermal_gap 0.5)
				(thermal_bridge_width 0.5)
				(island_removal_mode 0)
			)
			(polygon
				(pts
					(xy 83.312 -81.7118) (xy 83.1596 -81.7118) (xy 83.1596 -81.1022) (xy 83.312 -81.1022)
				)
			)
		)
	)
	(footprint ""
		(layer "B.Cu")
		(at 116.459 -29.464 90)
		(property "Reference" "R441"
			(at -3.429 -0.03937 270)
			(unlocked yes)
			(layer "B.SilkS")
			(effects
				(font
					(size 0.7874 0.5842)
					(thickness 0.1524)
				)
				(justify mirror)
			)
		)
		(property "Value" "VAL*"
			(at -0.02032 2.13233 90)
			(unlocked yes)
			(layer "B.Fab")
			(hide yes)
			(effects
				(font
					(size 0.7874 0.5842)
					(thickness 0.1524)
				)
				(justify mirror)
			)
		)
		(property "Tolerance" "TOL*"
			(at -0.044704 3.05435 90)
			(unlocked yes)
			(layer "Cmts.User")
			(hide yes)
			(effects
				(font
					(size 0.7874 0.5842)
					(thickness 0.1524)
				)
				(justify mirror)
			)
		)
		(property "User Part Number" "PARTNUM*"
			(at -0.02032 4.024884 90)
			(unlocked yes)
			(layer "Cmts.User")
			(hide yes)
			(effects
				(font
					(size 0.7874 0.5842)
					(thickness 0.1524)
				)
				(justify mirror)
			)
		)
		(property "Device Type" "RESISTOR-G155-11002-01,10KOHM,A"
			(at -0.008382 1.210564 90)
			(unlocked yes)
			(layer "B.Fab")
			(hide yes)
			(effects
				(font
					(size 0.7874 0.5842)
					(thickness 0.1524)
				)
				(justify mirror)
			)
		)
		(duplicate_pad_numbers_are_jumpers no)
		(fp_line
			(start 1.143 -0.5588)
			(end 1.143 0.5588)
			(stroke
				(width 0.1)
				(type default)
			)
			(layer "B.SilkS")
		)
		(fp_line
			(start -1.143 -0.5588)
			(end 1.143 -0.5588)
			(stroke
				(width 0.1)
				(type default)
			)
			(layer "B.SilkS")
		)
		(fp_line
			(start 1.143 0.5588)
			(end -1.143 0.5588)
			(stroke
				(width 0.1)
				(type default)
			)
			(layer "B.SilkS")
		)
		(fp_line
			(start -1.143 0.5588)
			(end -1.143 -0.5588)
			(stroke
				(width 0.1)
				(type default)
			)
			(layer "B.SilkS")
		)
		(fp_poly
			(pts
				(xy 1.143 0.5588) (xy -1.143 0.5588) (xy -1.143 -0.5588) (xy 1.143 -0.5588)
			)
			(stroke
				(width 0)
				(type default)
			)
			(fill no)
			(layer "B.CrtYd")
		)
		(fp_line
			(start 0.508 -0.3048)
			(end 0.508 0.3048)
			(stroke
				(width 0.1)
				(type default)
			)
			(layer "B.Fab")
		)
		(fp_line
			(start -0.508 -0.3048)
			(end 0.508 -0.3048)
			(stroke
				(width 0.1)
				(type default)
			)
			(layer "B.Fab")
		)
		(fp_line
			(start 0.508 0.3048)
			(end -0.508 0.3048)
			(stroke
				(width 0.1)
				(type default)
			)
			(layer "B.Fab")
		)
		(fp_line
			(start -0.508 0.3048)
			(end -0.508 -0.3048)
			(stroke
				(width 0.1)
				(type default)
			)
			(layer "B.Fab")
		)
		(pad "1" smd rect
			(at 0.5334 0 270)
			(size 0.7112 0.6096)
			(layers "B.Cu" "B.Mask" "B.Paste")
			(net "FPGA_IN_MAC_PPS_OUTN")
		)
		(pad "2" smd rect
			(at -0.5334 0 270)
			(size 0.7112 0.6096)
			(layers "B.Cu" "B.Mask" "B.Paste")
			(net "SG")
		)
		(zone
			(layer "B.Cu")
			(hatch none 0.5)
			(connect_pads
				(clearance 0)
			)
			(min_thickness 0.25)
			(keepout
				(tracks not_allowed)
				(vias allowed)
				(pads allowed)
				(copperpour not_allowed)
				(footprints allowed)
			)
			(placement
				(enabled no)
				(sheetname "")
			)
			(fill
				(thermal_gap 0.5)
				(thermal_bridge_width 0.5)
				(island_removal_mode 0)
			)
			(polygon
				(pts
					(xy 116.7638 -29.5402) (xy 116.1542 -29.5402) (xy 116.1542 -29.3878) (xy 116.7638 -29.3878)
				)
			)
		)
		(zone
			(layer "B.Cu")
			(hatch none 0.5)
			(connect_pads
				(clearance 0)
			)
			(min_thickness 0.25)
			(keepout
				(tracks allowed)
				(vias not_allowed)
				(pads allowed)
				(copperpour not_allowed)
				(footprints allowed)
			)
			(placement
				(enabled no)
				(sheetname "")
			)
			(fill
				(thermal_gap 0.5)
				(thermal_bridge_width 0.5)
				(island_removal_mode 0)
			)
			(polygon
				(pts
					(xy 116.7638 -29.5402) (xy 116.1542 -29.5402) (xy 116.1542 -29.3878) (xy 116.7638 -29.3878)
				)
			)
		)
	)
	(footprint ""
		(layer "B.Cu")
		(at 111.125 -103.251)
		(property "Reference" "R321"
			(at 0.381 -3.26263 0)
			(unlocked yes)
			(layer "B.SilkS")
			(effects
				(font
					(size 0.7874 0.5842)
					(thickness 0.1524)
				)
				(justify mirror)
			)
		)
		(property "Value" "VAL*"
			(at -0.02032 2.13233 0)
			(unlocked yes)
			(layer "B.Fab")
			(hide yes)
			(effects
				(font
					(size 0.7874 0.5842)
					(thickness 0.1524)
				)
				(justify mirror)
			)
		)
		(property "Tolerance" "TOL*"
			(at -0.044704 3.05435 0)
			(unlocked yes)
			(layer "Cmts.User")
			(hide yes)
			(effects
				(font
					(size 0.7874 0.5842)
					(thickness 0.1524)
				)
				(justify mirror)
			)
		)
		(property "User Part Number" "PARTNUM*"
			(at -0.02032 4.024884 0)
			(unlocked yes)
			(layer "Cmts.User")
			(hide yes)
			(effects
				(font
					(size 0.7874 0.5842)
					(thickness 0.1524)
				)
				(justify mirror)
			)
		)
		(property "Device Type" "RESISTOR-G155-133R0-01,33OHM,1%"
			(at -0.008382 1.210564 0)
			(unlocked yes)
			(layer "B.Fab")
			(hide yes)
			(effects
				(font
					(size 0.7874 0.5842)
					(thickness 0.1524)
				)
				(justify mirror)
			)
		)
		(duplicate_pad_numbers_are_jumpers no)
		(fp_line
			(start -1.143 -0.5588)
			(end 1.143 -0.5588)
			(stroke
				(width 0.1)
				(type default)
			)
			(layer "B.SilkS")
		)
		(fp_line
			(start -1.143 0.5588)
			(end -1.143 -0.5588)
			(stroke
				(width 0.1)
				(type default)
			)
			(layer "B.SilkS")
		)
		(fp_line
			(start 1.143 -0.5588)
			(end 1.143 0.5588)
			(stroke
				(width 0.1)
				(type default)
			)
			(layer "B.SilkS")
		)
		(fp_line
			(start 1.143 0.5588)
			(end -1.143 0.5588)
			(stroke
				(width 0.1)
				(type default)
			)
			(layer "B.SilkS")
		)
		(fp_poly
			(pts
				(xy 1.143 0.5588) (xy -1.143 0.5588) (xy -1.143 -0.5588) (xy 1.143 -0.5588)
			)
			(stroke
				(width 0)
				(type default)
			)
			(fill no)
			(layer "B.CrtYd")
		)
		(fp_line
			(start -0.508 -0.3048)
			(end 0.508 -0.3048)
			(stroke
				(width 0.1)
				(type default)
			)
			(layer "B.Fab")
		)
		(fp_line
			(start -0.508 0.3048)
			(end -0.508 -0.3048)
			(stroke
				(width 0.1)
				(type default)
			)
			(layer "B.Fab")
		)
		(fp_line
			(start 0.508 -0.3048)
			(end 0.508 0.3048)
			(stroke
				(width 0.1)
				(type default)
			)
			(layer "B.Fab")
		)
		(fp_line
			(start 0.508 0.3048)
			(end -0.508 0.3048)
			(stroke
				(width 0.1)
				(type default)
			)
			(layer "B.Fab")
		)
		(pad "1" smd rect
			(at 0.5334 0 180)
			(size 0.7112 0.6096)
			(layers "B.Cu" "B.Mask" "B.Paste")
			(net "FPGA_M_RGB_LED_I2C_SDA")
		)
		(pad "2" smd rect
			(at -0.5334 0 180)
			(size 0.7112 0.6096)
			(layers "B.Cu" "B.Mask" "B.Paste")
			(net "R_RGB_LED_I2C_SDA")
		)
		(zone
			(layer "B.Cu")
			(hatch none 0.5)
			(connect_pads
				(clearance 0)
			)
			(min_thickness 0.25)
			(keepout
				(tracks not_allowed)
				(vias allowed)
				(pads allowed)
				(copperpour not_allowed)
				(footprints allowed)
			)
			(placement
				(enabled no)
				(sheetname "")
			)
			(fill
				(thermal_gap 0.5)
				(thermal_bridge_width 0.5)
				(island_removal_mode 0)
			)
			(polygon
				(pts
					(xy 111.2012 -102.9462) (xy 111.2012 -103.5558) (xy 111.0488 -103.5558) (xy 111.0488 -102.9462)
				)
			)
		)
		(zone
			(layer "B.Cu")
			(hatch none 0.5)
			(connect_pads
				(clearance 0)
			)
			(min_thickness 0.25)
			(keepout
				(tracks allowed)
				(vias not_allowed)
				(pads allowed)
				(copperpour not_allowed)
				(footprints allowed)
			)
			(placement
				(enabled no)
				(sheetname "")
			)
			(fill
				(thermal_gap 0.5)
				(thermal_bridge_width 0.5)
				(island_removal_mode 0)
			)
			(polygon
				(pts
					(xy 111.2012 -102.9462) (xy 111.2012 -103.5558) (xy 111.0488 -103.5558) (xy 111.0488 -102.9462)
				)
			)
		)
	)
	(footprint ""
		(layer "B.Cu")
		(at 26.8986 -18.2372)
		(property "Reference" "R344"
			(at -0.2286 1.38557 0)
			(unlocked yes)
			(layer "B.SilkS")
			(effects
				(font
					(size 0.7874 0.5842)
					(thickness 0.1524)
				)
				(justify mirror)
			)
		)
		(property "Value" "VAL*"
			(at -0.02032 2.13233 0)
			(unlocked yes)
			(layer "B.Fab")
			(hide yes)
			(effects
				(font
					(size 0.7874 0.5842)
					(thickness 0.1524)
				)
				(justify mirror)
			)
		)
		(property "Tolerance" "TOL*"
			(at -0.044704 3.05435 0)
			(unlocked yes)
			(layer "Cmts.User")
			(hide yes)
			(effects
				(font
					(size 0.7874 0.5842)
					(thickness 0.1524)
				)
				(justify mirror)
			)
		)
		(property "User Part Number" "PARTNUM*"
			(at -0.02032 4.024884 0)
			(unlocked yes)
			(layer "Cmts.User")
			(hide yes)
			(effects
				(font
					(size 0.7874 0.5842)
					(thickness 0.1524)
				)
				(justify mirror)
			)
		)
		(property "Device Type" "RESISTOR-G155-14701-01,4.7KOHMA"
			(at -0.008382 1.210564 0)
			(unlocked yes)
			(layer "B.Fab")
			(hide yes)
			(effects
				(font
					(size 0.7874 0.5842)
					(thickness 0.1524)
				)
				(justify mirror)
			)
		)
		(duplicate_pad_numbers_are_jumpers no)
		(fp_line
			(start -1.143 -0.5588)
			(end 1.143 -0.5588)
			(stroke
				(width 0.1)
				(type default)
			)
			(layer "B.SilkS")
		)
		(fp_line
			(start -1.143 0.5588)
			(end -1.143 -0.5588)
			(stroke
				(width 0.1)
				(type default)
			)
			(layer "B.SilkS")
		)
		(fp_line
			(start 1.143 -0.5588)
			(end 1.143 0.5588)
			(stroke
				(width 0.1)
				(type default)
			)
			(layer "B.SilkS")
		)
		(fp_line
			(start 1.143 0.5588)
			(end -1.143 0.5588)
			(stroke
				(width 0.1)
				(type default)
			)
			(layer "B.SilkS")
		)
		(fp_rect
			(start 1.143 -0.5588)
			(end -1.143 0.5588)
			(stroke
				(width 0)
				(type default)
			)
			(fill no)
			(layer "B.CrtYd")
		)
		(fp_line
			(start -0.508 -0.3048)
			(end 0.508 -0.3048)
			(stroke
				(width 0.1)
				(type default)
			)
			(layer "B.Fab")
		)
		(fp_line
			(start -0.508 0.3048)
			(end -0.508 -0.3048)
			(stroke
				(width 0.1)
				(type default)
			)
			(layer "B.Fab")
		)
		(fp_line
			(start 0.508 -0.3048)
			(end 0.508 0.3048)
			(stroke
				(width 0.1)
				(type default)
			)
			(layer "B.Fab")
		)
		(fp_line
			(start 0.508 0.3048)
			(end -0.508 0.3048)
			(stroke
				(width 0.1)
				(type default)
			)
			(layer "B.Fab")
		)
		(pad "1" smd rect
			(at 0.5334 0 180)
			(size 0.7112 0.6096)
			(layers "B.Cu" "B.Mask" "B.Paste")
			(net "SN_EEPROM_WP")
		)
		(pad "2" smd rect
			(at -0.5334 0 180)
			(size 0.7112 0.6096)
			(layers "B.Cu" "B.Mask" "B.Paste")
			(net "SG")
		)
		(zone
			(layer "B.Cu")
			(hatch none 0.5)
			(connect_pads
				(clearance 0)
			)
			(min_thickness 0.25)
			(keepout
				(tracks allowed)
				(vias not_allowed)
				(pads allowed)
				(copperpour not_allowed)
				(footprints allowed)
			)
			(placement
				(enabled no)
				(sheetname "")
			)
			(fill
				(thermal_gap 0.5)
				(thermal_bridge_width 0.5)
				(island_removal_mode 0)
			)
			(polygon
				(pts
					(xy 26.9748 -18.542) (xy 26.8224 -18.542) (xy 26.8224 -17.9324) (xy 26.9748 -17.9324)
				)
			)
		)
	)
	(footprint ""
		(layer "B.Cu")
		(at 138.049 -107.696 90)
		(property "Reference" "R257"
			(at -5.88137 -0.254 0)
			(unlocked yes)
			(layer "B.SilkS")
			(effects
				(font
					(size 0.7874 0.5842)
					(thickness 0.1524)
				)
				(justify mirror)
			)
		)
		(property "Value" "VAL*"
			(at -0.02032 2.13233 90)
			(unlocked yes)
			(layer "B.Fab")
			(hide yes)
			(effects
				(font
					(size 0.7874 0.5842)
					(thickness 0.1524)
				)
				(justify mirror)
			)
		)
		(property "Device Type" "RESISTOR-G155-13300-01,330OHM,A"
			(at -0.008382 1.210564 90)
			(unlocked yes)
			(layer "B.Fab")
			(hide yes)
			(effects
				(font
					(size 0.7874 0.5842)
					(thickness 0.1524)
				)
				(justify mirror)
			)
		)
		(property "User Part Number" "PARTNUM*"
			(at -0.02032 4.024884 90)
			(unlocked yes)
			(layer "Cmts.User")
			(hide yes)
			(effects
				(font
					(size 0.7874 0.5842)
					(thickness 0.1524)
				)
				(justify mirror)
			)
		)
		(property "Tolerance" "TOL*"
			(at -0.044704 3.05435 90)
			(unlocked yes)
			(layer "Cmts.User")
			(hide yes)
			(effects
				(font
					(size 0.7874 0.5842)
					(thickness 0.1524)
				)
				(justify mirror)
			)
		)
		(duplicate_pad_numbers_are_jumpers no)
		(fp_line
			(start 1.143 -0.5588)
			(end 1.143 0.5588)
			(stroke
				(width 0.1)
				(type default)
			)
			(layer "B.SilkS")
		)
		(fp_line
			(start -1.143 -0.5588)
			(end 1.143 -0.5588)
			(stroke
				(width 0.1)
				(type default)
			)
			(layer "B.SilkS")
		)
		(fp_line
			(start 1.143 0.5588)
			(end -1.143 0.5588)
			(stroke
				(width 0.1)
				(type default)
			)
			(layer "B.SilkS")
		)
		(fp_line
			(start -1.143 0.5588)
			(end -1.143 -0.5588)
			(stroke
				(width 0.1)
				(type default)
			)
			(layer "B.SilkS")
		)
		(fp_rect
			(start -1.143 -0.5588)
			(end 1.143 0.5588)
			(stroke
				(width 0)
				(type default)
			)
			(fill no)
			(layer "B.CrtYd")
		)
		(fp_line
			(start 0.508 -0.3048)
			(end 0.508 0.3048)
			(stroke
				(width 0.1)
				(type default)
			)
			(layer "B.Fab")
		)
		(fp_line
			(start -0.508 -0.3048)
			(end 0.508 -0.3048)
			(stroke
				(width 0.1)
				(type default)
			)
			(layer "B.Fab")
		)
		(fp_line
			(start 0.508 0.3048)
			(end -0.508 0.3048)
			(stroke
				(width 0.1)
				(type default)
			)
			(layer "B.Fab")
		)
		(fp_line
			(start -0.508 0.3048)
			(end -0.508 -0.3048)
			(stroke
				(width 0.1)
				(type default)
			)
			(layer "B.Fab")
		)
		(pad "1" smd rect
			(at 0.5334 0 270)
			(size 0.7112 0.6096)
			(layers "B.Cu" "B.Mask" "B.Paste")
			(net "UNNAMED_14_OPTICAL_I12_A")
		)
		(pad "2" smd rect
			(at -0.5334 0 270)
			(size 0.7112 0.6096)
			(layers "B.Cu" "B.Mask" "B.Paste")
			(net "XP3R3V_FPGA")
		)
		(zone
			(layer "B.Cu")
			(hatch none 0.5)
			(connect_pads
				(clearance 0)
			)
			(min_thickness 0.25)
			(keepout
				(tracks allowed)
				(vias not_allowed)
				(pads allowed)
				(copperpour not_allowed)
				(footprints allowed)
			)
			(placement
				(enabled no)
				(sheetname "")
			)
			(fill
				(thermal_gap 0.5)
				(thermal_bridge_width 0.5)
				(island_removal_mode 0)
			)
			(polygon
				(pts
					(xy 137.7442 -107.6198) (xy 138.3538 -107.6198) (xy 138.3538 -107.7722) (xy 137.7442 -107.7722)
				)
			)
		)
	)
	(footprint ""
		(layer "B.Cu")
		(at 26.416 -91.059 90)
		(property "Reference" "R460"
			(at 2.286 -5.11937 270)
			(unlocked yes)
			(layer "B.SilkS")
			(effects
				(font
					(size 0.7874 0.5842)
					(thickness 0.1524)
				)
				(justify mirror)
			)
		)
		(property "Value" "VAL*"
			(at -0.02032 2.13233 90)
			(unlocked yes)
			(layer "B.Fab")
			(hide yes)
			(effects
				(font
					(size 0.7874 0.5842)
					(thickness 0.1524)
				)
				(justify mirror)
			)
		)
		(property "Tolerance" "TOL*"
			(at -0.044704 3.05435 90)
			(unlocked yes)
			(layer "Cmts.User")
			(hide yes)
			(effects
				(font
					(size 0.7874 0.5842)
					(thickness 0.1524)
				)
				(justify mirror)
			)
		)
		(property "User Part Number" "PARTNUM*"
			(at -0.02032 4.024884 90)
			(unlocked yes)
			(layer "Cmts.User")
			(hide yes)
			(effects
				(font
					(size 0.7874 0.5842)
					(thickness 0.1524)
				)
				(justify mirror)
			)
		)
		(property "Device Type" "RESISTOR-G155-11001-01,1KOHM,1%"
			(at -0.008382 1.210564 90)
			(unlocked yes)
			(layer "B.Fab")
			(hide yes)
			(effects
				(font
					(size 0.7874 0.5842)
					(thickness 0.1524)
				)
				(justify mirror)
			)
		)
		(duplicate_pad_numbers_are_jumpers no)
		(fp_line
			(start 1.143 -0.5588)
			(end 1.143 0.5588)
			(stroke
				(width 0.1)
				(type default)
			)
			(layer "B.SilkS")
		)
		(fp_line
			(start -1.143 -0.5588)
			(end 1.143 -0.5588)
			(stroke
				(width 0.1)
				(type default)
			)
			(layer "B.SilkS")
		)
		(fp_line
			(start 1.143 0.5588)
			(end -1.143 0.5588)
			(stroke
				(width 0.1)
				(type default)
			)
			(layer "B.SilkS")
		)
		(fp_line
			(start -1.143 0.5588)
			(end -1.143 -0.5588)
			(stroke
				(width 0.1)
				(type default)
			)
			(layer "B.SilkS")
		)
		(fp_poly
			(pts
				(xy 1.143 0.5588) (xy -1.143 0.5588) (xy -1.143 -0.5588) (xy 1.143 -0.5588)
			)
			(stroke
				(width 0)
				(type default)
			)
			(fill no)
			(layer "B.CrtYd")
		)
		(fp_line
			(start 0.508 -0.3048)
			(end 0.508 0.3048)
			(stroke
				(width 0.1)
				(type default)
			)
			(layer "B.Fab")
		)
		(fp_line
			(start -0.508 -0.3048)
			(end 0.508 -0.3048)
			(stroke
				(width 0.1)
				(type default)
			)
			(layer "B.Fab")
		)
		(fp_line
			(start 0.508 0.3048)
			(end -0.508 0.3048)
			(stroke
				(width 0.1)
				(type default)
			)
			(layer "B.Fab")
		)
		(fp_line
			(start -0.508 0.3048)
			(end -0.508 -0.3048)
			(stroke
				(width 0.1)
				(type default)
			)
			(layer "B.Fab")
		)
		(pad "1" smd rect
			(at 0.5334 0 270)
			(size 0.7112 0.6096)
			(layers "B.Cu" "B.Mask" "B.Paste")
			(net "FT_USB_DETECT")
		)
		(pad "2" smd rect
			(at -0.5334 0 270)
			(size 0.7112 0.6096)
			(layers "B.Cu" "B.Mask" "B.Paste")
			(net "UNNAMED_524_FT4232HLREELQFP64_7")
		)
		(zone
			(layer "B.Cu")
			(hatch none 0.5)
			(connect_pads
				(clearance 0)
			)
			(min_thickness 0.25)
			(keepout
				(tracks allowed)
				(vias not_allowed)
				(pads allowed)
				(copperpour not_allowed)
				(footprints allowed)
			)
			(placement
				(enabled no)
				(sheetname "")
			)
			(fill
				(thermal_gap 0.5)
				(thermal_bridge_width 0.5)
				(island_removal_mode 0)
			)
			(polygon
				(pts
					(xy 26.7208 -91.1352) (xy 26.1112 -91.1352) (xy 26.1112 -90.9828) (xy 26.7208 -90.9828)
				)
			)
		)
		(zone
			(layer "B.Cu")
			(hatch none 0.5)
			(connect_pads
				(clearance 0)
			)
			(min_thickness 0.25)
			(keepout
				(tracks not_allowed)
				(vias allowed)
				(pads allowed)
				(copperpour not_allowed)
				(footprints allowed)
			)
			(placement
				(enabled no)
				(sheetname "")
			)
			(fill
				(thermal_gap 0.5)
				(thermal_bridge_width 0.5)
				(island_removal_mode 0)
			)
			(polygon
				(pts
					(xy 26.7208 -91.1352) (xy 26.1112 -91.1352) (xy 26.1112 -90.9828) (xy 26.7208 -90.9828)
				)
			)
		)
	)
	(footprint ""
		(layer "B.Cu")
		(at 110.363 -75.565 180)
		(property "Reference" "R295"
			(at 2.032 1.35763 0)
			(unlocked yes)
			(layer "B.SilkS")
			(effects
				(font
					(size 0.7874 0.5842)
					(thickness 0.1524)
				)
				(justify mirror)
			)
		)
		(property "Value" "VAL*"
			(at -0.02032 2.13233 180)
			(unlocked yes)
			(layer "B.Fab")
			(hide yes)
			(effects
				(font
					(size 0.7874 0.5842)
					(thickness 0.1524)
				)
				(justify mirror)
			)
		)
		(property "Tolerance" "TOL*"
			(at -0.044704 3.05435 180)
			(unlocked yes)
			(layer "Cmts.User")
			(hide yes)
			(effects
				(font
					(size 0.7874 0.5842)
					(thickness 0.1524)
				)
				(justify mirror)
			)
		)
		(property "User Part Number" "PARTNUM*"
			(at -0.02032 4.024884 180)
			(unlocked yes)
			(layer "Cmts.User")
			(hide yes)
			(effects
				(font
					(size 0.7874 0.5842)
					(thickness 0.1524)
				)
				(justify mirror)
			)
		)
		(property "Device Type" "RESISTOR-G155-11002-01,10KOHM,A"
			(at -0.008382 1.210564 180)
			(unlocked yes)
			(layer "B.Fab")
			(hide yes)
			(effects
				(font
					(size 0.7874 0.5842)
					(thickness 0.1524)
				)
				(justify mirror)
			)
		)
		(duplicate_pad_numbers_are_jumpers no)
		(fp_line
			(start 1.143 0.5588)
			(end -1.143 0.5588)
			(stroke
				(width 0.1)
				(type default)
			)
			(layer "B.SilkS")
		)
		(fp_line
			(start 1.143 -0.5588)
			(end 1.143 0.5588)
			(stroke
				(width 0.1)
				(type default)
			)
			(layer "B.SilkS")
		)
		(fp_line
			(start -1.143 0.5588)
			(end -1.143 -0.5588)
			(stroke
				(width 0.1)
				(type default)
			)
			(layer "B.SilkS")
		)
		(fp_line
			(start -1.143 -0.5588)
			(end 1.143 -0.5588)
			(stroke
				(width 0.1)
				(type default)
			)
			(layer "B.SilkS")
		)
		(fp_poly
			(pts
				(xy 1.143 0.5588) (xy -1.143 0.5588) (xy -1.143 -0.5588) (xy 1.143 -0.5588)
			)
			(stroke
				(width 0)
				(type default)
			)
			(fill no)
			(layer "B.CrtYd")
		)
		(fp_line
			(start 0.508 0.3048)
			(end -0.508 0.3048)
			(stroke
				(width 0.1)
				(type default)
			)
			(layer "B.Fab")
		)
		(fp_line
			(start 0.508 -0.3048)
			(end 0.508 0.3048)
			(stroke
				(width 0.1)
				(type default)
			)
			(layer "B.Fab")
		)
		(fp_line
			(start -0.508 0.3048)
			(end -0.508 -0.3048)
			(stroke
				(width 0.1)
				(type default)
			)
			(layer "B.Fab")
		)
		(fp_line
			(start -0.508 -0.3048)
			(end 0.508 -0.3048)
			(stroke
				(width 0.1)
				(type default)
			)
			(layer "B.Fab")
		)
		(pad "1" smd rect
			(at 0.5334 0)
			(size 0.7112 0.6096)
			(layers "B.Cu" "B.Mask" "B.Paste")
			(net "XP3R3V_FPGA")
		)
		(pad "2" smd rect
			(at -0.5334 0)
			(size 0.7112 0.6096)
			(layers "B.Cu" "B.Mask" "B.Paste")
			(net "UNNAMED_515_NCP45560IMNTWGHDFN1")
		)
		(zone
			(layer "B.Cu")
			(hatch none 0.5)
			(connect_pads
				(clearance 0)
			)
			(min_thickness 0.25)
			(keepout
				(tracks allowed)
				(vias not_allowed)
				(pads allowed)
				(copperpour not_allowed)
				(footprints allowed)
			)
			(placement
				(enabled no)
				(sheetname "")
			)
			(fill
				(thermal_gap 0.5)
				(thermal_bridge_width 0.5)
				(island_removal_mode 0)
			)
			(polygon
				(pts
					(xy 110.2868 -75.8698) (xy 110.2868 -75.2602) (xy 110.4392 -75.2602) (xy 110.4392 -75.8698)
				)
			)
		)
		(zone
			(layer "B.Cu")
			(hatch none 0.5)
			(connect_pads
				(clearance 0)
			)
			(min_thickness 0.25)
			(keepout
				(tracks not_allowed)
				(vias allowed)
				(pads allowed)
				(copperpour not_allowed)
				(footprints allowed)
			)
			(placement
				(enabled no)
				(sheetname "")
			)
			(fill
				(thermal_gap 0.5)
				(thermal_bridge_width 0.5)
				(island_removal_mode 0)
			)
			(polygon
				(pts
					(xy 110.2868 -75.8698) (xy 110.2868 -75.2602) (xy 110.4392 -75.2602) (xy 110.4392 -75.8698)
				)
			)
		)
	)
	(footprint ""
		(layer "B.Cu")
		(at 124.079 -89.535 -90)
		(property "Reference" "R111"
			(at -3.683 -0.08763 270)
			(unlocked yes)
			(layer "B.SilkS")
			(effects
				(font
					(size 0.7874 0.5842)
					(thickness 0.1524)
				)
				(justify mirror)
			)
		)
		(property "Value" "VAL*"
			(at -0.02032 2.13233 270)
			(unlocked yes)
			(layer "B.Fab")
			(hide yes)
			(effects
				(font
					(size 0.7874 0.5842)
					(thickness 0.1524)
				)
				(justify mirror)
			)
		)
		(property "Tolerance" "TOL*"
			(at -0.044704 3.05435 270)
			(unlocked yes)
			(layer "Cmts.User")
			(hide yes)
			(effects
				(font
					(size 0.7874 0.5842)
					(thickness 0.1524)
				)
				(justify mirror)
			)
		)
		(property "User Part Number" "PARTNUM*"
			(at -0.02032 4.024884 270)
			(unlocked yes)
			(layer "Cmts.User")
			(hide yes)
			(effects
				(font
					(size 0.7874 0.5842)
					(thickness 0.1524)
				)
				(justify mirror)
			)
		)
		(property "Device Type" "RESISTOR-G155-133R0-01,33OHM,1%"
			(at -0.008382 1.210564 270)
			(unlocked yes)
			(layer "B.Fab")
			(hide yes)
			(effects
				(font
					(size 0.7874 0.5842)
					(thickness 0.1524)
				)
				(justify mirror)
			)
		)
		(duplicate_pad_numbers_are_jumpers no)
		(fp_line
			(start -1.143 0.5588)
			(end -1.143 -0.5588)
			(stroke
				(width 0.1)
				(type default)
			)
			(layer "B.SilkS")
		)
		(fp_line
			(start 1.143 0.5588)
			(end -1.143 0.5588)
			(stroke
				(width 0.1)
				(type default)
			)
			(layer "B.SilkS")
		)
		(fp_line
			(start -1.143 -0.5588)
			(end 1.143 -0.5588)
			(stroke
				(width 0.1)
				(type default)
			)
			(layer "B.SilkS")
		)
		(fp_line
			(start 1.143 -0.5588)
			(end 1.143 0.5588)
			(stroke
				(width 0.1)
				(type default)
			)
			(layer "B.SilkS")
		)
		(fp_rect
			(start 1.143 0.5588)
			(end -1.143 -0.5588)
			(stroke
				(width 0)
				(type default)
			)
			(fill no)
			(layer "B.CrtYd")
		)
		(fp_line
			(start -0.508 0.3048)
			(end -0.508 -0.3048)
			(stroke
				(width 0.1)
				(type default)
			)
			(layer "B.Fab")
		)
		(fp_line
			(start 0.508 0.3048)
			(end -0.508 0.3048)
			(stroke
				(width 0.1)
				(type default)
			)
			(layer "B.Fab")
		)
		(fp_line
			(start -0.508 -0.3048)
			(end 0.508 -0.3048)
			(stroke
				(width 0.1)
				(type default)
			)
			(layer "B.Fab")
		)
		(fp_line
			(start 0.508 -0.3048)
			(end 0.508 0.3048)
			(stroke
				(width 0.1)
				(type default)
			)
			(layer "B.Fab")
		)
		(pad "1" smd rect
			(at 0.5334 0 90)
			(size 0.7112 0.6096)
			(layers "B.Cu" "B.Mask" "B.Paste")
			(net "FPGA_IN_GPSTP2_OUT")
		)
		(pad "2" smd rect
			(at -0.5334 0 90)
			(size 0.7112 0.6096)
			(layers "B.Cu" "B.Mask" "B.Paste")
			(net "GPSTP2_OUT")
		)
		(zone
			(layer "B.Cu")
			(hatch none 0.5)
			(connect_pads
				(clearance 0)
			)
			(min_thickness 0.25)
			(keepout
				(tracks allowed)
				(vias not_allowed)
				(pads allowed)
				(copperpour not_allowed)
				(footprints allowed)
			)
			(placement
				(enabled no)
				(sheetname "")
			)
			(fill
				(thermal_gap 0.5)
				(thermal_bridge_width 0.5)
				(island_removal_mode 0)
			)
			(polygon
				(pts
					(xy 123.7742 -89.4588) (xy 124.3838 -89.4588) (xy 124.3838 -89.6112) (xy 123.7742 -89.6112)
				)
			)
		)
	)
	(footprint ""
		(layer "B.Cu")
		(at 100.347018 -50.823114)
		(property "Reference" "C211"
			(at -1.287018 1.070864 0)
			(unlocked yes)
			(layer "B.SilkS")
			(effects
				(font
					(size 0.635 0.4064)
					(thickness 0.1524)
				)
				(justify mirror)
			)
		)
		(property "Value" "VAL*"
			(at 0 3.718306 0)
			(unlocked yes)
			(layer "B.Fab")
			(hide yes)
			(effects
				(font
					(size 0.7874 0.5842)
					(thickness 0.127)
				)
				(justify mirror)
			)
		)
		(property "Device Type" "CAPACITOR-G105-0B104-CK,0.1UF,A"
			(at 0 1.432306 0)
			(unlocked yes)
			(layer "B.Fab")
			(hide yes)
			(effects
				(font
					(size 0.7874 0.5842)
					(thickness 0.127)
				)
				(justify mirror)
			)
		)
		(property "User Part Number" "PARTNUM*"
			(at 0 2.575306 0)
			(unlocked yes)
			(layer "Cmts.User")
			(hide yes)
			(effects
				(font
					(size 0.7874 0.5842)
					(thickness 0.127)
				)
				(justify mirror)
			)
		)
		(property "Tolerance" "TOL*"
			(at 0 4.861306 0)
			(unlocked yes)
			(layer "Cmts.User")
			(hide yes)
			(effects
				(font
					(size 0.7874 0.5842)
					(thickness 0.127)
				)
				(justify mirror)
			)
		)
		(duplicate_pad_numbers_are_jumpers no)
		(fp_line
			(start -0.970026 -0.4699)
			(end -0.970026 0.4699)
			(stroke
				(width 0.1)
				(type default)
			)
			(layer "B.SilkS")
		)
		(fp_line
			(start -0.970026 0.4699)
			(end 0.970026 0.4699)
			(stroke
				(width 0.1)
				(type default)
			)
			(layer "B.SilkS")
		)
		(fp_line
			(start 0.970026 -0.4699)
			(end -0.970026 -0.4699)
			(stroke
				(width 0.1)
				(type default)
			)
			(layer "B.SilkS")
		)
		(fp_line
			(start 0.970026 0.4699)
			(end 0.970026 -0.4699)
			(stroke
				(width 0.1)
				(type default)
			)
			(layer "B.SilkS")
		)
		(fp_poly
			(pts
				(xy 0.970026 0.4699) (xy -0.970026 0.4699) (xy -0.970026 -0.4699) (xy 0.970026 -0.4699)
			)
			(stroke
				(width 0)
				(type default)
			)
			(fill no)
			(layer "B.CrtYd")
		)
		(fp_line
			(start -0.508 -0.3048)
			(end -0.508 0.3048)
			(stroke
				(width 0.1)
				(type default)
			)
			(layer "B.Fab")
		)
		(fp_line
			(start -0.508 0.3048)
			(end 0.508 0.3048)
			(stroke
				(width 0.1)
				(type default)
			)
			(layer "B.Fab")
		)
		(fp_line
			(start 0.508 -0.3048)
			(end -0.508 -0.3048)
			(stroke
				(width 0.1)
				(type default)
			)
			(layer "B.Fab")
		)
		(fp_line
			(start 0.508 0.3048)
			(end 0.508 -0.3048)
			(stroke
				(width 0.1)
				(type default)
			)
			(layer "B.Fab")
		)
		(pad "1" smd circle
			(at 0.500126 0 180)
			(size 0.635 0.635)
			(layers "B.Cu" "B.Mask" "B.Paste")
			(net "XP3R3V_FPGA")
		)
		(pad "2" smd circle
			(at -0.500126 0 180)
			(size 0.635 0.635)
			(layers "B.Cu" "B.Mask" "B.Paste")
			(net "SG")
		)
	)
	(footprint ""
		(layer "B.Cu")
		(at 101.4476 -83.5914 180)
		(property "Reference" "R457"
			(at -0.1524 1.07823 0)
			(unlocked yes)
			(layer "B.SilkS")
			(effects
				(font
					(size 0.7874 0.5842)
					(thickness 0.1524)
				)
				(justify mirror)
			)
		)
		(property "Value" "VAL*"
			(at -0.02032 2.13233 180)
			(unlocked yes)
			(layer "B.Fab")
			(hide yes)
			(effects
				(font
					(size 0.7874 0.5842)
					(thickness 0.1524)
				)
				(justify mirror)
			)
		)
		(property "Tolerance" "TOL*"
			(at -0.044704 3.05435 180)
			(unlocked yes)
			(layer "Cmts.User")
			(hide yes)
			(effects
				(font
					(size 0.7874 0.5842)
					(thickness 0.1524)
				)
				(justify mirror)
			)
		)
		(property "User Part Number" "PARTNUM*"
			(at -0.02032 4.024884 180)
			(unlocked yes)
			(layer "Cmts.User")
			(hide yes)
			(effects
				(font
					(size 0.7874 0.5842)
					(thickness 0.1524)
				)
				(justify mirror)
			)
		)
		(property "Device Type" "RESISTOR-G155-14701-01,4.7KOHMA"
			(at -0.008382 1.210564 180)
			(unlocked yes)
			(layer "B.Fab")
			(hide yes)
			(effects
				(font
					(size 0.7874 0.5842)
					(thickness 0.1524)
				)
				(justify mirror)
			)
		)
		(duplicate_pad_numbers_are_jumpers no)
		(fp_line
			(start 1.143 0.5588)
			(end -1.143 0.5588)
			(stroke
				(width 0.1)
				(type default)
			)
			(layer "B.SilkS")
		)
		(fp_line
			(start 1.143 -0.5588)
			(end 1.143 0.5588)
			(stroke
				(width 0.1)
				(type default)
			)
			(layer "B.SilkS")
		)
		(fp_line
			(start -1.143 0.5588)
			(end -1.143 -0.5588)
			(stroke
				(width 0.1)
				(type default)
			)
			(layer "B.SilkS")
		)
		(fp_line
			(start -1.143 -0.5588)
			(end 1.143 -0.5588)
			(stroke
				(width 0.1)
				(type default)
			)
			(layer "B.SilkS")
		)
		(fp_poly
			(pts
				(xy 1.143 0.5588) (xy -1.143 0.5588) (xy -1.143 -0.5588) (xy 1.143 -0.5588)
			)
			(stroke
				(width 0)
				(type default)
			)
			(fill no)
			(layer "B.CrtYd")
		)
		(fp_line
			(start 0.508 0.3048)
			(end -0.508 0.3048)
			(stroke
				(width 0.1)
				(type default)
			)
			(layer "B.Fab")
		)
		(fp_line
			(start 0.508 -0.3048)
			(end 0.508 0.3048)
			(stroke
				(width 0.1)
				(type default)
			)
			(layer "B.Fab")
		)
		(fp_line
			(start -0.508 0.3048)
			(end -0.508 -0.3048)
			(stroke
				(width 0.1)
				(type default)
			)
			(layer "B.Fab")
		)
		(fp_line
			(start -0.508 -0.3048)
			(end 0.508 -0.3048)
			(stroke
				(width 0.1)
				(type default)
			)
			(layer "B.Fab")
		)
		(pad "1" smd rect
			(at 0.5334 0)
			(size 0.7112 0.6096)
			(layers "B.Cu" "B.Mask" "B.Paste")
			(net "XP3R3V_FPGA")
		)
		(pad "2" smd rect
			(at -0.5334 0)
			(size 0.7112 0.6096)
			(layers "B.Cu" "B.Mask" "B.Paste")
			(net "MUX2_SEL")
		)
		(zone
			(layer "B.Cu")
			(hatch none 0.5)
			(connect_pads
				(clearance 0)
			)
			(min_thickness 0.25)
			(keepout
				(tracks not_allowed)
				(vias allowed)
				(pads allowed)
				(copperpour not_allowed)
				(footprints allowed)
			)
			(placement
				(enabled no)
				(sheetname "")
			)
			(fill
				(thermal_gap 0.5)
				(thermal_bridge_width 0.5)
				(island_removal_mode 0)
			)
			(polygon
				(pts
					(xy 101.3714 -83.8962) (xy 101.3714 -83.2866) (xy 101.5238 -83.2866) (xy 101.5238 -83.8962)
				)
			)
		)
		(zone
			(layer "B.Cu")
			(hatch none 0.5)
			(connect_pads
				(clearance 0)
			)
			(min_thickness 0.25)
			(keepout
				(tracks allowed)
				(vias not_allowed)
				(pads allowed)
				(copperpour not_allowed)
				(footprints allowed)
			)
			(placement
				(enabled no)
				(sheetname "")
			)
			(fill
				(thermal_gap 0.5)
				(thermal_bridge_width 0.5)
				(island_removal_mode 0)
			)
			(polygon
				(pts
					(xy 101.3714 -83.8962) (xy 101.3714 -83.2866) (xy 101.5238 -83.2866) (xy 101.5238 -83.8962)
				)
			)
		)
	)
	(footprint ""
		(layer "B.Cu")
		(at 105.918 -87.63 -90)
		(property "Reference" "C102"
			(at 0.127 -1.23063 270)
			(unlocked yes)
			(layer "B.SilkS")
			(effects
				(font
					(size 0.7874 0.5842)
					(thickness 0.1524)
				)
				(justify mirror)
			)
		)
		(property "Value" "VAL*"
			(at -0.0762 2.067306 270)
			(unlocked yes)
			(layer "B.Fab")
			(hide yes)
			(effects
				(font
					(size 0.7874 0.5842)
					(thickness 0.1524)
				)
				(justify mirror)
			)
		)
		(property "Tolerance" "TOL*"
			(at -0.0762 3.032506 270)
			(unlocked yes)
			(layer "Cmts.User")
			(hide yes)
			(effects
				(font
					(size 0.7874 0.5842)
					(thickness 0.1524)
				)
				(justify mirror)
			)
		)
		(property "User Part Number" "PARTNUM*"
			(at -0.1016 4.023106 270)
			(unlocked yes)
			(layer "Cmts.User")
			(hide yes)
			(effects
				(font
					(size 0.7874 0.5842)
					(thickness 0.1524)
				)
				(justify mirror)
			)
		)
		(property "Device Type" "CAPACITOR-G105-0B104-EK,0.1UF,A"
			(at -0.0508 1.127506 270)
			(unlocked yes)
			(layer "B.Fab")
			(hide yes)
			(effects
				(font
					(size 0.7874 0.5842)
					(thickness 0.1524)
				)
				(justify mirror)
			)
		)
		(duplicate_pad_numbers_are_jumpers no)
		(fp_line
			(start -1.143 0.5588)
			(end -1.143 -0.5588)
			(stroke
				(width 0.1)
				(type default)
			)
			(layer "B.SilkS")
		)
		(fp_line
			(start 1.143 0.5588)
			(end -1.143 0.5588)
			(stroke
				(width 0.1)
				(type default)
			)
			(layer "B.SilkS")
		)
		(fp_line
			(start -1.143 -0.5588)
			(end 1.143 -0.5588)
			(stroke
				(width 0.1)
				(type default)
			)
			(layer "B.SilkS")
		)
		(fp_line
			(start 1.143 -0.5588)
			(end 1.143 0.5588)
			(stroke
				(width 0.1)
				(type default)
			)
			(layer "B.SilkS")
		)
		(fp_poly
			(pts
				(xy 1.143 0.5588) (xy -1.143 0.5588) (xy -1.143 -0.5588) (xy 1.143 -0.5588)
			)
			(stroke
				(width 0)
				(type default)
			)
			(fill no)
			(layer "B.CrtYd")
		)
		(fp_line
			(start -0.508 0.3048)
			(end -0.508 -0.3048)
			(stroke
				(width 0.1)
				(type default)
			)
			(layer "B.Fab")
		)
		(fp_line
			(start 0.508 0.3048)
			(end -0.508 0.3048)
			(stroke
				(width 0.1)
				(type default)
			)
			(layer "B.Fab")
		)
		(fp_line
			(start -0.508 -0.3048)
			(end 0.508 -0.3048)
			(stroke
				(width 0.1)
				(type default)
			)
			(layer "B.Fab")
		)
		(fp_line
			(start 0.508 -0.3048)
			(end 0.508 0.3048)
			(stroke
				(width 0.1)
				(type default)
			)
			(layer "B.Fab")
		)
		(pad "1" smd rect
			(at 0.5334 0 90)
			(size 0.7112 0.6096)
			(layers "B.Cu" "B.Mask" "B.Paste")
			(net "XP3R3V_FPGA")
		)
		(pad "2" smd rect
			(at -0.5334 0 90)
			(size 0.7112 0.6096)
			(layers "B.Cu" "B.Mask" "B.Paste")
			(net "SG")
		)
		(zone
			(layer "B.Cu")
			(hatch none 0.5)
			(connect_pads
				(clearance 0)
			)
			(min_thickness 0.25)
			(keepout
				(tracks allowed)
				(vias not_allowed)
				(pads allowed)
				(copperpour not_allowed)
				(footprints allowed)
			)
			(placement
				(enabled no)
				(sheetname "")
			)
			(fill
				(thermal_gap 0.5)
				(thermal_bridge_width 0.5)
				(island_removal_mode 0)
			)
			(polygon
				(pts
					(xy 105.6132 -87.5538) (xy 106.2228 -87.5538) (xy 106.2228 -87.7062) (xy 105.6132 -87.7062)
				)
			)
		)
		(zone
			(layer "B.Cu")
			(hatch none 0.5)
			(connect_pads
				(clearance 0)
			)
			(min_thickness 0.25)
			(keepout
				(tracks not_allowed)
				(vias allowed)
				(pads allowed)
				(copperpour not_allowed)
				(footprints allowed)
			)
			(placement
				(enabled no)
				(sheetname "")
			)
			(fill
				(thermal_gap 0.5)
				(thermal_bridge_width 0.5)
				(island_removal_mode 0)
			)
			(polygon
				(pts
					(xy 105.6132 -87.5538) (xy 106.2228 -87.5538) (xy 106.2228 -87.7062) (xy 105.6132 -87.7062)
				)
			)
		)
	)
	(footprint ""
		(layer "B.Cu")
		(at 13.462 -52.578 90)
		(property "Reference" "R495"
			(at 0 1.10363 270)
			(unlocked yes)
			(layer "B.SilkS")
			(effects
				(font
					(size 0.7874 0.5842)
					(thickness 0.1524)
				)
				(justify mirror)
			)
		)
		(property "Value" "VAL*"
			(at -0.02032 2.13233 90)
			(unlocked yes)
			(layer "B.Fab")
			(hide yes)
			(effects
				(font
					(size 0.7874 0.5842)
					(thickness 0.1524)
				)
				(justify mirror)
			)
		)
		(property "Tolerance" "TOL*"
			(at -0.044704 3.05435 90)
			(unlocked yes)
			(layer "Cmts.User")
			(hide yes)
			(effects
				(font
					(size 0.7874 0.5842)
					(thickness 0.1524)
				)
				(justify mirror)
			)
		)
		(property "User Part Number" "PARTNUM*"
			(at -0.02032 4.024884 90)
			(unlocked yes)
			(layer "Cmts.User")
			(hide yes)
			(effects
				(font
					(size 0.7874 0.5842)
					(thickness 0.1524)
				)
				(justify mirror)
			)
		)
		(property "Device Type" "RESISTOR-G155-100R0-J0,0OHM,-"
			(at -0.008382 1.210564 90)
			(unlocked yes)
			(layer "B.Fab")
			(hide yes)
			(effects
				(font
					(size 0.7874 0.5842)
					(thickness 0.1524)
				)
				(justify mirror)
			)
		)
		(duplicate_pad_numbers_are_jumpers no)
		(fp_line
			(start 1.143 -0.5588)
			(end 1.143 0.5588)
			(stroke
				(width 0.1)
				(type default)
			)
			(layer "B.SilkS")
		)
		(fp_line
			(start -1.143 -0.5588)
			(end 1.143 -0.5588)
			(stroke
				(width 0.1)
				(type default)
			)
			(layer "B.SilkS")
		)
		(fp_line
			(start 1.143 0.5588)
			(end -1.143 0.5588)
			(stroke
				(width 0.1)
				(type default)
			)
			(layer "B.SilkS")
		)
		(fp_line
			(start -1.143 0.5588)
			(end -1.143 -0.5588)
			(stroke
				(width 0.1)
				(type default)
			)
			(layer "B.SilkS")
		)
		(fp_poly
			(pts
				(xy 1.143 0.5588) (xy -1.143 0.5588) (xy -1.143 -0.5588) (xy 1.143 -0.5588)
			)
			(stroke
				(width 0)
				(type default)
			)
			(fill no)
			(layer "B.CrtYd")
		)
		(fp_line
			(start 0.508 -0.3048)
			(end 0.508 0.3048)
			(stroke
				(width 0.1)
				(type default)
			)
			(layer "B.Fab")
		)
		(fp_line
			(start -0.508 -0.3048)
			(end 0.508 -0.3048)
			(stroke
				(width 0.1)
				(type default)
			)
			(layer "B.Fab")
		)
		(fp_line
			(start 0.508 0.3048)
			(end -0.508 0.3048)
			(stroke
				(width 0.1)
				(type default)
			)
			(layer "B.Fab")
		)
		(fp_line
			(start -0.508 0.3048)
			(end -0.508 -0.3048)
			(stroke
				(width 0.1)
				(type default)
			)
			(layer "B.Fab")
		)
		(pad "1" smd rect
			(at 0.5334 0 270)
			(size 0.7112 0.6096)
			(layers "B.Cu" "B.Mask" "B.Paste")
			(net "UNNAMED_12_CAPACITOR_I332_2")
		)
		(pad "2" smd rect
			(at -0.5334 0 270)
			(size 0.7112 0.6096)
			(layers "B.Cu" "B.Mask" "B.Paste")
			(net "UNNAMED_12_74HCT2G125DPTSSOP8_9")
		)
		(zone
			(layer "B.Cu")
			(hatch none 0.5)
			(connect_pads
				(clearance 0)
			)
			(min_thickness 0.25)
			(keepout
				(tracks not_allowed)
				(vias allowed)
				(pads allowed)
				(copperpour not_allowed)
				(footprints allowed)
			)
			(placement
				(enabled no)
				(sheetname "")
			)
			(fill
				(thermal_gap 0.5)
				(thermal_bridge_width 0.5)
				(island_removal_mode 0)
			)
			(polygon
				(pts
					(xy 13.7668 -52.6542) (xy 13.1572 -52.6542) (xy 13.1572 -52.5018) (xy 13.7668 -52.5018)
				)
			)
		)
		(zone
			(layer "B.Cu")
			(hatch none 0.5)
			(connect_pads
				(clearance 0)
			)
			(min_thickness 0.25)
			(keepout
				(tracks allowed)
				(vias not_allowed)
				(pads allowed)
				(copperpour not_allowed)
				(footprints allowed)
			)
			(placement
				(enabled no)
				(sheetname "")
			)
			(fill
				(thermal_gap 0.5)
				(thermal_bridge_width 0.5)
				(island_removal_mode 0)
			)
			(polygon
				(pts
					(xy 13.7668 -52.6542) (xy 13.1572 -52.6542) (xy 13.1572 -52.5018) (xy 13.7668 -52.5018)
				)
			)
		)
	)
	(footprint ""
		(layer "B.Cu")
		(at 21.59 -61.5442 -90)
		(property "Reference" "R281"
			(at 3.1242 -0.84963 270)
			(unlocked yes)
			(layer "B.SilkS")
			(effects
				(font
					(size 0.7874 0.5842)
					(thickness 0.1524)
				)
				(justify mirror)
			)
		)
		(property "Value" "VAL*"
			(at -0.02032 2.13233 270)
			(unlocked yes)
			(layer "B.Fab")
			(hide yes)
			(effects
				(font
					(size 0.7874 0.5842)
					(thickness 0.1524)
				)
				(justify mirror)
			)
		)
		(property "Tolerance" "TOL*"
			(at -0.044704 3.05435 270)
			(unlocked yes)
			(layer "Cmts.User")
			(hide yes)
			(effects
				(font
					(size 0.7874 0.5842)
					(thickness 0.1524)
				)
				(justify mirror)
			)
		)
		(property "User Part Number" "PARTNUM*"
			(at -0.02032 4.024884 270)
			(unlocked yes)
			(layer "Cmts.User")
			(hide yes)
			(effects
				(font
					(size 0.7874 0.5842)
					(thickness 0.1524)
				)
				(justify mirror)
			)
		)
		(property "Device Type" "RESISTOR-G155-14701-01,4.7KOHMA"
			(at -0.008382 1.210564 270)
			(unlocked yes)
			(layer "B.Fab")
			(hide yes)
			(effects
				(font
					(size 0.7874 0.5842)
					(thickness 0.1524)
				)
				(justify mirror)
			)
		)
		(duplicate_pad_numbers_are_jumpers no)
		(fp_line
			(start -1.143 0.5588)
			(end -1.143 -0.5588)
			(stroke
				(width 0.1)
				(type default)
			)
			(layer "B.SilkS")
		)
		(fp_line
			(start 1.143 0.5588)
			(end -1.143 0.5588)
			(stroke
				(width 0.1)
				(type default)
			)
			(layer "B.SilkS")
		)
		(fp_line
			(start -1.143 -0.5588)
			(end 1.143 -0.5588)
			(stroke
				(width 0.1)
				(type default)
			)
			(layer "B.SilkS")
		)
		(fp_line
			(start 1.143 -0.5588)
			(end 1.143 0.5588)
			(stroke
				(width 0.1)
				(type default)
			)
			(layer "B.SilkS")
		)
		(fp_poly
			(pts
				(xy 1.143 0.5588) (xy -1.143 0.5588) (xy -1.143 -0.5588) (xy 1.143 -0.5588)
			)
			(stroke
				(width 0)
				(type default)
			)
			(fill no)
			(layer "B.CrtYd")
		)
		(fp_line
			(start -0.508 0.3048)
			(end -0.508 -0.3048)
			(stroke
				(width 0.1)
				(type default)
			)
			(layer "B.Fab")
		)
		(fp_line
			(start 0.508 0.3048)
			(end -0.508 0.3048)
			(stroke
				(width 0.1)
				(type default)
			)
			(layer "B.Fab")
		)
		(fp_line
			(start -0.508 -0.3048)
			(end 0.508 -0.3048)
			(stroke
				(width 0.1)
				(type default)
			)
			(layer "B.Fab")
		)
		(fp_line
			(start 0.508 -0.3048)
			(end 0.508 0.3048)
			(stroke
				(width 0.1)
				(type default)
			)
			(layer "B.Fab")
		)
		(pad "1" smd rect
			(at 0.5334 0 90)
			(size 0.7112 0.6096)
			(layers "B.Cu" "B.Mask" "B.Paste")
			(net "XP3R3V_FPGA")
		)
		(pad "2" smd rect
			(at -0.5334 0 90)
			(size 0.7112 0.6096)
			(layers "B.Cu" "B.Mask" "B.Paste")
			(net "ICP10100_I2C_SDA")
		)
		(zone
			(layer "B.Cu")
			(hatch none 0.5)
			(connect_pads
				(clearance 0)
			)
			(min_thickness 0.25)
			(keepout
				(tracks not_allowed)
				(vias allowed)
				(pads allowed)
				(copperpour not_allowed)
				(footprints allowed)
			)
			(placement
				(enabled no)
				(sheetname "")
			)
			(fill
				(thermal_gap 0.5)
				(thermal_bridge_width 0.5)
				(island_removal_mode 0)
			)
			(polygon
				(pts
					(xy 21.2852 -61.468) (xy 21.8948 -61.468) (xy 21.8948 -61.6204) (xy 21.2852 -61.6204)
				)
			)
		)
		(zone
			(layer "B.Cu")
			(hatch none 0.5)
			(connect_pads
				(clearance 0)
			)
			(min_thickness 0.25)
			(keepout
				(tracks allowed)
				(vias not_allowed)
				(pads allowed)
				(copperpour not_allowed)
				(footprints allowed)
			)
			(placement
				(enabled no)
				(sheetname "")
			)
			(fill
				(thermal_gap 0.5)
				(thermal_bridge_width 0.5)
				(island_removal_mode 0)
			)
			(polygon
				(pts
					(xy 21.2852 -61.468) (xy 21.8948 -61.468) (xy 21.8948 -61.6204) (xy 21.2852 -61.6204)
				)
			)
		)
	)
	(footprint ""
		(layer "B.Cu")
		(at 119.847106 -54.323234 -90)
		(property "Reference" "R504"
			(at -3.461766 -0.001524 270)
			(unlocked yes)
			(layer "B.SilkS")
			(effects
				(font
					(size 0.7874 0.5842)
					(thickness 0.1524)
				)
				(justify mirror)
			)
		)
		(property "Value" "VAL*"
			(at 0 3.718306 270)
			(unlocked yes)
			(layer "B.Fab")
			(hide yes)
			(effects
				(font
					(size 0.7874 0.5842)
					(thickness 0.127)
				)
				(justify mirror)
			)
		)
		(property "Tolerance" "TOL*"
			(at 0 4.861306 270)
			(unlocked yes)
			(layer "Cmts.User")
			(hide yes)
			(effects
				(font
					(size 0.7874 0.5842)
					(thickness 0.127)
				)
				(justify mirror)
			)
		)
		(property "User Part Number" "PARTNUM*"
			(at 0 2.575306 270)
			(unlocked yes)
			(layer "Cmts.User")
			(hide yes)
			(effects
				(font
					(size 0.7874 0.5842)
					(thickness 0.127)
				)
				(justify mirror)
			)
		)
		(property "Device Type" "RESISTOR-G155-14701-01,4.7KOHMA"
			(at 0 1.432306 270)
			(unlocked yes)
			(layer "B.Fab")
			(hide yes)
			(effects
				(font
					(size 0.7874 0.5842)
					(thickness 0.127)
				)
				(justify mirror)
			)
		)
		(duplicate_pad_numbers_are_jumpers no)
		(fp_line
			(start -0.970026 0.4699)
			(end 0.970026 0.4699)
			(stroke
				(width 0.1)
				(type default)
			)
			(layer "B.SilkS")
		)
		(fp_line
			(start 0.970026 0.4699)
			(end 0.970026 -0.4699)
			(stroke
				(width 0.1)
				(type default)
			)
			(layer "B.SilkS")
		)
		(fp_line
			(start -0.970026 -0.4699)
			(end -0.970026 0.4699)
			(stroke
				(width 0.1)
				(type default)
			)
			(layer "B.SilkS")
		)
		(fp_line
			(start 0.970026 -0.4699)
			(end -0.970026 -0.4699)
			(stroke
				(width 0.1)
				(type default)
			)
			(layer "B.SilkS")
		)
		(fp_poly
			(pts
				(xy 0.970026 0.4699) (xy -0.970026 0.4699) (xy -0.970026 -0.4699) (xy 0.970026 -0.4699)
			)
			(stroke
				(width 0)
				(type default)
			)
			(fill no)
			(layer "B.CrtYd")
		)
		(fp_line
			(start -0.508 0.3048)
			(end 0.508 0.3048)
			(stroke
				(width 0.1)
				(type default)
			)
			(layer "B.Fab")
		)
		(fp_line
			(start 0.508 0.3048)
			(end 0.508 -0.3048)
			(stroke
				(width 0.1)
				(type default)
			)
			(layer "B.Fab")
		)
		(fp_line
			(start -0.508 -0.3048)
			(end -0.508 0.3048)
			(stroke
				(width 0.1)
				(type default)
			)
			(layer "B.Fab")
		)
		(fp_line
			(start 0.508 -0.3048)
			(end -0.508 -0.3048)
			(stroke
				(width 0.1)
				(type default)
			)
			(layer "B.Fab")
		)
		(pad "1" smd circle
			(at 0.500126 0 90)
			(size 0.635 0.635)
			(layers "B.Cu" "B.Mask" "B.Paste")
			(net "ANT1_IN")
		)
		(pad "2" smd circle
			(at -0.500126 0 90)
			(size 0.635 0.635)
			(layers "B.Cu" "B.Mask" "B.Paste")
			(net "SG")
		)
	)
	(footprint ""
		(layer "B.Cu")
		(at 113.846864 -49.32299 -90)
		(property "Reference" "C126"
			(at -1.85801 -0.929386 270)
			(unlocked yes)
			(layer "B.SilkS")
			(effects
				(font
					(size 0.635 0.4064)
					(thickness 0.1524)
				)
				(justify mirror)
			)
		)
		(property "Value" "VAL*"
			(at 0 3.718306 270)
			(unlocked yes)
			(layer "B.Fab")
			(hide yes)
			(effects
				(font
					(size 0.7874 0.5842)
					(thickness 0.127)
				)
				(justify mirror)
			)
		)
		(property "Tolerance" "TOL*"
			(at 0 4.861306 270)
			(unlocked yes)
			(layer "Cmts.User")
			(hide yes)
			(effects
				(font
					(size 0.7874 0.5842)
					(thickness 0.127)
				)
				(justify mirror)
			)
		)
		(property "User Part Number" "PARTNUM*"
			(at 0 2.575306 270)
			(unlocked yes)
			(layer "Cmts.User")
			(hide yes)
			(effects
				(font
					(size 0.7874 0.5842)
					(thickness 0.127)
				)
				(justify mirror)
			)
		)
		(property "Device Type" "CAPACITOR-G105-0B104-CK,0.1UF,A"
			(at 0 1.432306 270)
			(unlocked yes)
			(layer "B.Fab")
			(hide yes)
			(effects
				(font
					(size 0.7874 0.5842)
					(thickness 0.127)
				)
				(justify mirror)
			)
		)
		(duplicate_pad_numbers_are_jumpers no)
		(fp_line
			(start -0.970026 0.4699)
			(end 0.970026 0.4699)
			(stroke
				(width 0.1)
				(type default)
			)
			(layer "B.SilkS")
		)
		(fp_line
			(start 0.970026 0.4699)
			(end 0.970026 -0.4699)
			(stroke
				(width 0.1)
				(type default)
			)
			(layer "B.SilkS")
		)
		(fp_line
			(start -0.970026 -0.4699)
			(end -0.970026 0.4699)
			(stroke
				(width 0.1)
				(type default)
			)
			(layer "B.SilkS")
		)
		(fp_line
			(start 0.970026 -0.4699)
			(end -0.970026 -0.4699)
			(stroke
				(width 0.1)
				(type default)
			)
			(layer "B.SilkS")
		)
		(fp_poly
			(pts
				(xy 0.970026 0.4699) (xy -0.970026 0.4699) (xy -0.970026 -0.4699) (xy 0.970026 -0.4699)
			)
			(stroke
				(width 0)
				(type default)
			)
			(fill no)
			(layer "B.CrtYd")
		)
		(fp_line
			(start -0.508 0.3048)
			(end 0.508 0.3048)
			(stroke
				(width 0.1)
				(type default)
			)
			(layer "B.Fab")
		)
		(fp_line
			(start 0.508 0.3048)
			(end 0.508 -0.3048)
			(stroke
				(width 0.1)
				(type default)
			)
			(layer "B.Fab")
		)
		(fp_line
			(start -0.508 -0.3048)
			(end -0.508 0.3048)
			(stroke
				(width 0.1)
				(type default)
			)
			(layer "B.Fab")
		)
		(fp_line
			(start 0.508 -0.3048)
			(end -0.508 -0.3048)
			(stroke
				(width 0.1)
				(type default)
			)
			(layer "B.Fab")
		)
		(pad "1" smd circle
			(at 0.500126 0 90)
			(size 0.635 0.635)
			(layers "B.Cu" "B.Mask" "B.Paste")
			(net "XP3R3V_FPGA")
		)
		(pad "2" smd circle
			(at -0.500126 0 90)
			(size 0.635 0.635)
			(layers "B.Cu" "B.Mask" "B.Paste")
			(net "SG")
		)
	)
	(footprint ""
		(layer "B.Cu")
		(at 105.8418 -74.5744)
		(property "Reference" "C241"
			(at -3.81 -0.08763 0)
			(unlocked yes)
			(layer "B.SilkS")
			(effects
				(font
					(size 0.7874 0.5842)
					(thickness 0.1524)
				)
				(justify mirror)
			)
		)
		(property "Value" "VAL*"
			(at -0.0762 3.134106 0)
			(unlocked yes)
			(layer "B.Fab")
			(hide yes)
			(effects
				(font
					(size 0.7874 0.5842)
					(thickness 0.1524)
				)
				(justify mirror)
			)
		)
		(property "Device Type" "CAPACITOR-G107-0F226-CM,22UF,2A"
			(at -0.0508 2.194306 0)
			(unlocked yes)
			(layer "B.Fab")
			(hide yes)
			(effects
				(font
					(size 0.7874 0.5842)
					(thickness 0.1524)
				)
				(justify mirror)
			)
		)
		(property "User Part Number" "PARTNUM*"
			(at -0.1016 5.013706 0)
			(unlocked yes)
			(layer "Cmts.User")
			(hide yes)
			(effects
				(font
					(size 0.7874 0.5842)
					(thickness 0.1524)
				)
				(justify mirror)
			)
		)
		(property "Tolerance" "TOL*"
			(at -0.0762 4.048506 0)
			(unlocked yes)
			(layer "Cmts.User")
			(hide yes)
			(effects
				(font
					(size 0.7874 0.5842)
					(thickness 0.1524)
				)
				(justify mirror)
			)
		)
		(duplicate_pad_numbers_are_jumpers no)
		(fp_line
			(start -1.5748 -0.9398)
			(end 1.5748 -0.9398)
			(stroke
				(width 0.1)
				(type default)
			)
			(layer "B.SilkS")
		)
		(fp_line
			(start -1.5748 0.9398)
			(end -1.5748 -0.9398)
			(stroke
				(width 0.1)
				(type default)
			)
			(layer "B.SilkS")
		)
		(fp_line
			(start 1.5748 -0.9398)
			(end 1.5748 0.9398)
			(stroke
				(width 0.1)
				(type default)
			)
			(layer "B.SilkS")
		)
		(fp_line
			(start 1.5748 0.9398)
			(end -1.5748 0.9398)
			(stroke
				(width 0.1)
				(type default)
			)
			(layer "B.SilkS")
		)
		(fp_rect
			(start 1.5748 -0.9398)
			(end -1.5748 0.9398)
			(stroke
				(width 0)
				(type default)
			)
			(fill no)
			(layer "B.CrtYd")
		)
		(fp_line
			(start -1.016 -0.635)
			(end 1.016 -0.635)
			(stroke
				(width 0.1)
				(type default)
			)
			(layer "B.Fab")
		)
		(fp_line
			(start -1.016 0.635)
			(end -1.016 -0.635)
			(stroke
				(width 0.1)
				(type default)
			)
			(layer "B.Fab")
		)
		(fp_line
			(start 1.016 -0.635)
			(end 1.016 0.635)
			(stroke
				(width 0.1)
				(type default)
			)
			(layer "B.Fab")
		)
		(fp_line
			(start 1.016 0.635)
			(end -1.016 0.635)
			(stroke
				(width 0.1)
				(type default)
			)
			(layer "B.Fab")
		)
		(pad "1" smd rect
			(at 0.8382 0 180)
			(size 0.9652 1.3716)
			(layers "B.Cu" "B.Mask" "B.Paste")
			(net "XP3R3V_FPGA")
		)
		(pad "2" smd rect
			(at -0.8382 0 180)
			(size 0.9652 1.3716)
			(layers "B.Cu" "B.Mask" "B.Paste")
			(net "SG")
		)
		(zone
			(layer "B.Cu")
			(hatch none 0.5)
			(connect_pads
				(clearance 0)
			)
			(min_thickness 0.25)
			(keepout
				(tracks allowed)
				(vias not_allowed)
				(pads allowed)
				(copperpour not_allowed)
				(footprints allowed)
			)
			(placement
				(enabled no)
				(sheetname "")
			)
			(fill
				(thermal_gap 0.5)
				(thermal_bridge_width 0.5)
				(island_removal_mode 0)
			)
			(polygon
				(pts
					(xy 106.0704 -75.2094) (xy 105.6132 -75.2094) (xy 105.6132 -73.9394) (xy 106.0704 -73.9394)
				)
			)
		)
	)
	(footprint ""
		(layer "B.Cu")
		(at 92.202 -55.118 180)
		(property "Reference" "C150"
			(at -0.508 -1.94437 0)
			(unlocked yes)
			(layer "B.SilkS")
			(effects
				(font
					(size 0.7874 0.5842)
					(thickness 0.1524)
				)
				(justify mirror)
			)
		)
		(property "Value" "VAL*"
			(at -0.0762 2.067306 180)
			(unlocked yes)
			(layer "B.Fab")
			(hide yes)
			(effects
				(font
					(size 0.7874 0.5842)
					(thickness 0.1524)
				)
				(justify mirror)
			)
		)
		(property "Device Type" "CAPACITOR-G105-0B104-CK,0.1UF,A"
			(at -0.0508 1.127506 180)
			(unlocked yes)
			(layer "B.Fab")
			(hide yes)
			(effects
				(font
					(size 0.7874 0.5842)
					(thickness 0.1524)
				)
				(justify mirror)
			)
		)
		(property "User Part Number" "PARTNUM*"
			(at -0.1016 4.023106 180)
			(unlocked yes)
			(layer "Cmts.User")
			(hide yes)
			(effects
				(font
					(size 0.7874 0.5842)
					(thickness 0.1524)
				)
				(justify mirror)
			)
		)
		(property "Tolerance" "TOL*"
			(at -0.0762 3.032506 180)
			(unlocked yes)
			(layer "Cmts.User")
			(hide yes)
			(effects
				(font
					(size 0.7874 0.5842)
					(thickness 0.1524)
				)
				(justify mirror)
			)
		)
		(duplicate_pad_numbers_are_jumpers no)
		(fp_line
			(start 1.143 0.5588)
			(end -1.143 0.5588)
			(stroke
				(width 0.1)
				(type default)
			)
			(layer "B.SilkS")
		)
		(fp_line
			(start 1.143 -0.5588)
			(end 1.143 0.5588)
			(stroke
				(width 0.1)
				(type default)
			)
			(layer "B.SilkS")
		)
		(fp_line
			(start -1.143 0.5588)
			(end -1.143 -0.5588)
			(stroke
				(width 0.1)
				(type default)
			)
			(layer "B.SilkS")
		)
		(fp_line
			(start -1.143 -0.5588)
			(end 1.143 -0.5588)
			(stroke
				(width 0.1)
				(type default)
			)
			(layer "B.SilkS")
		)
		(fp_rect
			(start -1.143 0.5588)
			(end 1.143 -0.5588)
			(stroke
				(width 0)
				(type default)
			)
			(fill no)
			(layer "B.CrtYd")
		)
		(fp_line
			(start 0.508 0.3048)
			(end -0.508 0.3048)
			(stroke
				(width 0.1)
				(type default)
			)
			(layer "B.Fab")
		)
		(fp_line
			(start 0.508 -0.3048)
			(end 0.508 0.3048)
			(stroke
				(width 0.1)
				(type default)
			)
			(layer "B.Fab")
		)
		(fp_line
			(start -0.508 0.3048)
			(end -0.508 -0.3048)
			(stroke
				(width 0.1)
				(type default)
			)
			(layer "B.Fab")
		)
		(fp_line
			(start -0.508 -0.3048)
			(end 0.508 -0.3048)
			(stroke
				(width 0.1)
				(type default)
			)
			(layer "B.Fab")
		)
		(pad "1" smd rect
			(at 0.5334 0)
			(size 0.7112 0.6096)
			(layers "B.Cu" "B.Mask" "B.Paste")
			(net "XP1R8V_FPGA")
		)
		(pad "2" smd rect
			(at -0.5334 0)
			(size 0.7112 0.6096)
			(layers "B.Cu" "B.Mask" "B.Paste")
			(net "SG")
		)
		(zone
			(layer "B.Cu")
			(hatch none 0.5)
			(connect_pads
				(clearance 0)
			)
			(min_thickness 0.25)
			(keepout
				(tracks allowed)
				(vias not_allowed)
				(pads allowed)
				(copperpour not_allowed)
				(footprints allowed)
			)
			(placement
				(enabled no)
				(sheetname "")
			)
			(fill
				(thermal_gap 0.5)
				(thermal_bridge_width 0.5)
				(island_removal_mode 0)
			)
			(polygon
				(pts
					(xy 92.2782 -55.4228) (xy 92.1258 -55.4228) (xy 92.1258 -54.8132) (xy 92.2782 -54.8132)
				)
			)
		)
	)
	(footprint ""
		(layer "B.Cu")
		(at 100.84689 -37.323268 -90)
		(property "Reference" "C217"
			(at 1.524508 42.01922 270)
			(unlocked yes)
			(layer "B.SilkS")
			(effects
				(font
					(size 0.635 0.4064)
					(thickness 0.1524)
				)
				(justify mirror)
			)
		)
		(property "Value" "VAL*"
			(at 0 3.718306 270)
			(unlocked yes)
			(layer "B.Fab")
			(hide yes)
			(effects
				(font
					(size 0.7874 0.5842)
					(thickness 0.127)
				)
				(justify mirror)
			)
		)
		(property "Tolerance" "TOL*"
			(at 0 4.861306 270)
			(unlocked yes)
			(layer "Cmts.User")
			(hide yes)
			(effects
				(font
					(size 0.7874 0.5842)
					(thickness 0.127)
				)
				(justify mirror)
			)
		)
		(property "User Part Number" "PARTNUM*"
			(at 0 2.575306 270)
			(unlocked yes)
			(layer "Cmts.User")
			(hide yes)
			(effects
				(font
					(size 0.7874 0.5842)
					(thickness 0.127)
				)
				(justify mirror)
			)
		)
		(property "Device Type" "CAPACITOR-G105-0B104-CK,0.1UF,A"
			(at 0 1.432306 270)
			(unlocked yes)
			(layer "B.Fab")
			(hide yes)
			(effects
				(font
					(size 0.7874 0.5842)
					(thickness 0.127)
				)
				(justify mirror)
			)
		)
		(duplicate_pad_numbers_are_jumpers no)
		(fp_line
			(start -0.970026 0.4699)
			(end 0.970026 0.4699)
			(stroke
				(width 0.1)
				(type default)
			)
			(layer "B.SilkS")
		)
		(fp_line
			(start 0.970026 0.4699)
			(end 0.970026 -0.4699)
			(stroke
				(width 0.1)
				(type default)
			)
			(layer "B.SilkS")
		)
		(fp_line
			(start -0.970026 -0.4699)
			(end -0.970026 0.4699)
			(stroke
				(width 0.1)
				(type default)
			)
			(layer "B.SilkS")
		)
		(fp_line
			(start 0.970026 -0.4699)
			(end -0.970026 -0.4699)
			(stroke
				(width 0.1)
				(type default)
			)
			(layer "B.SilkS")
		)
		(fp_poly
			(pts
				(xy 0.970026 0.4699) (xy -0.970026 0.4699) (xy -0.970026 -0.4699) (xy 0.970026 -0.4699)
			)
			(stroke
				(width 0)
				(type default)
			)
			(fill no)
			(layer "B.CrtYd")
		)
		(fp_line
			(start -0.508 0.3048)
			(end 0.508 0.3048)
			(stroke
				(width 0.1)
				(type default)
			)
			(layer "B.Fab")
		)
		(fp_line
			(start 0.508 0.3048)
			(end 0.508 -0.3048)
			(stroke
				(width 0.1)
				(type default)
			)
			(layer "B.Fab")
		)
		(fp_line
			(start -0.508 -0.3048)
			(end -0.508 0.3048)
			(stroke
				(width 0.1)
				(type default)
			)
			(layer "B.Fab")
		)
		(fp_line
			(start 0.508 -0.3048)
			(end -0.508 -0.3048)
			(stroke
				(width 0.1)
				(type default)
			)
			(layer "B.Fab")
		)
		(pad "1" smd circle
			(at 0.500126 0 90)
			(size 0.635 0.635)
			(layers "B.Cu" "B.Mask" "B.Paste")
			(net "FPGA_MGTAVTT")
		)
		(pad "2" smd circle
			(at -0.500126 0 90)
			(size 0.635 0.635)
			(layers "B.Cu" "B.Mask" "B.Paste")
			(net "SG")
		)
	)
	(footprint ""
		(layer "B.Cu")
		(at 107.823 -104.521 180)
		(property "Reference" "R318"
			(at -0.127 2.88163 0)
			(unlocked yes)
			(layer "B.SilkS")
			(effects
				(font
					(size 0.7874 0.5842)
					(thickness 0.1524)
				)
				(justify mirror)
			)
		)
		(property "Value" "VAL*"
			(at -0.02032 2.13233 180)
			(unlocked yes)
			(layer "B.Fab")
			(hide yes)
			(effects
				(font
					(size 0.7874 0.5842)
					(thickness 0.1524)
				)
				(justify mirror)
			)
		)
		(property "Tolerance" "TOL*"
			(at -0.044704 3.05435 180)
			(unlocked yes)
			(layer "Cmts.User")
			(hide yes)
			(effects
				(font
					(size 0.7874 0.5842)
					(thickness 0.1524)
				)
				(justify mirror)
			)
		)
		(property "User Part Number" "PARTNUM*"
			(at -0.02032 4.024884 180)
			(unlocked yes)
			(layer "Cmts.User")
			(hide yes)
			(effects
				(font
					(size 0.7874 0.5842)
					(thickness 0.1524)
				)
				(justify mirror)
			)
		)
		(property "Device Type" "RESISTOR-G155-11002-01,10KOHM,A"
			(at -0.008382 1.210564 180)
			(unlocked yes)
			(layer "B.Fab")
			(hide yes)
			(effects
				(font
					(size 0.7874 0.5842)
					(thickness 0.1524)
				)
				(justify mirror)
			)
		)
		(duplicate_pad_numbers_are_jumpers no)
		(fp_line
			(start 1.143 0.5588)
			(end -1.143 0.5588)
			(stroke
				(width 0.1)
				(type default)
			)
			(layer "B.SilkS")
		)
		(fp_line
			(start 1.143 -0.5588)
			(end 1.143 0.5588)
			(stroke
				(width 0.1)
				(type default)
			)
			(layer "B.SilkS")
		)
		(fp_line
			(start -1.143 0.5588)
			(end -1.143 -0.5588)
			(stroke
				(width 0.1)
				(type default)
			)
			(layer "B.SilkS")
		)
		(fp_line
			(start -1.143 -0.5588)
			(end 1.143 -0.5588)
			(stroke
				(width 0.1)
				(type default)
			)
			(layer "B.SilkS")
		)
		(fp_poly
			(pts
				(xy 1.143 0.5588) (xy -1.143 0.5588) (xy -1.143 -0.5588) (xy 1.143 -0.5588)
			)
			(stroke
				(width 0)
				(type default)
			)
			(fill no)
			(layer "B.CrtYd")
		)
		(fp_line
			(start 0.508 0.3048)
			(end -0.508 0.3048)
			(stroke
				(width 0.1)
				(type default)
			)
			(layer "B.Fab")
		)
		(fp_line
			(start 0.508 -0.3048)
			(end 0.508 0.3048)
			(stroke
				(width 0.1)
				(type default)
			)
			(layer "B.Fab")
		)
		(fp_line
			(start -0.508 0.3048)
			(end -0.508 -0.3048)
			(stroke
				(width 0.1)
				(type default)
			)
			(layer "B.Fab")
		)
		(fp_line
			(start -0.508 -0.3048)
			(end 0.508 -0.3048)
			(stroke
				(width 0.1)
				(type default)
			)
			(layer "B.Fab")
		)
		(pad "1" smd rect
			(at 0.5334 0)
			(size 0.7112 0.6096)
			(layers "B.Cu" "B.Mask" "B.Paste")
			(net "XP3R3V_FPGA")
		)
		(pad "2" smd rect
			(at -0.5334 0)
			(size 0.7112 0.6096)
			(layers "B.Cu" "B.Mask" "B.Paste")
			(net "R_RGB_LED_I2C_SCL")
		)
		(zone
			(layer "B.Cu")
			(hatch none 0.5)
			(connect_pads
				(clearance 0)
			)
			(min_thickness 0.25)
			(keepout
				(tracks not_allowed)
				(vias allowed)
				(pads allowed)
				(copperpour not_allowed)
				(footprints allowed)
			)
			(placement
				(enabled no)
				(sheetname "")
			)
			(fill
				(thermal_gap 0.5)
				(thermal_bridge_width 0.5)
				(island_removal_mode 0)
			)
			(polygon
				(pts
					(xy 107.7468 -104.8258) (xy 107.7468 -104.2162) (xy 107.8992 -104.2162) (xy 107.8992 -104.8258)
				)
			)
		)
		(zone
			(layer "B.Cu")
			(hatch none 0.5)
			(connect_pads
				(clearance 0)
			)
			(min_thickness 0.25)
			(keepout
				(tracks allowed)
				(vias not_allowed)
				(pads allowed)
				(copperpour not_allowed)
				(footprints allowed)
			)
			(placement
				(enabled no)
				(sheetname "")
			)
			(fill
				(thermal_gap 0.5)
				(thermal_bridge_width 0.5)
				(island_removal_mode 0)
			)
			(polygon
				(pts
					(xy 107.7468 -104.8258) (xy 107.7468 -104.2162) (xy 107.8992 -104.2162) (xy 107.8992 -104.8258)
				)
			)
		)
	)
	(footprint ""
		(layer "B.Cu")
		(at 150.343108 -49.01311 -90)
		(property "Reference" "R64"
			(at -3.81889 0.776478 270)
			(unlocked yes)
			(layer "B.SilkS")
			(effects
				(font
					(size 0.7874 0.5842)
					(thickness 0.1524)
				)
				(justify mirror)
			)
		)
		(property "Value" "VAL*"
			(at -0.02032 2.13233 270)
			(unlocked yes)
			(layer "B.Fab")
			(hide yes)
			(effects
				(font
					(size 0.7874 0.5842)
					(thickness 0.1524)
				)
				(justify mirror)
			)
		)
		(property "Device Type" "RESISTOR-G155-14701-01,4.7KOHMA"
			(at -0.008382 1.210564 270)
			(unlocked yes)
			(layer "B.Fab")
			(hide yes)
			(effects
				(font
					(size 0.7874 0.5842)
					(thickness 0.1524)
				)
				(justify mirror)
			)
		)
		(property "User Part Number" "PARTNUM*"
			(at -0.02032 4.024884 270)
			(unlocked yes)
			(layer "Cmts.User")
			(hide yes)
			(effects
				(font
					(size 0.7874 0.5842)
					(thickness 0.1524)
				)
				(justify mirror)
			)
		)
		(property "Tolerance" "TOL*"
			(at -0.044704 3.05435 270)
			(unlocked yes)
			(layer "Cmts.User")
			(hide yes)
			(effects
				(font
					(size 0.7874 0.5842)
					(thickness 0.1524)
				)
				(justify mirror)
			)
		)
		(duplicate_pad_numbers_are_jumpers no)
		(fp_line
			(start -1.143 0.5588)
			(end -1.143 -0.5588)
			(stroke
				(width 0.1)
				(type default)
			)
			(layer "B.SilkS")
		)
		(fp_line
			(start 1.143 0.5588)
			(end -1.143 0.5588)
			(stroke
				(width 0.1)
				(type default)
			)
			(layer "B.SilkS")
		)
		(fp_line
			(start -1.143 -0.5588)
			(end 1.143 -0.5588)
			(stroke
				(width 0.1)
				(type default)
			)
			(layer "B.SilkS")
		)
		(fp_line
			(start 1.143 -0.5588)
			(end 1.143 0.5588)
			(stroke
				(width 0.1)
				(type default)
			)
			(layer "B.SilkS")
		)
		(fp_rect
			(start 1.143 0.5588)
			(end -1.143 -0.5588)
			(stroke
				(width 0)
				(type default)
			)
			(fill no)
			(layer "B.CrtYd")
		)
		(fp_line
			(start -0.508 0.3048)
			(end -0.508 -0.3048)
			(stroke
				(width 0.1)
				(type default)
			)
			(layer "B.Fab")
		)
		(fp_line
			(start 0.508 0.3048)
			(end -0.508 0.3048)
			(stroke
				(width 0.1)
				(type default)
			)
			(layer "B.Fab")
		)
		(fp_line
			(start -0.508 -0.3048)
			(end 0.508 -0.3048)
			(stroke
				(width 0.1)
				(type default)
			)
			(layer "B.Fab")
		)
		(fp_line
			(start 0.508 -0.3048)
			(end 0.508 0.3048)
			(stroke
				(width 0.1)
				(type default)
			)
			(layer "B.Fab")
		)
		(pad "1" smd rect
			(at 0.5334 0 90)
			(size 0.7112 0.6096)
			(layers "B.Cu" "B.Mask" "B.Paste")
			(net "XP3R3V_FPGA")
		)
		(pad "2" smd rect
			(at -0.5334 0 90)
			(size 0.7112 0.6096)
			(layers "B.Cu" "B.Mask" "B.Paste")
			(net "SHT3X_I2C_SDA")
		)
		(zone
			(layer "B.Cu")
			(hatch none 0.5)
			(connect_pads
				(clearance 0)
			)
			(min_thickness 0.25)
			(keepout
				(tracks allowed)
				(vias not_allowed)
				(pads allowed)
				(copperpour not_allowed)
				(footprints allowed)
			)
			(placement
				(enabled no)
				(sheetname "")
			)
			(fill
				(thermal_gap 0.5)
				(thermal_bridge_width 0.5)
				(island_removal_mode 0)
			)
			(polygon
				(pts
					(xy 150.038308 -48.93691) (xy 150.647908 -48.93691) (xy 150.647908 -49.08931) (xy 150.038308 -49.08931)
				)
			)
		)
	)
	(footprint ""
		(layer "B.Cu")
		(at 17.6784 -39.2176 180)
		(property "Reference" "R145"
			(at 0.4064 -2.55397 0)
			(unlocked yes)
			(layer "B.SilkS")
			(effects
				(font
					(size 0.7874 0.5842)
					(thickness 0.1524)
				)
				(justify mirror)
			)
		)
		(property "Value" "VAL*"
			(at -0.02032 2.13233 180)
			(unlocked yes)
			(layer "B.Fab")
			(hide yes)
			(effects
				(font
					(size 0.7874 0.5842)
					(thickness 0.1524)
				)
				(justify mirror)
			)
		)
		(property "Device Type" "RESISTOR-G155-133R0-01,33OHM,1%"
			(at -0.008382 1.210564 180)
			(unlocked yes)
			(layer "B.Fab")
			(hide yes)
			(effects
				(font
					(size 0.7874 0.5842)
					(thickness 0.1524)
				)
				(justify mirror)
			)
		)
		(property "User Part Number" "PARTNUM*"
			(at -0.02032 4.024884 180)
			(unlocked yes)
			(layer "Cmts.User")
			(hide yes)
			(effects
				(font
					(size 0.7874 0.5842)
					(thickness 0.1524)
				)
				(justify mirror)
			)
		)
		(property "Tolerance" "TOL*"
			(at -0.044704 3.05435 180)
			(unlocked yes)
			(layer "Cmts.User")
			(hide yes)
			(effects
				(font
					(size 0.7874 0.5842)
					(thickness 0.1524)
				)
				(justify mirror)
			)
		)
		(duplicate_pad_numbers_are_jumpers no)
		(fp_line
			(start 1.143 0.5588)
			(end -1.143 0.5588)
			(stroke
				(width 0.1)
				(type default)
			)
			(layer "B.SilkS")
		)
		(fp_line
			(start 1.143 -0.5588)
			(end 1.143 0.5588)
			(stroke
				(width 0.1)
				(type default)
			)
			(layer "B.SilkS")
		)
		(fp_line
			(start -1.143 0.5588)
			(end -1.143 -0.5588)
			(stroke
				(width 0.1)
				(type default)
			)
			(layer "B.SilkS")
		)
		(fp_line
			(start -1.143 -0.5588)
			(end 1.143 -0.5588)
			(stroke
				(width 0.1)
				(type default)
			)
			(layer "B.SilkS")
		)
		(fp_rect
			(start 1.143 0.5588)
			(end -1.143 -0.5588)
			(stroke
				(width 0)
				(type default)
			)
			(fill no)
			(layer "B.CrtYd")
		)
		(fp_line
			(start 0.508 0.3048)
			(end -0.508 0.3048)
			(stroke
				(width 0.1)
				(type default)
			)
			(layer "B.Fab")
		)
		(fp_line
			(start 0.508 -0.3048)
			(end 0.508 0.3048)
			(stroke
				(width 0.1)
				(type default)
			)
			(layer "B.Fab")
		)
		(fp_line
			(start -0.508 0.3048)
			(end -0.508 -0.3048)
			(stroke
				(width 0.1)
				(type default)
			)
			(layer "B.Fab")
		)
		(fp_line
			(start -0.508 -0.3048)
			(end 0.508 -0.3048)
			(stroke
				(width 0.1)
				(type default)
			)
			(layer "B.Fab")
		)
		(pad "1" smd rect
			(at 0.5334 0)
			(size 0.7112 0.6096)
			(layers "B.Cu" "B.Mask" "B.Paste")
			(net "PCA9546_I2C_SCL")
		)
		(pad "2" smd rect
			(at -0.5334 0)
			(size 0.7112 0.6096)
			(layers "B.Cu" "B.Mask" "B.Paste")
			(net "R_PCA9546_I2C_SCL")
		)
		(zone
			(layer "B.Cu")
			(hatch none 0.5)
			(connect_pads
				(clearance 0)
			)
			(min_thickness 0.25)
			(keepout
				(tracks allowed)
				(vias not_allowed)
				(pads allowed)
				(copperpour not_allowed)
				(footprints allowed)
			)
			(placement
				(enabled no)
				(sheetname "")
			)
			(fill
				(thermal_gap 0.5)
				(thermal_bridge_width 0.5)
				(island_removal_mode 0)
			)
			(polygon
				(pts
					(xy 17.6022 -39.5224) (xy 17.6022 -38.9128) (xy 17.7546 -38.9128) (xy 17.7546 -39.5224)
				)
			)
		)
	)
	(footprint ""
		(layer "B.Cu")
		(at 98.17862 -44.323)
		(property "Reference" "C104"
			(at -0.13462 -1.42875 0)
			(unlocked yes)
			(layer "B.SilkS")
			(effects
				(font
					(size 0.635 0.4064)
					(thickness 0.1524)
				)
				(justify mirror)
			)
		)
		(property "Value" "VAL*"
			(at -0.0762 2.067306 0)
			(unlocked yes)
			(layer "B.Fab")
			(hide yes)
			(effects
				(font
					(size 0.7874 0.5842)
					(thickness 0.1524)
				)
				(justify mirror)
			)
		)
		(property "Tolerance" "TOL*"
			(at -0.0762 3.032506 0)
			(unlocked yes)
			(layer "Cmts.User")
			(hide yes)
			(effects
				(font
					(size 0.7874 0.5842)
					(thickness 0.1524)
				)
				(justify mirror)
			)
		)
		(property "User Part Number" "PARTNUM*"
			(at -0.1016 4.023106 0)
			(unlocked yes)
			(layer "Cmts.User")
			(hide yes)
			(effects
				(font
					(size 0.7874 0.5842)
					(thickness 0.1524)
				)
				(justify mirror)
			)
		)
		(property "Device Type" "CAPACITOR-G105-0B104-CK,0.1UF,A"
			(at -0.0508 1.127506 0)
			(unlocked yes)
			(layer "B.Fab")
			(hide yes)
			(effects
				(font
					(size 0.7874 0.5842)
					(thickness 0.1524)
				)
				(justify mirror)
			)
		)
		(duplicate_pad_numbers_are_jumpers no)
		(fp_line
			(start -1.143 -0.5588)
			(end 1.143 -0.5588)
			(stroke
				(width 0.1)
				(type default)
			)
			(layer "B.SilkS")
		)
		(fp_line
			(start -1.143 0.5588)
			(end -1.143 -0.5588)
			(stroke
				(width 0.1)
				(type default)
			)
			(layer "B.SilkS")
		)
		(fp_line
			(start 1.143 -0.5588)
			(end 1.143 0.5588)
			(stroke
				(width 0.1)
				(type default)
			)
			(layer "B.SilkS")
		)
		(fp_line
			(start 1.143 0.5588)
			(end -1.143 0.5588)
			(stroke
				(width 0.1)
				(type default)
			)
			(layer "B.SilkS")
		)
		(fp_rect
			(start -1.143 0.5588)
			(end 1.143 -0.5588)
			(stroke
				(width 0)
				(type default)
			)
			(fill no)
			(layer "B.CrtYd")
		)
		(fp_line
			(start -0.508 -0.3048)
			(end 0.508 -0.3048)
			(stroke
				(width 0.1)
				(type default)
			)
			(layer "B.Fab")
		)
		(fp_line
			(start -0.508 0.3048)
			(end -0.508 -0.3048)
			(stroke
				(width 0.1)
				(type default)
			)
			(layer "B.Fab")
		)
		(fp_line
			(start 0.508 -0.3048)
			(end 0.508 0.3048)
			(stroke
				(width 0.1)
				(type default)
			)
			(layer "B.Fab")
		)
		(fp_line
			(start 0.508 0.3048)
			(end -0.508 0.3048)
			(stroke
				(width 0.1)
				(type default)
			)
			(layer "B.Fab")
		)
		(pad "1" smd rect
			(at 0.5334 0 180)
			(size 0.7112 0.6096)
			(layers "B.Cu" "B.Mask" "B.Paste")
			(net "FPGA_MGTAVTT")
		)
		(pad "2" smd rect
			(at -0.5334 0 180)
			(size 0.7112 0.6096)
			(layers "B.Cu" "B.Mask" "B.Paste")
			(net "SG")
		)
		(zone
			(layer "B.Cu")
			(hatch none 0.5)
			(connect_pads
				(clearance 0)
			)
			(min_thickness 0.25)
			(keepout
				(tracks allowed)
				(vias not_allowed)
				(pads allowed)
				(copperpour not_allowed)
				(footprints allowed)
			)
			(placement
				(enabled no)
				(sheetname "")
			)
			(fill
				(thermal_gap 0.5)
				(thermal_bridge_width 0.5)
				(island_removal_mode 0)
			)
			(polygon
				(pts
					(xy 98.10242 -44.0182) (xy 98.25482 -44.0182) (xy 98.25482 -44.6278) (xy 98.10242 -44.6278)
				)
			)
		)
	)
	(footprint ""
		(layer "B.Cu")
		(at 101.0412 -64.2874 90)
		(property "Reference" "R171"
			(at 3.4036 -0.24257 270)
			(unlocked yes)
			(layer "B.SilkS")
			(effects
				(font
					(size 0.7874 0.5842)
					(thickness 0.1524)
				)
				(justify mirror)
			)
		)
		(property "Value" "VAL*"
			(at -0.02032 2.13233 90)
			(unlocked yes)
			(layer "B.Fab")
			(hide yes)
			(effects
				(font
					(size 0.7874 0.5842)
					(thickness 0.1524)
				)
				(justify mirror)
			)
		)
		(property "Tolerance" "TOL*"
			(at -0.044704 3.05435 90)
			(unlocked yes)
			(layer "Cmts.User")
			(hide yes)
			(effects
				(font
					(size 0.7874 0.5842)
					(thickness 0.1524)
				)
				(justify mirror)
			)
		)
		(property "User Part Number" "PARTNUM*"
			(at -0.02032 4.024884 90)
			(unlocked yes)
			(layer "Cmts.User")
			(hide yes)
			(effects
				(font
					(size 0.7874 0.5842)
					(thickness 0.1524)
				)
				(justify mirror)
			)
		)
		(property "Device Type" "RESISTOR-G155-14701-01,4.7KOHMA"
			(at -0.008382 1.210564 90)
			(unlocked yes)
			(layer "B.Fab")
			(hide yes)
			(effects
				(font
					(size 0.7874 0.5842)
					(thickness 0.1524)
				)
				(justify mirror)
			)
		)
		(duplicate_pad_numbers_are_jumpers no)
		(fp_line
			(start 1.143 -0.5588)
			(end 1.143 0.5588)
			(stroke
				(width 0.1)
				(type default)
			)
			(layer "B.SilkS")
		)
		(fp_line
			(start -1.143 -0.5588)
			(end 1.143 -0.5588)
			(stroke
				(width 0.1)
				(type default)
			)
			(layer "B.SilkS")
		)
		(fp_line
			(start 1.143 0.5588)
			(end -1.143 0.5588)
			(stroke
				(width 0.1)
				(type default)
			)
			(layer "B.SilkS")
		)
		(fp_line
			(start -1.143 0.5588)
			(end -1.143 -0.5588)
			(stroke
				(width 0.1)
				(type default)
			)
			(layer "B.SilkS")
		)
		(fp_rect
			(start -1.143 0.5588)
			(end 1.143 -0.5588)
			(stroke
				(width 0)
				(type default)
			)
			(fill no)
			(layer "B.CrtYd")
		)
		(fp_line
			(start 0.508 -0.3048)
			(end 0.508 0.3048)
			(stroke
				(width 0.1)
				(type default)
			)
			(layer "B.Fab")
		)
		(fp_line
			(start -0.508 -0.3048)
			(end 0.508 -0.3048)
			(stroke
				(width 0.1)
				(type default)
			)
			(layer "B.Fab")
		)
		(fp_line
			(start 0.508 0.3048)
			(end -0.508 0.3048)
			(stroke
				(width 0.1)
				(type default)
			)
			(layer "B.Fab")
		)
		(fp_line
			(start -0.508 0.3048)
			(end -0.508 -0.3048)
			(stroke
				(width 0.1)
				(type default)
			)
			(layer "B.Fab")
		)
		(pad "1" smd rect
			(at 0.5334 0 270)
			(size 0.7112 0.6096)
			(layers "B.Cu" "B.Mask" "B.Paste")
			(net "SG")
		)
		(pad "2" smd rect
			(at -0.5334 0 270)
			(size 0.7112 0.6096)
			(layers "B.Cu" "B.Mask" "B.Paste")
			(net "FPGA_IO_0")
		)
		(zone
			(layer "B.Cu")
			(hatch none 0.5)
			(connect_pads
				(clearance 0)
			)
			(min_thickness 0.25)
			(keepout
				(tracks allowed)
				(vias not_allowed)
				(pads allowed)
				(copperpour not_allowed)
				(footprints allowed)
			)
			(placement
				(enabled no)
				(sheetname "")
			)
			(fill
				(thermal_gap 0.5)
				(thermal_bridge_width 0.5)
				(island_removal_mode 0)
			)
			(polygon
				(pts
					(xy 101.346 -64.2112) (xy 101.346 -64.3636) (xy 100.7364 -64.3636) (xy 100.7364 -64.2112)
				)
			)
		)
	)
	(footprint ""
		(layer "B.Cu")
		(at 73.66 -72.771 -90)
		(property "Reference" "C60"
			(at -3.81 -0.59563 270)
			(unlocked yes)
			(layer "B.SilkS")
			(effects
				(font
					(size 0.7874 0.5842)
					(thickness 0.1524)
				)
				(justify mirror)
			)
		)
		(property "Value" "VAL*"
			(at -0.0762 2.067306 270)
			(unlocked yes)
			(layer "B.Fab")
			(hide yes)
			(effects
				(font
					(size 0.7874 0.5842)
					(thickness 0.1524)
				)
				(justify mirror)
			)
		)
		(property "Tolerance" "TOL*"
			(at -0.0762 3.032506 270)
			(unlocked yes)
			(layer "Cmts.User")
			(hide yes)
			(effects
				(font
					(size 0.7874 0.5842)
					(thickness 0.1524)
				)
				(justify mirror)
			)
		)
		(property "User Part Number" "PARTNUM*"
			(at -0.1016 4.023106 270)
			(unlocked yes)
			(layer "Cmts.User")
			(hide yes)
			(effects
				(font
					(size 0.7874 0.5842)
					(thickness 0.1524)
				)
				(justify mirror)
			)
		)
		(property "Device Type" "CAPACITOR-G105-0B104-EK,0.1UF,A"
			(at -0.0508 1.127506 270)
			(unlocked yes)
			(layer "B.Fab")
			(hide yes)
			(effects
				(font
					(size 0.7874 0.5842)
					(thickness 0.1524)
				)
				(justify mirror)
			)
		)
		(duplicate_pad_numbers_are_jumpers no)
		(fp_line
			(start -1.143 0.5588)
			(end -1.143 -0.5588)
			(stroke
				(width 0.1)
				(type default)
			)
			(layer "B.SilkS")
		)
		(fp_line
			(start 1.143 0.5588)
			(end -1.143 0.5588)
			(stroke
				(width 0.1)
				(type default)
			)
			(layer "B.SilkS")
		)
		(fp_line
			(start -1.143 -0.5588)
			(end 1.143 -0.5588)
			(stroke
				(width 0.1)
				(type default)
			)
			(layer "B.SilkS")
		)
		(fp_line
			(start 1.143 -0.5588)
			(end 1.143 0.5588)
			(stroke
				(width 0.1)
				(type default)
			)
			(layer "B.SilkS")
		)
		(fp_rect
			(start 1.143 -0.5588)
			(end -1.143 0.5588)
			(stroke
				(width 0)
				(type default)
			)
			(fill no)
			(layer "B.CrtYd")
		)
		(fp_line
			(start -0.508 0.3048)
			(end -0.508 -0.3048)
			(stroke
				(width 0.1)
				(type default)
			)
			(layer "B.Fab")
		)
		(fp_line
			(start 0.508 0.3048)
			(end -0.508 0.3048)
			(stroke
				(width 0.1)
				(type default)
			)
			(layer "B.Fab")
		)
		(fp_line
			(start -0.508 -0.3048)
			(end 0.508 -0.3048)
			(stroke
				(width 0.1)
				(type default)
			)
			(layer "B.Fab")
		)
		(fp_line
			(start 0.508 -0.3048)
			(end 0.508 0.3048)
			(stroke
				(width 0.1)
				(type default)
			)
			(layer "B.Fab")
		)
		(pad "1" smd rect
			(at 0.5334 0 90)
			(size 0.7112 0.6096)
			(layers "B.Cu" "B.Mask" "B.Paste")
			(net "XP5R0V_MAC")
		)
		(pad "2" smd rect
			(at -0.5334 0 90)
			(size 0.7112 0.6096)
			(layers "B.Cu" "B.Mask" "B.Paste")
			(net "SG")
		)
		(zone
			(layer "B.Cu")
			(hatch none 0.5)
			(connect_pads
				(clearance 0)
			)
			(min_thickness 0.25)
			(keepout
				(tracks allowed)
				(vias not_allowed)
				(pads allowed)
				(copperpour not_allowed)
				(footprints allowed)
			)
			(placement
				(enabled no)
				(sheetname "")
			)
			(fill
				(thermal_gap 0.5)
				(thermal_bridge_width 0.5)
				(island_removal_mode 0)
			)
			(polygon
				(pts
					(xy 73.9648 -72.6948) (xy 73.9648 -72.8472) (xy 73.3552 -72.8472) (xy 73.3552 -72.6948)
				)
			)
		)
	)
	(footprint ""
		(layer "B.Cu")
		(at 18.415 -80.137)
		(property "Reference" "R473"
			(at 3.81 0.29337 0)
			(unlocked yes)
			(layer "B.SilkS")
			(effects
				(font
					(size 0.7874 0.5842)
					(thickness 0.1524)
				)
				(justify mirror)
			)
		)
		(property "Value" "VAL*"
			(at -0.02032 2.13233 0)
			(unlocked yes)
			(layer "B.Fab")
			(hide yes)
			(effects
				(font
					(size 0.7874 0.5842)
					(thickness 0.1524)
				)
				(justify mirror)
			)
		)
		(property "Tolerance" "TOL*"
			(at -0.044704 3.05435 0)
			(unlocked yes)
			(layer "Cmts.User")
			(hide yes)
			(effects
				(font
					(size 0.7874 0.5842)
					(thickness 0.1524)
				)
				(justify mirror)
			)
		)
		(property "User Part Number" "PARTNUM*"
			(at -0.02032 4.024884 0)
			(unlocked yes)
			(layer "Cmts.User")
			(hide yes)
			(effects
				(font
					(size 0.7874 0.5842)
					(thickness 0.1524)
				)
				(justify mirror)
			)
		)
		(property "Device Type" "RESISTOR-G155-100R0-J0,0OHM,-"
			(at -0.008382 1.210564 0)
			(unlocked yes)
			(layer "B.Fab")
			(hide yes)
			(effects
				(font
					(size 0.7874 0.5842)
					(thickness 0.1524)
				)
				(justify mirror)
			)
		)
		(duplicate_pad_numbers_are_jumpers no)
		(fp_line
			(start -1.143 -0.5588)
			(end 1.143 -0.5588)
			(stroke
				(width 0.1)
				(type default)
			)
			(layer "B.SilkS")
		)
		(fp_line
			(start -1.143 0.5588)
			(end -1.143 -0.5588)
			(stroke
				(width 0.1)
				(type default)
			)
			(layer "B.SilkS")
		)
		(fp_line
			(start 1.143 -0.5588)
			(end 1.143 0.5588)
			(stroke
				(width 0.1)
				(type default)
			)
			(layer "B.SilkS")
		)
		(fp_line
			(start 1.143 0.5588)
			(end -1.143 0.5588)
			(stroke
				(width 0.1)
				(type default)
			)
			(layer "B.SilkS")
		)
		(fp_poly
			(pts
				(xy 1.143 0.5588) (xy -1.143 0.5588) (xy -1.143 -0.5588) (xy 1.143 -0.5588)
			)
			(stroke
				(width 0)
				(type default)
			)
			(fill no)
			(layer "B.CrtYd")
		)
		(fp_line
			(start -0.508 -0.3048)
			(end 0.508 -0.3048)
			(stroke
				(width 0.1)
				(type default)
			)
			(layer "B.Fab")
		)
		(fp_line
			(start -0.508 0.3048)
			(end -0.508 -0.3048)
			(stroke
				(width 0.1)
				(type default)
			)
			(layer "B.Fab")
		)
		(fp_line
			(start 0.508 -0.3048)
			(end 0.508 0.3048)
			(stroke
				(width 0.1)
				(type default)
			)
			(layer "B.Fab")
		)
		(fp_line
			(start 0.508 0.3048)
			(end -0.508 0.3048)
			(stroke
				(width 0.1)
				(type default)
			)
			(layer "B.Fab")
		)
		(pad "1" smd rect
			(at 0.5334 0 180)
			(size 0.7112 0.6096)
			(layers "B.Cu" "B.Mask" "B.Paste")
			(net "R_FT4232_I2C_SDA_IN")
		)
		(pad "2" smd rect
			(at -0.5334 0 180)
			(size 0.7112 0.6096)
			(layers "B.Cu" "B.Mask" "B.Paste")
			(net "FT4232_I2C_SDA")
		)
		(zone
			(layer "B.Cu")
			(hatch none 0.5)
			(connect_pads
				(clearance 0)
			)
			(min_thickness 0.25)
			(keepout
				(tracks not_allowed)
				(vias allowed)
				(pads allowed)
				(copperpour not_allowed)
				(footprints allowed)
			)
			(placement
				(enabled no)
				(sheetname "")
			)
			(fill
				(thermal_gap 0.5)
				(thermal_bridge_width 0.5)
				(island_removal_mode 0)
			)
			(polygon
				(pts
					(xy 18.4912 -79.8322) (xy 18.4912 -80.4418) (xy 18.3388 -80.4418) (xy 18.3388 -79.8322)
				)
			)
		)
		(zone
			(layer "B.Cu")
			(hatch none 0.5)
			(connect_pads
				(clearance 0)
			)
			(min_thickness 0.25)
			(keepout
				(tracks allowed)
				(vias not_allowed)
				(pads allowed)
				(copperpour not_allowed)
				(footprints allowed)
			)
			(placement
				(enabled no)
				(sheetname "")
			)
			(fill
				(thermal_gap 0.5)
				(thermal_bridge_width 0.5)
				(island_removal_mode 0)
			)
			(polygon
				(pts
					(xy 18.4912 -79.8322) (xy 18.4912 -80.4418) (xy 18.3388 -80.4418) (xy 18.3388 -79.8322)
				)
			)
		)
	)
	(footprint ""
		(layer "B.Cu")
		(at 162.56 -24.511 180)
		(property "Reference" "R411"
			(at 0.381 -1.43637 0)
			(unlocked yes)
			(layer "B.SilkS")
			(effects
				(font
					(size 0.7874 0.5842)
					(thickness 0.1524)
				)
				(justify mirror)
			)
		)
		(property "Value" "VAL*"
			(at -0.02032 2.13233 180)
			(unlocked yes)
			(layer "B.Fab")
			(hide yes)
			(effects
				(font
					(size 0.7874 0.5842)
					(thickness 0.1524)
				)
				(justify mirror)
			)
		)
		(property "Tolerance" "TOL*"
			(at -0.044704 3.05435 180)
			(unlocked yes)
			(layer "Cmts.User")
			(hide yes)
			(effects
				(font
					(size 0.7874 0.5842)
					(thickness 0.1524)
				)
				(justify mirror)
			)
		)
		(property "User Part Number" "PARTNUM*"
			(at -0.02032 4.024884 180)
			(unlocked yes)
			(layer "Cmts.User")
			(hide yes)
			(effects
				(font
					(size 0.7874 0.5842)
					(thickness 0.1524)
				)
				(justify mirror)
			)
		)
		(property "Device Type" "RESISTOR-G155-11001-01,1KOHM,1%"
			(at -0.008382 1.210564 180)
			(unlocked yes)
			(layer "B.Fab")
			(hide yes)
			(effects
				(font
					(size 0.7874 0.5842)
					(thickness 0.1524)
				)
				(justify mirror)
			)
		)
		(duplicate_pad_numbers_are_jumpers no)
		(fp_line
			(start 1.143 0.5588)
			(end -1.143 0.5588)
			(stroke
				(width 0.1)
				(type default)
			)
			(layer "B.SilkS")
		)
		(fp_line
			(start 1.143 -0.5588)
			(end 1.143 0.5588)
			(stroke
				(width 0.1)
				(type default)
			)
			(layer "B.SilkS")
		)
		(fp_line
			(start -1.143 0.5588)
			(end -1.143 -0.5588)
			(stroke
				(width 0.1)
				(type default)
			)
			(layer "B.SilkS")
		)
		(fp_line
			(start -1.143 -0.5588)
			(end 1.143 -0.5588)
			(stroke
				(width 0.1)
				(type default)
			)
			(layer "B.SilkS")
		)
		(fp_rect
			(start 1.143 0.5588)
			(end -1.143 -0.5588)
			(stroke
				(width 0)
				(type default)
			)
			(fill no)
			(layer "B.CrtYd")
		)
		(fp_line
			(start 0.508 0.3048)
			(end -0.508 0.3048)
			(stroke
				(width 0.1)
				(type default)
			)
			(layer "B.Fab")
		)
		(fp_line
			(start 0.508 -0.3048)
			(end 0.508 0.3048)
			(stroke
				(width 0.1)
				(type default)
			)
			(layer "B.Fab")
		)
		(fp_line
			(start -0.508 0.3048)
			(end -0.508 -0.3048)
			(stroke
				(width 0.1)
				(type default)
			)
			(layer "B.Fab")
		)
		(fp_line
			(start -0.508 -0.3048)
			(end 0.508 -0.3048)
			(stroke
				(width 0.1)
				(type default)
			)
			(layer "B.Fab")
		)
		(pad "1" smd rect
			(at 0.5334 0)
			(size 0.7112 0.6096)
			(layers "B.Cu" "B.Mask" "B.Paste")
			(net "UNNAMED_6_LM75BDPTSSOP8_I81_A2")
		)
		(pad "2" smd rect
			(at -0.5334 0)
			(size 0.7112 0.6096)
			(layers "B.Cu" "B.Mask" "B.Paste")
			(net "SG")
		)
		(zone
			(layer "B.Cu")
			(hatch none 0.5)
			(connect_pads
				(clearance 0)
			)
			(min_thickness 0.25)
			(keepout
				(tracks allowed)
				(vias not_allowed)
				(pads allowed)
				(copperpour not_allowed)
				(footprints allowed)
			)
			(placement
				(enabled no)
				(sheetname "")
			)
			(fill
				(thermal_gap 0.5)
				(thermal_bridge_width 0.5)
				(island_removal_mode 0)
			)
			(polygon
				(pts
					(xy 162.4838 -24.8158) (xy 162.4838 -24.2062) (xy 162.6362 -24.2062) (xy 162.6362 -24.8158)
				)
			)
		)
		(zone
			(layer "B.Cu")
			(hatch none 0.5)
			(connect_pads
				(clearance 0)
			)
			(min_thickness 0.25)
			(keepout
				(tracks not_allowed)
				(vias allowed)
				(pads allowed)
				(copperpour not_allowed)
				(footprints allowed)
			)
			(placement
				(enabled no)
				(sheetname "")
			)
			(fill
				(thermal_gap 0.5)
				(thermal_bridge_width 0.5)
				(island_removal_mode 0)
			)
			(polygon
				(pts
					(xy 162.4838 -24.8158) (xy 162.4838 -24.2062) (xy 162.6362 -24.2062) (xy 162.6362 -24.8158)
				)
			)
		)
	)
	(footprint ""
		(layer "B.Cu")
		(at 153.0858 -107.696 90)
		(property "Reference" "R279"
			(at 0.508 -2.37617 270)
			(unlocked yes)
			(layer "B.SilkS")
			(effects
				(font
					(size 0.7874 0.5842)
					(thickness 0.1524)
				)
				(justify mirror)
			)
		)
		(property "Value" "VAL*"
			(at -0.02032 2.13233 90)
			(unlocked yes)
			(layer "B.Fab")
			(hide yes)
			(effects
				(font
					(size 0.7874 0.5842)
					(thickness 0.1524)
				)
				(justify mirror)
			)
		)
		(property "Tolerance" "TOL*"
			(at -0.044704 3.05435 90)
			(unlocked yes)
			(layer "Cmts.User")
			(hide yes)
			(effects
				(font
					(size 0.7874 0.5842)
					(thickness 0.1524)
				)
				(justify mirror)
			)
		)
		(property "User Part Number" "PARTNUM*"
			(at -0.02032 4.024884 90)
			(unlocked yes)
			(layer "Cmts.User")
			(hide yes)
			(effects
				(font
					(size 0.7874 0.5842)
					(thickness 0.1524)
				)
				(justify mirror)
			)
		)
		(property "Device Type" "RESISTOR-G155-13300-01,330OHM,A"
			(at -0.008382 1.210564 90)
			(unlocked yes)
			(layer "B.Fab")
			(hide yes)
			(effects
				(font
					(size 0.7874 0.5842)
					(thickness 0.1524)
				)
				(justify mirror)
			)
		)
		(duplicate_pad_numbers_are_jumpers no)
		(fp_line
			(start 1.143 -0.5588)
			(end 1.143 0.5588)
			(stroke
				(width 0.1)
				(type default)
			)
			(layer "B.SilkS")
		)
		(fp_line
			(start -1.143 -0.5588)
			(end 1.143 -0.5588)
			(stroke
				(width 0.1)
				(type default)
			)
			(layer "B.SilkS")
		)
		(fp_line
			(start 1.143 0.5588)
			(end -1.143 0.5588)
			(stroke
				(width 0.1)
				(type default)
			)
			(layer "B.SilkS")
		)
		(fp_line
			(start -1.143 0.5588)
			(end -1.143 -0.5588)
			(stroke
				(width 0.1)
				(type default)
			)
			(layer "B.SilkS")
		)
		(fp_rect
			(start -1.143 -0.5588)
			(end 1.143 0.5588)
			(stroke
				(width 0)
				(type default)
			)
			(fill no)
			(layer "B.CrtYd")
		)
		(fp_line
			(start 0.508 -0.3048)
			(end 0.508 0.3048)
			(stroke
				(width 0.1)
				(type default)
			)
			(layer "B.Fab")
		)
		(fp_line
			(start -0.508 -0.3048)
			(end 0.508 -0.3048)
			(stroke
				(width 0.1)
				(type default)
			)
			(layer "B.Fab")
		)
		(fp_line
			(start 0.508 0.3048)
			(end -0.508 0.3048)
			(stroke
				(width 0.1)
				(type default)
			)
			(layer "B.Fab")
		)
		(fp_line
			(start -0.508 0.3048)
			(end -0.508 -0.3048)
			(stroke
				(width 0.1)
				(type default)
			)
			(layer "B.Fab")
		)
		(pad "1" smd rect
			(at 0.5334 0 270)
			(size 0.7112 0.6096)
			(layers "B.Cu" "B.Mask" "B.Paste")
			(net "UNNAMED_14_OPTICAL_I138_A")
		)
		(pad "2" smd rect
			(at -0.5334 0 270)
			(size 0.7112 0.6096)
			(layers "B.Cu" "B.Mask" "B.Paste")
			(net "XP3R3V_FPGA")
		)
		(zone
			(layer "B.Cu")
			(hatch none 0.5)
			(connect_pads
				(clearance 0)
			)
			(min_thickness 0.25)
			(keepout
				(tracks allowed)
				(vias not_allowed)
				(pads allowed)
				(copperpour not_allowed)
				(footprints allowed)
			)
			(placement
				(enabled no)
				(sheetname "")
			)
			(fill
				(thermal_gap 0.5)
				(thermal_bridge_width 0.5)
				(island_removal_mode 0)
			)
			(polygon
				(pts
					(xy 152.781 -107.6198) (xy 153.3906 -107.6198) (xy 153.3906 -107.7722) (xy 152.781 -107.7722)
				)
			)
		)
	)
	(footprint ""
		(layer "B.Cu")
		(at 87.376 -56.134)
		(property "Reference" "R76"
			(at 1.778 3.08737 0)
			(unlocked yes)
			(layer "B.SilkS")
			(effects
				(font
					(size 0.7874 0.5842)
					(thickness 0.1524)
				)
				(justify mirror)
			)
		)
		(property "Value" "VAL*"
			(at -0.02032 2.13233 0)
			(unlocked yes)
			(layer "B.Fab")
			(hide yes)
			(effects
				(font
					(size 0.7874 0.5842)
					(thickness 0.1524)
				)
				(justify mirror)
			)
		)
		(property "Device Type" "RESISTOR-G155-133R0-01,33OHM,1%"
			(at -0.008382 1.210564 0)
			(unlocked yes)
			(layer "B.Fab")
			(hide yes)
			(effects
				(font
					(size 0.7874 0.5842)
					(thickness 0.1524)
				)
				(justify mirror)
			)
		)
		(property "User Part Number" "PARTNUM*"
			(at -0.02032 4.024884 0)
			(unlocked yes)
			(layer "Cmts.User")
			(hide yes)
			(effects
				(font
					(size 0.7874 0.5842)
					(thickness 0.1524)
				)
				(justify mirror)
			)
		)
		(property "Tolerance" "TOL*"
			(at -0.044704 3.05435 0)
			(unlocked yes)
			(layer "Cmts.User")
			(hide yes)
			(effects
				(font
					(size 0.7874 0.5842)
					(thickness 0.1524)
				)
				(justify mirror)
			)
		)
		(duplicate_pad_numbers_are_jumpers no)
		(fp_line
			(start -1.143 -0.5588)
			(end 1.143 -0.5588)
			(stroke
				(width 0.1)
				(type default)
			)
			(layer "B.SilkS")
		)
		(fp_line
			(start -1.143 0.5588)
			(end -1.143 -0.5588)
			(stroke
				(width 0.1)
				(type default)
			)
			(layer "B.SilkS")
		)
		(fp_line
			(start 1.143 -0.5588)
			(end 1.143 0.5588)
			(stroke
				(width 0.1)
				(type default)
			)
			(layer "B.SilkS")
		)
		(fp_line
			(start 1.143 0.5588)
			(end -1.143 0.5588)
			(stroke
				(width 0.1)
				(type default)
			)
			(layer "B.SilkS")
		)
		(fp_rect
			(start 1.143 -0.5588)
			(end -1.143 0.5588)
			(stroke
				(width 0)
				(type default)
			)
			(fill no)
			(layer "B.CrtYd")
		)
		(fp_line
			(start -0.508 -0.3048)
			(end 0.508 -0.3048)
			(stroke
				(width 0.1)
				(type default)
			)
			(layer "B.Fab")
		)
		(fp_line
			(start -0.508 0.3048)
			(end -0.508 -0.3048)
			(stroke
				(width 0.1)
				(type default)
			)
			(layer "B.Fab")
		)
		(fp_line
			(start 0.508 -0.3048)
			(end 0.508 0.3048)
			(stroke
				(width 0.1)
				(type default)
			)
			(layer "B.Fab")
		)
		(fp_line
			(start 0.508 0.3048)
			(end -0.508 0.3048)
			(stroke
				(width 0.1)
				(type default)
			)
			(layer "B.Fab")
		)
		(pad "1" smd rect
			(at 0.5334 0 180)
			(size 0.7112 0.6096)
			(layers "B.Cu" "B.Mask" "B.Paste")
			(net "BNO080_I2C_SDA")
		)
		(pad "2" smd rect
			(at -0.5334 0 180)
			(size 0.7112 0.6096)
			(layers "B.Cu" "B.Mask" "B.Paste")
			(net "R_BNO080_I2C_SDA")
		)
		(zone
			(layer "B.Cu")
			(hatch none 0.5)
			(connect_pads
				(clearance 0)
			)
			(min_thickness 0.25)
			(keepout
				(tracks allowed)
				(vias not_allowed)
				(pads allowed)
				(copperpour not_allowed)
				(footprints allowed)
			)
			(placement
				(enabled no)
				(sheetname "")
			)
			(fill
				(thermal_gap 0.5)
				(thermal_bridge_width 0.5)
				(island_removal_mode 0)
			)
			(polygon
				(pts
					(xy 87.4522 -56.4388) (xy 87.2998 -56.4388) (xy 87.2998 -55.8292) (xy 87.4522 -55.8292)
				)
			)
		)
	)
	(footprint ""
		(layer "B.Cu")
		(at 115.443 -70.993)
		(property "Reference" "R260"
			(at -0.127 2.19837 0)
			(unlocked yes)
			(layer "B.SilkS")
			(effects
				(font
					(size 0.7874 0.5842)
					(thickness 0.1524)
				)
				(justify mirror)
			)
		)
		(property "Value" "VAL*"
			(at -0.02032 2.13233 0)
			(unlocked yes)
			(layer "B.Fab")
			(hide yes)
			(effects
				(font
					(size 0.7874 0.5842)
					(thickness 0.1524)
				)
				(justify mirror)
			)
		)
		(property "Tolerance" "TOL*"
			(at -0.044704 3.05435 0)
			(unlocked yes)
			(layer "Cmts.User")
			(hide yes)
			(effects
				(font
					(size 0.7874 0.5842)
					(thickness 0.1524)
				)
				(justify mirror)
			)
		)
		(property "User Part Number" "PARTNUM*"
			(at -0.02032 4.024884 0)
			(unlocked yes)
			(layer "Cmts.User")
			(hide yes)
			(effects
				(font
					(size 0.7874 0.5842)
					(thickness 0.1524)
				)
				(justify mirror)
			)
		)
		(property "Device Type" "RESISTOR-G155-11001-01,1KOHM,1%"
			(at -0.008382 1.210564 0)
			(unlocked yes)
			(layer "B.Fab")
			(hide yes)
			(effects
				(font
					(size 0.7874 0.5842)
					(thickness 0.1524)
				)
				(justify mirror)
			)
		)
		(duplicate_pad_numbers_are_jumpers no)
		(fp_line
			(start -1.143 -0.5588)
			(end 1.143 -0.5588)
			(stroke
				(width 0.1)
				(type default)
			)
			(layer "B.SilkS")
		)
		(fp_line
			(start -1.143 0.5588)
			(end -1.143 -0.5588)
			(stroke
				(width 0.1)
				(type default)
			)
			(layer "B.SilkS")
		)
		(fp_line
			(start 1.143 -0.5588)
			(end 1.143 0.5588)
			(stroke
				(width 0.1)
				(type default)
			)
			(layer "B.SilkS")
		)
		(fp_line
			(start 1.143 0.5588)
			(end -1.143 0.5588)
			(stroke
				(width 0.1)
				(type default)
			)
			(layer "B.SilkS")
		)
		(fp_rect
			(start -1.143 0.5588)
			(end 1.143 -0.5588)
			(stroke
				(width 0)
				(type default)
			)
			(fill no)
			(layer "B.CrtYd")
		)
		(fp_line
			(start -0.508 -0.3048)
			(end 0.508 -0.3048)
			(stroke
				(width 0.1)
				(type default)
			)
			(layer "B.Fab")
		)
		(fp_line
			(start -0.508 0.3048)
			(end -0.508 -0.3048)
			(stroke
				(width 0.1)
				(type default)
			)
			(layer "B.Fab")
		)
		(fp_line
			(start 0.508 -0.3048)
			(end 0.508 0.3048)
			(stroke
				(width 0.1)
				(type default)
			)
			(layer "B.Fab")
		)
		(fp_line
			(start 0.508 0.3048)
			(end -0.508 0.3048)
			(stroke
				(width 0.1)
				(type default)
			)
			(layer "B.Fab")
		)
		(pad "1" smd rect
			(at 0.5334 0 180)
			(size 0.7112 0.6096)
			(layers "B.Cu" "B.Mask" "B.Paste")
			(net "XP3R3V")
		)
		(pad "2" smd rect
			(at -0.5334 0 180)
			(size 0.7112 0.6096)
			(layers "B.Cu" "B.Mask" "B.Paste")
			(net "XP3R3V_FPGA_EN_R")
		)
		(zone
			(layer "B.Cu")
			(hatch none 0.5)
			(connect_pads
				(clearance 0)
			)
			(min_thickness 0.25)
			(keepout
				(tracks allowed)
				(vias not_allowed)
				(pads allowed)
				(copperpour not_allowed)
				(footprints allowed)
			)
			(placement
				(enabled no)
				(sheetname "")
			)
			(fill
				(thermal_gap 0.5)
				(thermal_bridge_width 0.5)
				(island_removal_mode 0)
			)
			(polygon
				(pts
					(xy 115.3668 -70.6882) (xy 115.5192 -70.6882) (xy 115.5192 -71.2978) (xy 115.3668 -71.2978)
				)
			)
		)
	)
	(footprint ""
		(layer "B.Cu")
		(at 142.24 -59.563 -90)
		(property "Reference" "R249"
			(at -3.175 0.16637 270)
			(unlocked yes)
			(layer "B.SilkS")
			(effects
				(font
					(size 0.7874 0.5842)
					(thickness 0.1524)
				)
				(justify mirror)
			)
		)
		(property "Value" "VAL*"
			(at -0.02032 2.13233 270)
			(unlocked yes)
			(layer "B.Fab")
			(hide yes)
			(effects
				(font
					(size 0.7874 0.5842)
					(thickness 0.1524)
				)
				(justify mirror)
			)
		)
		(property "Device Type" "RESISTOR-G155-14701-01,4.7KOHMA"
			(at -0.008382 1.210564 270)
			(unlocked yes)
			(layer "B.Fab")
			(hide yes)
			(effects
				(font
					(size 0.7874 0.5842)
					(thickness 0.1524)
				)
				(justify mirror)
			)
		)
		(property "User Part Number" "PARTNUM*"
			(at -0.02032 4.024884 270)
			(unlocked yes)
			(layer "Cmts.User")
			(hide yes)
			(effects
				(font
					(size 0.7874 0.5842)
					(thickness 0.1524)
				)
				(justify mirror)
			)
		)
		(property "Tolerance" "TOL*"
			(at -0.044704 3.05435 270)
			(unlocked yes)
			(layer "Cmts.User")
			(hide yes)
			(effects
				(font
					(size 0.7874 0.5842)
					(thickness 0.1524)
				)
				(justify mirror)
			)
		)
		(duplicate_pad_numbers_are_jumpers no)
		(fp_line
			(start -1.143 0.5588)
			(end -1.143 -0.5588)
			(stroke
				(width 0.1)
				(type default)
			)
			(layer "B.SilkS")
		)
		(fp_line
			(start 1.143 0.5588)
			(end -1.143 0.5588)
			(stroke
				(width 0.1)
				(type default)
			)
			(layer "B.SilkS")
		)
		(fp_line
			(start -1.143 -0.5588)
			(end 1.143 -0.5588)
			(stroke
				(width 0.1)
				(type default)
			)
			(layer "B.SilkS")
		)
		(fp_line
			(start 1.143 -0.5588)
			(end 1.143 0.5588)
			(stroke
				(width 0.1)
				(type default)
			)
			(layer "B.SilkS")
		)
		(fp_rect
			(start 1.143 0.5588)
			(end -1.143 -0.5588)
			(stroke
				(width 0)
				(type default)
			)
			(fill no)
			(layer "B.CrtYd")
		)
		(fp_line
			(start -0.508 0.3048)
			(end -0.508 -0.3048)
			(stroke
				(width 0.1)
				(type default)
			)
			(layer "B.Fab")
		)
		(fp_line
			(start 0.508 0.3048)
			(end -0.508 0.3048)
			(stroke
				(width 0.1)
				(type default)
			)
			(layer "B.Fab")
		)
		(fp_line
			(start -0.508 -0.3048)
			(end 0.508 -0.3048)
			(stroke
				(width 0.1)
				(type default)
			)
			(layer "B.Fab")
		)
		(fp_line
			(start 0.508 -0.3048)
			(end 0.508 0.3048)
			(stroke
				(width 0.1)
				(type default)
			)
			(layer "B.Fab")
		)
		(pad "1" smd rect
			(at 0.5334 0 90)
			(size 0.7112 0.6096)
			(layers "B.Cu" "B.Mask" "B.Paste")
			(net "XP1R0V_COMP")
		)
		(pad "2" smd rect
			(at -0.5334 0 90)
			(size 0.7112 0.6096)
			(layers "B.Cu" "B.Mask" "B.Paste")
			(net "UNNAMED_523_CAPACITOR_I9_1")
		)
		(zone
			(layer "B.Cu")
			(hatch none 0.5)
			(connect_pads
				(clearance 0)
			)
			(min_thickness 0.25)
			(keepout
				(tracks allowed)
				(vias not_allowed)
				(pads allowed)
				(copperpour not_allowed)
				(footprints allowed)
			)
			(placement
				(enabled no)
				(sheetname "")
			)
			(fill
				(thermal_gap 0.5)
				(thermal_bridge_width 0.5)
				(island_removal_mode 0)
			)
			(polygon
				(pts
					(xy 141.9352 -59.4868) (xy 142.5448 -59.4868) (xy 142.5448 -59.6392) (xy 141.9352 -59.6392)
				)
			)
		)
	)
	(footprint ""
		(layer "B.Cu")
		(at 16.764 -77.089 90)
		(property "Reference" "R332"
			(at -1.143 3.13563 270)
			(unlocked yes)
			(layer "B.SilkS")
			(effects
				(font
					(size 0.7874 0.5842)
					(thickness 0.1524)
				)
				(justify mirror)
			)
		)
		(property "Value" "VAL*"
			(at -0.02032 2.13233 90)
			(unlocked yes)
			(layer "B.Fab")
			(hide yes)
			(effects
				(font
					(size 0.7874 0.5842)
					(thickness 0.1524)
				)
				(justify mirror)
			)
		)
		(property "Tolerance" "TOL*"
			(at -0.044704 3.05435 90)
			(unlocked yes)
			(layer "Cmts.User")
			(hide yes)
			(effects
				(font
					(size 0.7874 0.5842)
					(thickness 0.1524)
				)
				(justify mirror)
			)
		)
		(property "User Part Number" "PARTNUM*"
			(at -0.02032 4.024884 90)
			(unlocked yes)
			(layer "Cmts.User")
			(hide yes)
			(effects
				(font
					(size 0.7874 0.5842)
					(thickness 0.1524)
				)
				(justify mirror)
			)
		)
		(property "Device Type" "RESISTOR-G155-133R0-01,33OHM,1%"
			(at -0.008382 1.210564 90)
			(unlocked yes)
			(layer "B.Fab")
			(hide yes)
			(effects
				(font
					(size 0.7874 0.5842)
					(thickness 0.1524)
				)
				(justify mirror)
			)
		)
		(duplicate_pad_numbers_are_jumpers no)
		(fp_line
			(start 1.143 -0.5588)
			(end 1.143 0.5588)
			(stroke
				(width 0.1)
				(type default)
			)
			(layer "B.SilkS")
		)
		(fp_line
			(start -1.143 -0.5588)
			(end 1.143 -0.5588)
			(stroke
				(width 0.1)
				(type default)
			)
			(layer "B.SilkS")
		)
		(fp_line
			(start 1.143 0.5588)
			(end -1.143 0.5588)
			(stroke
				(width 0.1)
				(type default)
			)
			(layer "B.SilkS")
		)
		(fp_line
			(start -1.143 0.5588)
			(end -1.143 -0.5588)
			(stroke
				(width 0.1)
				(type default)
			)
			(layer "B.SilkS")
		)
		(fp_rect
			(start 1.143 -0.5588)
			(end -1.143 0.5588)
			(stroke
				(width 0)
				(type default)
			)
			(fill no)
			(layer "B.CrtYd")
		)
		(fp_line
			(start 0.508 -0.3048)
			(end 0.508 0.3048)
			(stroke
				(width 0.1)
				(type default)
			)
			(layer "B.Fab")
		)
		(fp_line
			(start -0.508 -0.3048)
			(end 0.508 -0.3048)
			(stroke
				(width 0.1)
				(type default)
			)
			(layer "B.Fab")
		)
		(fp_line
			(start 0.508 0.3048)
			(end -0.508 0.3048)
			(stroke
				(width 0.1)
				(type default)
			)
			(layer "B.Fab")
		)
		(fp_line
			(start -0.508 0.3048)
			(end -0.508 -0.3048)
			(stroke
				(width 0.1)
				(type default)
			)
			(layer "B.Fab")
		)
		(pad "1" smd rect
			(at 0.5334 0 270)
			(size 0.7112 0.6096)
			(layers "B.Cu" "B.Mask" "B.Paste")
			(net "LM75B_I2C_SDA")
		)
		(pad "2" smd rect
			(at -0.5334 0 270)
			(size 0.7112 0.6096)
			(layers "B.Cu" "B.Mask" "B.Paste")
			(net "R_LM75B_1_I2C_SDA")
		)
		(zone
			(layer "B.Cu")
			(hatch none 0.5)
			(connect_pads
				(clearance 0)
			)
			(min_thickness 0.25)
			(keepout
				(tracks allowed)
				(vias not_allowed)
				(pads allowed)
				(copperpour not_allowed)
				(footprints allowed)
			)
			(placement
				(enabled no)
				(sheetname "")
			)
			(fill
				(thermal_gap 0.5)
				(thermal_bridge_width 0.5)
				(island_removal_mode 0)
			)
			(polygon
				(pts
					(xy 16.4592 -77.1652) (xy 16.4592 -77.0128) (xy 17.0688 -77.0128) (xy 17.0688 -77.1652)
				)
			)
		)
	)
	(footprint ""
		(layer "B.Cu")
		(at 112.84712 -40.323262 -90)
		(property "Reference" "C161"
			(at 1.397762 42.01795 270)
			(unlocked yes)
			(layer "B.SilkS")
			(effects
				(font
					(size 0.635 0.4064)
					(thickness 0.1524)
				)
				(justify mirror)
			)
		)
		(property "Value" "VAL*"
			(at 0 3.718306 270)
			(unlocked yes)
			(layer "B.Fab")
			(hide yes)
			(effects
				(font
					(size 0.7874 0.5842)
					(thickness 0.127)
				)
				(justify mirror)
			)
		)
		(property "Device Type" "CAPACITOR-G105-0B104-CK,0.1UF,A"
			(at 0 1.432306 270)
			(unlocked yes)
			(layer "B.Fab")
			(hide yes)
			(effects
				(font
					(size 0.7874 0.5842)
					(thickness 0.127)
				)
				(justify mirror)
			)
		)
		(property "User Part Number" "PARTNUM*"
			(at 0 2.575306 270)
			(unlocked yes)
			(layer "Cmts.User")
			(hide yes)
			(effects
				(font
					(size 0.7874 0.5842)
					(thickness 0.127)
				)
				(justify mirror)
			)
		)
		(property "Tolerance" "TOL*"
			(at 0 4.861306 270)
			(unlocked yes)
			(layer "Cmts.User")
			(hide yes)
			(effects
				(font
					(size 0.7874 0.5842)
					(thickness 0.127)
				)
				(justify mirror)
			)
		)
		(duplicate_pad_numbers_are_jumpers no)
		(fp_line
			(start -0.970026 0.4699)
			(end 0.970026 0.4699)
			(stroke
				(width 0.1)
				(type default)
			)
			(layer "B.SilkS")
		)
		(fp_line
			(start 0.970026 0.4699)
			(end 0.970026 -0.4699)
			(stroke
				(width 0.1)
				(type default)
			)
			(layer "B.SilkS")
		)
		(fp_line
			(start -0.970026 -0.4699)
			(end -0.970026 0.4699)
			(stroke
				(width 0.1)
				(type default)
			)
			(layer "B.SilkS")
		)
		(fp_line
			(start 0.970026 -0.4699)
			(end -0.970026 -0.4699)
			(stroke
				(width 0.1)
				(type default)
			)
			(layer "B.SilkS")
		)
		(fp_poly
			(pts
				(xy 0.970026 0.4699) (xy -0.970026 0.4699) (xy -0.970026 -0.4699) (xy 0.970026 -0.4699)
			)
			(stroke
				(width 0)
				(type default)
			)
			(fill no)
			(layer "B.CrtYd")
		)
		(fp_line
			(start -0.508 0.3048)
			(end 0.508 0.3048)
			(stroke
				(width 0.1)
				(type default)
			)
			(layer "B.Fab")
		)
		(fp_line
			(start 0.508 0.3048)
			(end 0.508 -0.3048)
			(stroke
				(width 0.1)
				(type default)
			)
			(layer "B.Fab")
		)
		(fp_line
			(start -0.508 -0.3048)
			(end -0.508 0.3048)
			(stroke
				(width 0.1)
				(type default)
			)
			(layer "B.Fab")
		)
		(fp_line
			(start 0.508 -0.3048)
			(end -0.508 -0.3048)
			(stroke
				(width 0.1)
				(type default)
			)
			(layer "B.Fab")
		)
		(pad "1" smd circle
			(at 0.500126 0 90)
			(size 0.635 0.635)
			(layers "B.Cu" "B.Mask" "B.Paste")
			(net "XP1R0V_FPGA_VCCINT")
		)
		(pad "2" smd circle
			(at -0.500126 0 90)
			(size 0.635 0.635)
			(layers "B.Cu" "B.Mask" "B.Paste")
			(net "SG")
		)
	)
	(footprint ""
		(layer "B.Cu")
		(at 96.5454 -64.2874 90)
		(property "Reference" "R286"
			(at 3.4036 0.31623 270)
			(unlocked yes)
			(layer "B.SilkS")
			(effects
				(font
					(size 0.7874 0.5842)
					(thickness 0.1524)
				)
				(justify mirror)
			)
		)
		(property "Value" "VAL*"
			(at -0.02032 2.13233 90)
			(unlocked yes)
			(layer "B.Fab")
			(hide yes)
			(effects
				(font
					(size 0.7874 0.5842)
					(thickness 0.1524)
				)
				(justify mirror)
			)
		)
		(property "Tolerance" "TOL*"
			(at -0.044704 3.05435 90)
			(unlocked yes)
			(layer "Cmts.User")
			(hide yes)
			(effects
				(font
					(size 0.7874 0.5842)
					(thickness 0.1524)
				)
				(justify mirror)
			)
		)
		(property "User Part Number" "PARTNUM*"
			(at -0.02032 4.024884 90)
			(unlocked yes)
			(layer "Cmts.User")
			(hide yes)
			(effects
				(font
					(size 0.7874 0.5842)
					(thickness 0.1524)
				)
				(justify mirror)
			)
		)
		(property "Device Type" "RESISTOR-G155-14701-01,4.7KOHMA"
			(at -0.008382 1.210564 90)
			(unlocked yes)
			(layer "B.Fab")
			(hide yes)
			(effects
				(font
					(size 0.7874 0.5842)
					(thickness 0.1524)
				)
				(justify mirror)
			)
		)
		(duplicate_pad_numbers_are_jumpers no)
		(fp_line
			(start 1.143 -0.5588)
			(end 1.143 0.5588)
			(stroke
				(width 0.1)
				(type default)
			)
			(layer "B.SilkS")
		)
		(fp_line
			(start -1.143 -0.5588)
			(end 1.143 -0.5588)
			(stroke
				(width 0.1)
				(type default)
			)
			(layer "B.SilkS")
		)
		(fp_line
			(start 1.143 0.5588)
			(end -1.143 0.5588)
			(stroke
				(width 0.1)
				(type default)
			)
			(layer "B.SilkS")
		)
		(fp_line
			(start -1.143 0.5588)
			(end -1.143 -0.5588)
			(stroke
				(width 0.1)
				(type default)
			)
			(layer "B.SilkS")
		)
		(fp_poly
			(pts
				(xy 1.143 0.5588) (xy -1.143 0.5588) (xy -1.143 -0.5588) (xy 1.143 -0.5588)
			)
			(stroke
				(width 0)
				(type default)
			)
			(fill no)
			(layer "B.CrtYd")
		)
		(fp_line
			(start 0.508 -0.3048)
			(end 0.508 0.3048)
			(stroke
				(width 0.1)
				(type default)
			)
			(layer "B.Fab")
		)
		(fp_line
			(start -0.508 -0.3048)
			(end 0.508 -0.3048)
			(stroke
				(width 0.1)
				(type default)
			)
			(layer "B.Fab")
		)
		(fp_line
			(start 0.508 0.3048)
			(end -0.508 0.3048)
			(stroke
				(width 0.1)
				(type default)
			)
			(layer "B.Fab")
		)
		(fp_line
			(start -0.508 0.3048)
			(end -0.508 -0.3048)
			(stroke
				(width 0.1)
				(type default)
			)
			(layer "B.Fab")
		)
		(pad "1" smd rect
			(at 0.5334 0 270)
			(size 0.7112 0.6096)
			(layers "B.Cu" "B.Mask" "B.Paste")
			(net "SG")
		)
		(pad "2" smd rect
			(at -0.5334 0 270)
			(size 0.7112 0.6096)
			(layers "B.Cu" "B.Mask" "B.Paste")
			(net "FPGA_IO_3")
		)
		(zone
			(layer "B.Cu")
			(hatch none 0.5)
			(connect_pads
				(clearance 0)
			)
			(min_thickness 0.25)
			(keepout
				(tracks allowed)
				(vias not_allowed)
				(pads allowed)
				(copperpour not_allowed)
				(footprints allowed)
			)
			(placement
				(enabled no)
				(sheetname "")
			)
			(fill
				(thermal_gap 0.5)
				(thermal_bridge_width 0.5)
				(island_removal_mode 0)
			)
			(polygon
				(pts
					(xy 96.8502 -64.3636) (xy 96.2406 -64.3636) (xy 96.2406 -64.2112) (xy 96.8502 -64.2112)
				)
			)
		)
		(zone
			(layer "B.Cu")
			(hatch none 0.5)
			(connect_pads
				(clearance 0)
			)
			(min_thickness 0.25)
			(keepout
				(tracks not_allowed)
				(vias allowed)
				(pads allowed)
				(copperpour not_allowed)
				(footprints allowed)
			)
			(placement
				(enabled no)
				(sheetname "")
			)
			(fill
				(thermal_gap 0.5)
				(thermal_bridge_width 0.5)
				(island_removal_mode 0)
			)
			(polygon
				(pts
					(xy 96.8502 -64.3636) (xy 96.2406 -64.3636) (xy 96.2406 -64.2112) (xy 96.8502 -64.2112)
				)
			)
		)
	)
	(footprint ""
		(layer "B.Cu")
		(at 7.366 -72.39 90)
		(property "Reference" "R334"
			(at -0.381 2.75463 270)
			(unlocked yes)
			(layer "B.SilkS")
			(effects
				(font
					(size 0.7874 0.5842)
					(thickness 0.1524)
				)
				(justify mirror)
			)
		)
		(property "Value" "VAL*"
			(at -0.02032 2.13233 90)
			(unlocked yes)
			(layer "B.Fab")
			(hide yes)
			(effects
				(font
					(size 0.7874 0.5842)
					(thickness 0.1524)
				)
				(justify mirror)
			)
		)
		(property "Tolerance" "TOL*"
			(at -0.044704 3.05435 90)
			(unlocked yes)
			(layer "Cmts.User")
			(hide yes)
			(effects
				(font
					(size 0.7874 0.5842)
					(thickness 0.1524)
				)
				(justify mirror)
			)
		)
		(property "User Part Number" "PARTNUM*"
			(at -0.02032 4.024884 90)
			(unlocked yes)
			(layer "Cmts.User")
			(hide yes)
			(effects
				(font
					(size 0.7874 0.5842)
					(thickness 0.1524)
				)
				(justify mirror)
			)
		)
		(property "Device Type" "RESISTOR-G155-11001-01,1KOHM,1%"
			(at -0.008382 1.210564 90)
			(unlocked yes)
			(layer "B.Fab")
			(hide yes)
			(effects
				(font
					(size 0.7874 0.5842)
					(thickness 0.1524)
				)
				(justify mirror)
			)
		)
		(duplicate_pad_numbers_are_jumpers no)
		(fp_line
			(start 1.143 -0.5588)
			(end 1.143 0.5588)
			(stroke
				(width 0.1)
				(type default)
			)
			(layer "B.SilkS")
		)
		(fp_line
			(start -1.143 -0.5588)
			(end 1.143 -0.5588)
			(stroke
				(width 0.1)
				(type default)
			)
			(layer "B.SilkS")
		)
		(fp_line
			(start 1.143 0.5588)
			(end -1.143 0.5588)
			(stroke
				(width 0.1)
				(type default)
			)
			(layer "B.SilkS")
		)
		(fp_line
			(start -1.143 0.5588)
			(end -1.143 -0.5588)
			(stroke
				(width 0.1)
				(type default)
			)
			(layer "B.SilkS")
		)
		(fp_rect
			(start 1.143 0.5588)
			(end -1.143 -0.5588)
			(stroke
				(width 0)
				(type default)
			)
			(fill no)
			(layer "B.CrtYd")
		)
		(fp_line
			(start 0.508 -0.3048)
			(end 0.508 0.3048)
			(stroke
				(width 0.1)
				(type default)
			)
			(layer "B.Fab")
		)
		(fp_line
			(start -0.508 -0.3048)
			(end 0.508 -0.3048)
			(stroke
				(width 0.1)
				(type default)
			)
			(layer "B.Fab")
		)
		(fp_line
			(start 0.508 0.3048)
			(end -0.508 0.3048)
			(stroke
				(width 0.1)
				(type default)
			)
			(layer "B.Fab")
		)
		(fp_line
			(start -0.508 0.3048)
			(end -0.508 -0.3048)
			(stroke
				(width 0.1)
				(type default)
			)
			(layer "B.Fab")
		)
		(pad "1" smd rect
			(at 0.5334 0 270)
			(size 0.7112 0.6096)
			(layers "B.Cu" "B.Mask" "B.Paste")
			(net "UNNAMED_6_LM75BDPTSSOP8_I34_A2")
		)
		(pad "2" smd rect
			(at -0.5334 0 270)
			(size 0.7112 0.6096)
			(layers "B.Cu" "B.Mask" "B.Paste")
			(net "SG")
		)
		(zone
			(layer "B.Cu")
			(hatch none 0.5)
			(connect_pads
				(clearance 0)
			)
			(min_thickness 0.25)
			(keepout
				(tracks allowed)
				(vias not_allowed)
				(pads allowed)
				(copperpour not_allowed)
				(footprints allowed)
			)
			(placement
				(enabled no)
				(sheetname "")
			)
			(fill
				(thermal_gap 0.5)
				(thermal_bridge_width 0.5)
				(island_removal_mode 0)
			)
			(polygon
				(pts
					(xy 7.6708 -72.4662) (xy 7.0612 -72.4662) (xy 7.0612 -72.3138) (xy 7.6708 -72.3138)
				)
			)
		)
	)
	(footprint ""
		(layer "B.Cu")
		(at 127.889 -98.425 90)
		(property "Reference" "C78"
			(at -2.794 -0.42037 270)
			(unlocked yes)
			(layer "B.SilkS")
			(effects
				(font
					(size 0.7874 0.5842)
					(thickness 0.1524)
				)
				(justify mirror)
			)
		)
		(property "Value" "VAL*"
			(at -0.0762 2.067306 90)
			(unlocked yes)
			(layer "B.Fab")
			(hide yes)
			(effects
				(font
					(size 0.7874 0.5842)
					(thickness 0.1524)
				)
				(justify mirror)
			)
		)
		(property "Device Type" "CAPACITOR-G105-0B104-EK,0.1UF,A"
			(at -0.0508 1.127506 90)
			(unlocked yes)
			(layer "B.Fab")
			(hide yes)
			(effects
				(font
					(size 0.7874 0.5842)
					(thickness 0.1524)
				)
				(justify mirror)
			)
		)
		(property "User Part Number" "PARTNUM*"
			(at -0.1016 4.023106 90)
			(unlocked yes)
			(layer "Cmts.User")
			(hide yes)
			(effects
				(font
					(size 0.7874 0.5842)
					(thickness 0.1524)
				)
				(justify mirror)
			)
		)
		(property "Tolerance" "TOL*"
			(at -0.0762 3.032506 90)
			(unlocked yes)
			(layer "Cmts.User")
			(hide yes)
			(effects
				(font
					(size 0.7874 0.5842)
					(thickness 0.1524)
				)
				(justify mirror)
			)
		)
		(duplicate_pad_numbers_are_jumpers no)
		(fp_line
			(start 1.143 -0.5588)
			(end 1.143 0.5588)
			(stroke
				(width 0.1)
				(type default)
			)
			(layer "B.SilkS")
		)
		(fp_line
			(start -1.143 -0.5588)
			(end 1.143 -0.5588)
			(stroke
				(width 0.1)
				(type default)
			)
			(layer "B.SilkS")
		)
		(fp_line
			(start 1.143 0.5588)
			(end -1.143 0.5588)
			(stroke
				(width 0.1)
				(type default)
			)
			(layer "B.SilkS")
		)
		(fp_line
			(start -1.143 0.5588)
			(end -1.143 -0.5588)
			(stroke
				(width 0.1)
				(type default)
			)
			(layer "B.SilkS")
		)
		(fp_rect
			(start -1.143 -0.5588)
			(end 1.143 0.5588)
			(stroke
				(width 0)
				(type default)
			)
			(fill no)
			(layer "B.CrtYd")
		)
		(fp_line
			(start 0.508 -0.3048)
			(end 0.508 0.3048)
			(stroke
				(width 0.1)
				(type default)
			)
			(layer "B.Fab")
		)
		(fp_line
			(start -0.508 -0.3048)
			(end 0.508 -0.3048)
			(stroke
				(width 0.1)
				(type default)
			)
			(layer "B.Fab")
		)
		(fp_line
			(start 0.508 0.3048)
			(end -0.508 0.3048)
			(stroke
				(width 0.1)
				(type default)
			)
			(layer "B.Fab")
		)
		(fp_line
			(start -0.508 0.3048)
			(end -0.508 -0.3048)
			(stroke
				(width 0.1)
				(type default)
			)
			(layer "B.Fab")
		)
		(pad "1" smd rect
			(at 0.5334 0 270)
			(size 0.7112 0.6096)
			(layers "B.Cu" "B.Mask" "B.Paste")
			(net "XP5R0V_VCC_ANT")
		)
		(pad "2" smd rect
			(at -0.5334 0 270)
			(size 0.7112 0.6096)
			(layers "B.Cu" "B.Mask" "B.Paste")
			(net "SG")
		)
		(zone
			(layer "B.Cu")
			(hatch none 0.5)
			(connect_pads
				(clearance 0)
			)
			(min_thickness 0.25)
			(keepout
				(tracks allowed)
				(vias not_allowed)
				(pads allowed)
				(copperpour not_allowed)
				(footprints allowed)
			)
			(placement
				(enabled no)
				(sheetname "")
			)
			(fill
				(thermal_gap 0.5)
				(thermal_bridge_width 0.5)
				(island_removal_mode 0)
			)
			(polygon
				(pts
					(xy 127.5842 -98.3488) (xy 128.1938 -98.3488) (xy 128.1938 -98.5012) (xy 127.5842 -98.5012)
				)
			)
		)
	)
	(footprint ""
		(layer "B.Cu")
		(at 118.847108 -54.323234 -90)
		(property "Reference" "C154"
			(at -3.461766 0.014478 270)
			(unlocked yes)
			(layer "B.SilkS")
			(effects
				(font
					(size 0.7874 0.5842)
					(thickness 0.1524)
				)
				(justify mirror)
			)
		)
		(property "Value" "VAL*"
			(at 0 3.718306 270)
			(unlocked yes)
			(layer "B.Fab")
			(hide yes)
			(effects
				(font
					(size 0.7874 0.5842)
					(thickness 0.127)
				)
				(justify mirror)
			)
		)
		(property "Device Type" "CAPACITOR-G105-0F475-BM,4.7UF,A"
			(at 0 1.432306 270)
			(unlocked yes)
			(layer "B.Fab")
			(hide yes)
			(effects
				(font
					(size 0.7874 0.5842)
					(thickness 0.127)
				)
				(justify mirror)
			)
		)
		(property "User Part Number" "PARTNUM*"
			(at 0 2.575306 270)
			(unlocked yes)
			(layer "Cmts.User")
			(hide yes)
			(effects
				(font
					(size 0.7874 0.5842)
					(thickness 0.127)
				)
				(justify mirror)
			)
		)
		(property "Tolerance" "TOL*"
			(at 0 4.861306 270)
			(unlocked yes)
			(layer "Cmts.User")
			(hide yes)
			(effects
				(font
					(size 0.7874 0.5842)
					(thickness 0.127)
				)
				(justify mirror)
			)
		)
		(duplicate_pad_numbers_are_jumpers no)
		(fp_line
			(start -0.970026 0.4699)
			(end 0.970026 0.4699)
			(stroke
				(width 0.1)
				(type default)
			)
			(layer "B.SilkS")
		)
		(fp_line
			(start 0.970026 0.4699)
			(end 0.970026 -0.4699)
			(stroke
				(width 0.1)
				(type default)
			)
			(layer "B.SilkS")
		)
		(fp_line
			(start -0.970026 -0.4699)
			(end -0.970026 0.4699)
			(stroke
				(width 0.1)
				(type default)
			)
			(layer "B.SilkS")
		)
		(fp_line
			(start 0.970026 -0.4699)
			(end -0.970026 -0.4699)
			(stroke
				(width 0.1)
				(type default)
			)
			(layer "B.SilkS")
		)
		(fp_poly
			(pts
				(xy 0.970026 0.4699) (xy -0.970026 0.4699) (xy -0.970026 -0.4699) (xy 0.970026 -0.4699)
			)
			(stroke
				(width 0)
				(type default)
			)
			(fill no)
			(layer "B.CrtYd")
		)
		(fp_line
			(start -0.508 0.3048)
			(end 0.508 0.3048)
			(stroke
				(width 0.1)
				(type default)
			)
			(layer "B.Fab")
		)
		(fp_line
			(start 0.508 0.3048)
			(end 0.508 -0.3048)
			(stroke
				(width 0.1)
				(type default)
			)
			(layer "B.Fab")
		)
		(fp_line
			(start -0.508 -0.3048)
			(end -0.508 0.3048)
			(stroke
				(width 0.1)
				(type default)
			)
			(layer "B.Fab")
		)
		(fp_line
			(start 0.508 -0.3048)
			(end -0.508 -0.3048)
			(stroke
				(width 0.1)
				(type default)
			)
			(layer "B.Fab")
		)
		(pad "1" smd circle
			(at 0.500126 0 90)
			(size 0.635 0.635)
			(layers "B.Cu" "B.Mask" "B.Paste")
			(net "XP3R3V_FPGA")
		)
		(pad "2" smd circle
			(at -0.500126 0 90)
			(size 0.635 0.635)
			(layers "B.Cu" "B.Mask" "B.Paste")
			(net "SG")
		)
	)
	(footprint ""
		(layer "B.Cu")
		(at 144.78 -59.563 90)
		(property "Reference" "R252"
			(at 0.889 3.13563 270)
			(unlocked yes)
			(layer "B.SilkS")
			(effects
				(font
					(size 0.7874 0.5842)
					(thickness 0.1524)
				)
				(justify mirror)
			)
		)
		(property "Value" "VAL*"
			(at 0.0254 2.524506 90)
			(unlocked yes)
			(layer "B.Fab")
			(hide yes)
			(effects
				(font
					(size 0.7874 0.5842)
					(thickness 0.1524)
				)
				(justify mirror)
			)
		)
		(property "Device Type" "RESISTOR-G156-100R0-J0,0OHM,-"
			(at 0 1.610106 90)
			(unlocked yes)
			(layer "B.Fab")
			(hide yes)
			(effects
				(font
					(size 0.7874 0.5842)
					(thickness 0.1524)
				)
				(justify mirror)
			)
		)
		(property "User Part Number" "PARTNUM*"
			(at 0.0254 4.505706 90)
			(unlocked yes)
			(layer "Cmts.User")
			(hide yes)
			(effects
				(font
					(size 0.7874 0.5842)
					(thickness 0.1524)
				)
				(justify mirror)
			)
		)
		(property "Tolerance" "TOL*"
			(at 0.0254 3.464306 90)
			(unlocked yes)
			(layer "Cmts.User")
			(hide yes)
			(effects
				(font
					(size 0.7874 0.5842)
					(thickness 0.1524)
				)
				(justify mirror)
			)
		)
		(duplicate_pad_numbers_are_jumpers no)
		(fp_line
			(start 1.3208 -0.7112)
			(end -1.3208 -0.7112)
			(stroke
				(width 0.1)
				(type default)
			)
			(layer "B.SilkS")
		)
		(fp_line
			(start -1.3208 -0.7112)
			(end -1.3208 0.7112)
			(stroke
				(width 0.1)
				(type default)
			)
			(layer "B.SilkS")
		)
		(fp_line
			(start 1.3208 0.7112)
			(end 1.3208 -0.7112)
			(stroke
				(width 0.1)
				(type default)
			)
			(layer "B.SilkS")
		)
		(fp_line
			(start -1.3208 0.7112)
			(end 1.3208 0.7112)
			(stroke
				(width 0.1)
				(type default)
			)
			(layer "B.SilkS")
		)
		(fp_rect
			(start -1.3208 -0.7112)
			(end 1.3208 0.7112)
			(stroke
				(width 0)
				(type default)
			)
			(fill no)
			(layer "B.CrtYd")
		)
		(fp_line
			(start 0.8128 -0.4572)
			(end -0.8128 -0.4572)
			(stroke
				(width 0.1)
				(type default)
			)
			(layer "B.Fab")
		)
		(fp_line
			(start -0.8128 -0.4572)
			(end -0.8128 0.4572)
			(stroke
				(width 0.1)
				(type default)
			)
			(layer "B.Fab")
		)
		(fp_line
			(start 0.8128 0.4572)
			(end 0.8128 -0.4572)
			(stroke
				(width 0.1)
				(type default)
			)
			(layer "B.Fab")
		)
		(fp_line
			(start -0.8128 0.4572)
			(end 0.8128 0.4572)
			(stroke
				(width 0.1)
				(type default)
			)
			(layer "B.Fab")
		)
		(pad "1" smd rect
			(at 0.6858 0 270)
			(size 0.762 0.8636)
			(layers "B.Cu" "B.Mask" "B.Paste")
			(net "XP1R0V_AGND")
		)
		(pad "2" smd rect
			(at -0.6858 0 270)
			(size 0.762 0.8636)
			(layers "B.Cu" "B.Mask" "B.Paste")
			(net "XP1R0V_FB_R_TO_AGND")
		)
		(zone
			(layer "B.Cu")
			(hatch none 0.5)
			(connect_pads
				(clearance 0)
			)
			(min_thickness 0.25)
			(keepout
				(tracks allowed)
				(vias not_allowed)
				(pads allowed)
				(copperpour not_allowed)
				(footprints allowed)
			)
			(placement
				(enabled no)
				(sheetname "")
			)
			(fill
				(thermal_gap 0.5)
				(thermal_bridge_width 0.5)
				(island_removal_mode 0)
			)
			(polygon
				(pts
					(xy 144.3228 -59.4106) (xy 145.2372 -59.4106) (xy 145.2372 -59.7154) (xy 144.3228 -59.7154)
				)
			)
		)
	)
	(footprint ""
		(layer "B.Cu")
		(at 22.606 -88.9 180)
		(property "Reference" "R469"
			(at -1.016 -3.59537 0)
			(unlocked yes)
			(layer "B.SilkS")
			(effects
				(font
					(size 0.7874 0.5842)
					(thickness 0.1524)
				)
				(justify mirror)
			)
		)
		(property "Value" "VAL*"
			(at -0.02032 2.13233 180)
			(unlocked yes)
			(layer "B.Fab")
			(hide yes)
			(effects
				(font
					(size 0.7874 0.5842)
					(thickness 0.1524)
				)
				(justify mirror)
			)
		)
		(property "Tolerance" "TOL*"
			(at -0.044704 3.05435 180)
			(unlocked yes)
			(layer "Cmts.User")
			(hide yes)
			(effects
				(font
					(size 0.7874 0.5842)
					(thickness 0.1524)
				)
				(justify mirror)
			)
		)
		(property "User Part Number" "PARTNUM*"
			(at -0.02032 4.024884 180)
			(unlocked yes)
			(layer "Cmts.User")
			(hide yes)
			(effects
				(font
					(size 0.7874 0.5842)
					(thickness 0.1524)
				)
				(justify mirror)
			)
		)
		(property "Device Type" "RESISTOR-G155-133R0-01,33OHM,1%"
			(at -0.008382 1.210564 180)
			(unlocked yes)
			(layer "B.Fab")
			(hide yes)
			(effects
				(font
					(size 0.7874 0.5842)
					(thickness 0.1524)
				)
				(justify mirror)
			)
		)
		(duplicate_pad_numbers_are_jumpers no)
		(fp_line
			(start 1.143 0.5588)
			(end -1.143 0.5588)
			(stroke
				(width 0.1)
				(type default)
			)
			(layer "B.SilkS")
		)
		(fp_line
			(start 1.143 -0.5588)
			(end 1.143 0.5588)
			(stroke
				(width 0.1)
				(type default)
			)
			(layer "B.SilkS")
		)
		(fp_line
			(start -1.143 0.5588)
			(end -1.143 -0.5588)
			(stroke
				(width 0.1)
				(type default)
			)
			(layer "B.SilkS")
		)
		(fp_line
			(start -1.143 -0.5588)
			(end 1.143 -0.5588)
			(stroke
				(width 0.1)
				(type default)
			)
			(layer "B.SilkS")
		)
		(fp_poly
			(pts
				(xy 1.143 0.5588) (xy -1.143 0.5588) (xy -1.143 -0.5588) (xy 1.143 -0.5588)
			)
			(stroke
				(width 0)
				(type default)
			)
			(fill no)
			(layer "B.CrtYd")
		)
		(fp_line
			(start 0.508 0.3048)
			(end -0.508 0.3048)
			(stroke
				(width 0.1)
				(type default)
			)
			(layer "B.Fab")
		)
		(fp_line
			(start 0.508 -0.3048)
			(end 0.508 0.3048)
			(stroke
				(width 0.1)
				(type default)
			)
			(layer "B.Fab")
		)
		(fp_line
			(start -0.508 0.3048)
			(end -0.508 -0.3048)
			(stroke
				(width 0.1)
				(type default)
			)
			(layer "B.Fab")
		)
		(fp_line
			(start -0.508 -0.3048)
			(end 0.508 -0.3048)
			(stroke
				(width 0.1)
				(type default)
			)
			(layer "B.Fab")
		)
		(pad "1" smd rect
			(at 0.5334 0)
			(size 0.7112 0.6096)
			(layers "B.Cu" "B.Mask" "B.Paste")
			(net "R_FT4232_TDO")
		)
		(pad "2" smd rect
			(at -0.5334 0)
			(size 0.7112 0.6096)
			(layers "B.Cu" "B.Mask" "B.Paste")
			(net "FT4232_TDO_MISO")
		)
		(zone
			(layer "B.Cu")
			(hatch none 0.5)
			(connect_pads
				(clearance 0)
			)
			(min_thickness 0.25)
			(keepout
				(tracks allowed)
				(vias not_allowed)
				(pads allowed)
				(copperpour not_allowed)
				(footprints allowed)
			)
			(placement
				(enabled no)
				(sheetname "")
			)
			(fill
				(thermal_gap 0.5)
				(thermal_bridge_width 0.5)
				(island_removal_mode 0)
			)
			(polygon
				(pts
					(xy 22.5298 -89.2048) (xy 22.5298 -88.5952) (xy 22.6822 -88.5952) (xy 22.6822 -89.2048)
				)
			)
		)
		(zone
			(layer "B.Cu")
			(hatch none 0.5)
			(connect_pads
				(clearance 0)
			)
			(min_thickness 0.25)
			(keepout
				(tracks not_allowed)
				(vias allowed)
				(pads allowed)
				(copperpour not_allowed)
				(footprints allowed)
			)
			(placement
				(enabled no)
				(sheetname "")
			)
			(fill
				(thermal_gap 0.5)
				(thermal_bridge_width 0.5)
				(island_removal_mode 0)
			)
			(polygon
				(pts
					(xy 22.5298 -89.2048) (xy 22.5298 -88.5952) (xy 22.6822 -88.5952) (xy 22.6822 -89.2048)
				)
			)
		)
	)
	(footprint ""
		(layer "B.Cu")
		(at 64.516 -58.039 -90)
		(property "Reference" "R100"
			(at 5.969 -0.34163 270)
			(unlocked yes)
			(layer "B.SilkS")
			(effects
				(font
					(size 0.7874 0.5842)
					(thickness 0.1524)
				)
				(justify mirror)
			)
		)
		(property "Value" "VAL*"
			(at -0.02032 2.13233 270)
			(unlocked yes)
			(layer "B.Fab")
			(hide yes)
			(effects
				(font
					(size 0.7874 0.5842)
					(thickness 0.1524)
				)
				(justify mirror)
			)
		)
		(property "Tolerance" "TOL*"
			(at -0.044704 3.05435 270)
			(unlocked yes)
			(layer "Cmts.User")
			(hide yes)
			(effects
				(font
					(size 0.7874 0.5842)
					(thickness 0.1524)
				)
				(justify mirror)
			)
		)
		(property "User Part Number" "PARTNUM*"
			(at -0.02032 4.024884 270)
			(unlocked yes)
			(layer "Cmts.User")
			(hide yes)
			(effects
				(font
					(size 0.7874 0.5842)
					(thickness 0.1524)
				)
				(justify mirror)
			)
		)
		(property "Device Type" "RESISTOR-G155-133R0-01,33OHM,1%"
			(at -0.008382 1.210564 270)
			(unlocked yes)
			(layer "B.Fab")
			(hide yes)
			(effects
				(font
					(size 0.7874 0.5842)
					(thickness 0.1524)
				)
				(justify mirror)
			)
		)
		(duplicate_pad_numbers_are_jumpers no)
		(fp_line
			(start -1.143 0.5588)
			(end -1.143 -0.5588)
			(stroke
				(width 0.1)
				(type default)
			)
			(layer "B.SilkS")
		)
		(fp_line
			(start 1.143 0.5588)
			(end -1.143 0.5588)
			(stroke
				(width 0.1)
				(type default)
			)
			(layer "B.SilkS")
		)
		(fp_line
			(start -1.143 -0.5588)
			(end 1.143 -0.5588)
			(stroke
				(width 0.1)
				(type default)
			)
			(layer "B.SilkS")
		)
		(fp_line
			(start 1.143 -0.5588)
			(end 1.143 0.5588)
			(stroke
				(width 0.1)
				(type default)
			)
			(layer "B.SilkS")
		)
		(fp_rect
			(start -1.143 -0.5588)
			(end 1.143 0.5588)
			(stroke
				(width 0)
				(type default)
			)
			(fill no)
			(layer "B.CrtYd")
		)
		(fp_line
			(start -0.508 0.3048)
			(end -0.508 -0.3048)
			(stroke
				(width 0.1)
				(type default)
			)
			(layer "B.Fab")
		)
		(fp_line
			(start 0.508 0.3048)
			(end -0.508 0.3048)
			(stroke
				(width 0.1)
				(type default)
			)
			(layer "B.Fab")
		)
		(fp_line
			(start -0.508 -0.3048)
			(end 0.508 -0.3048)
			(stroke
				(width 0.1)
				(type default)
			)
			(layer "B.Fab")
		)
		(fp_line
			(start 0.508 -0.3048)
			(end 0.508 0.3048)
			(stroke
				(width 0.1)
				(type default)
			)
			(layer "B.Fab")
		)
		(pad "1" smd rect
			(at 0.5334 0 90)
			(size 0.7112 0.6096)
			(layers "B.Cu" "B.Mask" "B.Paste")
			(net "FPGA_OUT_MACUSBPOWER_EN")
		)
		(pad "2" smd rect
			(at -0.5334 0 90)
			(size 0.7112 0.6096)
			(layers "B.Cu" "B.Mask" "B.Paste")
			(net "USB_PWR_EN")
		)
		(zone
			(layer "B.Cu")
			(hatch none 0.5)
			(connect_pads
				(clearance 0)
			)
			(min_thickness 0.25)
			(keepout
				(tracks allowed)
				(vias not_allowed)
				(pads allowed)
				(copperpour not_allowed)
				(footprints allowed)
			)
			(placement
				(enabled no)
				(sheetname "")
			)
			(fill
				(thermal_gap 0.5)
				(thermal_bridge_width 0.5)
				(island_removal_mode 0)
			)
			(polygon
				(pts
					(xy 64.8208 -58.1152) (xy 64.2112 -58.1152) (xy 64.2112 -57.9628) (xy 64.8208 -57.9628)
				)
			)
		)
	)
	(footprint ""
		(layer "B.Cu")
		(at 5.588 -74.295 180)
		(property "Reference" "R335"
			(at 2.921 0.34163 0)
			(unlocked yes)
			(layer "B.SilkS")
			(effects
				(font
					(size 0.7874 0.5842)
					(thickness 0.1524)
				)
				(justify mirror)
			)
		)
		(property "Value" "VAL*"
			(at -0.02032 2.13233 180)
			(unlocked yes)
			(layer "B.Fab")
			(hide yes)
			(effects
				(font
					(size 0.7874 0.5842)
					(thickness 0.1524)
				)
				(justify mirror)
			)
		)
		(property "Tolerance" "TOL*"
			(at -0.044704 3.05435 180)
			(unlocked yes)
			(layer "Cmts.User")
			(hide yes)
			(effects
				(font
					(size 0.7874 0.5842)
					(thickness 0.1524)
				)
				(justify mirror)
			)
		)
		(property "User Part Number" "PARTNUM*"
			(at -0.02032 4.024884 180)
			(unlocked yes)
			(layer "Cmts.User")
			(hide yes)
			(effects
				(font
					(size 0.7874 0.5842)
					(thickness 0.1524)
				)
				(justify mirror)
			)
		)
		(property "Device Type" "RESISTOR-G155-14701-01,4.7KOHMA"
			(at -0.008382 1.210564 180)
			(unlocked yes)
			(layer "B.Fab")
			(hide yes)
			(effects
				(font
					(size 0.7874 0.5842)
					(thickness 0.1524)
				)
				(justify mirror)
			)
		)
		(duplicate_pad_numbers_are_jumpers no)
		(fp_line
			(start 1.143 0.5588)
			(end -1.143 0.5588)
			(stroke
				(width 0.1)
				(type default)
			)
			(layer "B.SilkS")
		)
		(fp_line
			(start 1.143 -0.5588)
			(end 1.143 0.5588)
			(stroke
				(width 0.1)
				(type default)
			)
			(layer "B.SilkS")
		)
		(fp_line
			(start -1.143 0.5588)
			(end -1.143 -0.5588)
			(stroke
				(width 0.1)
				(type default)
			)
			(layer "B.SilkS")
		)
		(fp_line
			(start -1.143 -0.5588)
			(end 1.143 -0.5588)
			(stroke
				(width 0.1)
				(type default)
			)
			(layer "B.SilkS")
		)
		(fp_rect
			(start -1.143 0.5588)
			(end 1.143 -0.5588)
			(stroke
				(width 0)
				(type default)
			)
			(fill no)
			(layer "B.CrtYd")
		)
		(fp_line
			(start 0.508 0.3048)
			(end -0.508 0.3048)
			(stroke
				(width 0.1)
				(type default)
			)
			(layer "B.Fab")
		)
		(fp_line
			(start 0.508 -0.3048)
			(end 0.508 0.3048)
			(stroke
				(width 0.1)
				(type default)
			)
			(layer "B.Fab")
		)
		(fp_line
			(start -0.508 0.3048)
			(end -0.508 -0.3048)
			(stroke
				(width 0.1)
				(type default)
			)
			(layer "B.Fab")
		)
		(fp_line
			(start -0.508 -0.3048)
			(end 0.508 -0.3048)
			(stroke
				(width 0.1)
				(type default)
			)
			(layer "B.Fab")
		)
		(pad "1" smd rect
			(at 0.5334 0)
			(size 0.7112 0.6096)
			(layers "B.Cu" "B.Mask" "B.Paste")
			(net "XP3R3V_FPGA")
		)
		(pad "2" smd rect
			(at -0.5334 0)
			(size 0.7112 0.6096)
			(layers "B.Cu" "B.Mask" "B.Paste")
			(net "UNNAMED_6_LM75BDPTSSOP8_I34_A1")
		)
		(zone
			(layer "B.Cu")
			(hatch none 0.5)
			(connect_pads
				(clearance 0)
			)
			(min_thickness 0.25)
			(keepout
				(tracks allowed)
				(vias not_allowed)
				(pads allowed)
				(copperpour not_allowed)
				(footprints allowed)
			)
			(placement
				(enabled no)
				(sheetname "")
			)
			(fill
				(thermal_gap 0.5)
				(thermal_bridge_width 0.5)
				(island_removal_mode 0)
			)
			(polygon
				(pts
					(xy 5.6642 -74.5998) (xy 5.5118 -74.5998) (xy 5.5118 -73.9902) (xy 5.6642 -73.9902)
				)
			)
		)
	)
	(footprint ""
		(layer "B.Cu")
		(at 87.376 -57.277 180)
		(property "Reference" "R74"
			(at -1.778 -3.08737 0)
			(unlocked yes)
			(layer "B.SilkS")
			(effects
				(font
					(size 0.7874 0.5842)
					(thickness 0.1524)
				)
				(justify mirror)
			)
		)
		(property "Value" "VAL*"
			(at -0.02032 2.13233 180)
			(unlocked yes)
			(layer "B.Fab")
			(hide yes)
			(effects
				(font
					(size 0.7874 0.5842)
					(thickness 0.1524)
				)
				(justify mirror)
			)
		)
		(property "Device Type" "RESISTOR-G155-14701-01,4.7KOHMA"
			(at -0.008382 1.210564 180)
			(unlocked yes)
			(layer "B.Fab")
			(hide yes)
			(effects
				(font
					(size 0.7874 0.5842)
					(thickness 0.1524)
				)
				(justify mirror)
			)
		)
		(property "User Part Number" "PARTNUM*"
			(at -0.02032 4.024884 180)
			(unlocked yes)
			(layer "Cmts.User")
			(hide yes)
			(effects
				(font
					(size 0.7874 0.5842)
					(thickness 0.1524)
				)
				(justify mirror)
			)
		)
		(property "Tolerance" "TOL*"
			(at -0.044704 3.05435 180)
			(unlocked yes)
			(layer "Cmts.User")
			(hide yes)
			(effects
				(font
					(size 0.7874 0.5842)
					(thickness 0.1524)
				)
				(justify mirror)
			)
		)
		(duplicate_pad_numbers_are_jumpers no)
		(fp_line
			(start 1.143 0.5588)
			(end -1.143 0.5588)
			(stroke
				(width 0.1)
				(type default)
			)
			(layer "B.SilkS")
		)
		(fp_line
			(start 1.143 -0.5588)
			(end 1.143 0.5588)
			(stroke
				(width 0.1)
				(type default)
			)
			(layer "B.SilkS")
		)
		(fp_line
			(start -1.143 0.5588)
			(end -1.143 -0.5588)
			(stroke
				(width 0.1)
				(type default)
			)
			(layer "B.SilkS")
		)
		(fp_line
			(start -1.143 -0.5588)
			(end 1.143 -0.5588)
			(stroke
				(width 0.1)
				(type default)
			)
			(layer "B.SilkS")
		)
		(fp_rect
			(start -1.143 -0.5588)
			(end 1.143 0.5588)
			(stroke
				(width 0)
				(type default)
			)
			(fill no)
			(layer "B.CrtYd")
		)
		(fp_line
			(start 0.508 0.3048)
			(end -0.508 0.3048)
			(stroke
				(width 0.1)
				(type default)
			)
			(layer "B.Fab")
		)
		(fp_line
			(start 0.508 -0.3048)
			(end 0.508 0.3048)
			(stroke
				(width 0.1)
				(type default)
			)
			(layer "B.Fab")
		)
		(fp_line
			(start -0.508 0.3048)
			(end -0.508 -0.3048)
			(stroke
				(width 0.1)
				(type default)
			)
			(layer "B.Fab")
		)
		(fp_line
			(start -0.508 -0.3048)
			(end 0.508 -0.3048)
			(stroke
				(width 0.1)
				(type default)
			)
			(layer "B.Fab")
		)
		(pad "1" smd rect
			(at 0.5334 0)
			(size 0.7112 0.6096)
			(layers "B.Cu" "B.Mask" "B.Paste")
			(net "XP3R3V_FPGA")
		)
		(pad "2" smd rect
			(at -0.5334 0)
			(size 0.7112 0.6096)
			(layers "B.Cu" "B.Mask" "B.Paste")
			(net "BNO080_I2C_SDA")
		)
		(zone
			(layer "B.Cu")
			(hatch none 0.5)
			(connect_pads
				(clearance 0)
			)
			(min_thickness 0.25)
			(keepout
				(tracks allowed)
				(vias not_allowed)
				(pads allowed)
				(copperpour not_allowed)
				(footprints allowed)
			)
			(placement
				(enabled no)
				(sheetname "")
			)
			(fill
				(thermal_gap 0.5)
				(thermal_bridge_width 0.5)
				(island_removal_mode 0)
			)
			(polygon
				(pts
					(xy 87.4522 -56.9722) (xy 87.4522 -57.5818) (xy 87.2998 -57.5818) (xy 87.2998 -56.9722)
				)
			)
		)
	)
	(footprint ""
		(layer "B.Cu")
		(at 55.1942 -74.9808 90)
		(property "Reference" "R416"
			(at 4.064 0.08763 270)
			(unlocked yes)
			(layer "B.SilkS")
			(effects
				(font
					(size 0.7874 0.5842)
					(thickness 0.1524)
				)
				(justify mirror)
			)
		)
		(property "Value" "VAL*"
			(at -0.02032 2.13233 90)
			(unlocked yes)
			(layer "B.Fab")
			(hide yes)
			(effects
				(font
					(size 0.7874 0.5842)
					(thickness 0.1524)
				)
				(justify mirror)
			)
		)
		(property "Device Type" "RESISTOR-G155-11001-01,1KOHM,1%"
			(at -0.008382 1.210564 90)
			(unlocked yes)
			(layer "B.Fab")
			(hide yes)
			(effects
				(font
					(size 0.7874 0.5842)
					(thickness 0.1524)
				)
				(justify mirror)
			)
		)
		(property "User Part Number" "PARTNUM*"
			(at -0.02032 4.024884 90)
			(unlocked yes)
			(layer "Cmts.User")
			(hide yes)
			(effects
				(font
					(size 0.7874 0.5842)
					(thickness 0.1524)
				)
				(justify mirror)
			)
		)
		(property "Tolerance" "TOL*"
			(at -0.044704 3.05435 90)
			(unlocked yes)
			(layer "Cmts.User")
			(hide yes)
			(effects
				(font
					(size 0.7874 0.5842)
					(thickness 0.1524)
				)
				(justify mirror)
			)
		)
		(duplicate_pad_numbers_are_jumpers no)
		(fp_line
			(start 1.143 -0.5588)
			(end 1.143 0.5588)
			(stroke
				(width 0.1)
				(type default)
			)
			(layer "B.SilkS")
		)
		(fp_line
			(start -1.143 -0.5588)
			(end 1.143 -0.5588)
			(stroke
				(width 0.1)
				(type default)
			)
			(layer "B.SilkS")
		)
		(fp_line
			(start 1.143 0.5588)
			(end -1.143 0.5588)
			(stroke
				(width 0.1)
				(type default)
			)
			(layer "B.SilkS")
		)
		(fp_line
			(start -1.143 0.5588)
			(end -1.143 -0.5588)
			(stroke
				(width 0.1)
				(type default)
			)
			(layer "B.SilkS")
		)
		(fp_rect
			(start 1.143 0.5588)
			(end -1.143 -0.5588)
			(stroke
				(width 0)
				(type default)
			)
			(fill no)
			(layer "B.CrtYd")
		)
		(fp_line
			(start 0.508 -0.3048)
			(end 0.508 0.3048)
			(stroke
				(width 0.1)
				(type default)
			)
			(layer "B.Fab")
		)
		(fp_line
			(start -0.508 -0.3048)
			(end 0.508 -0.3048)
			(stroke
				(width 0.1)
				(type default)
			)
			(layer "B.Fab")
		)
		(fp_line
			(start 0.508 0.3048)
			(end -0.508 0.3048)
			(stroke
				(width 0.1)
				(type default)
			)
			(layer "B.Fab")
		)
		(fp_line
			(start -0.508 0.3048)
			(end -0.508 -0.3048)
			(stroke
				(width 0.1)
				(type default)
			)
			(layer "B.Fab")
		)
		(pad "1" smd rect
			(at 0.5334 0 270)
			(size 0.7112 0.6096)
			(layers "B.Cu" "B.Mask" "B.Paste")
			(net "UNNAMED_6_LM75BDPTSSOP8_I59_A0")
		)
		(pad "2" smd rect
			(at -0.5334 0 270)
			(size 0.7112 0.6096)
			(layers "B.Cu" "B.Mask" "B.Paste")
			(net "SG")
		)
		(zone
			(layer "B.Cu")
			(hatch none 0.5)
			(connect_pads
				(clearance 0)
			)
			(min_thickness 0.25)
			(keepout
				(tracks allowed)
				(vias not_allowed)
				(pads allowed)
				(copperpour not_allowed)
				(footprints allowed)
			)
			(placement
				(enabled no)
				(sheetname "")
			)
			(fill
				(thermal_gap 0.5)
				(thermal_bridge_width 0.5)
				(island_removal_mode 0)
			)
			(polygon
				(pts
					(xy 55.499 -75.057) (xy 54.8894 -75.057) (xy 54.8894 -74.9046) (xy 55.499 -74.9046)
				)
			)
		)
		(zone
			(layer "B.Cu")
			(hatch none 0.5)
			(connect_pads
				(clearance 0)
			)
			(min_thickness 0.25)
			(keepout
				(tracks not_allowed)
				(vias allowed)
				(pads allowed)
				(copperpour not_allowed)
				(footprints allowed)
			)
			(placement
				(enabled no)
				(sheetname "")
			)
			(fill
				(thermal_gap 0.5)
				(thermal_bridge_width 0.5)
				(island_removal_mode 0)
			)
			(polygon
				(pts
					(xy 55.499 -75.057) (xy 54.8894 -75.057) (xy 54.8894 -74.9046) (xy 55.499 -74.9046)
				)
			)
		)
	)
	(footprint ""
		(layer "B.Cu")
		(at 85.09 -56.134 180)
		(property "Reference" "R77"
			(at 2.032 -1.18237 0)
			(unlocked yes)
			(layer "B.SilkS")
			(effects
				(font
					(size 0.7874 0.5842)
					(thickness 0.1524)
				)
				(justify mirror)
			)
		)
		(property "Value" "VAL*"
			(at -0.02032 2.13233 180)
			(unlocked yes)
			(layer "B.Fab")
			(hide yes)
			(effects
				(font
					(size 0.7874 0.5842)
					(thickness 0.1524)
				)
				(justify mirror)
			)
		)
		(property "Device Type" "RESISTOR-G155-133R0-01,33OHM,1%"
			(at -0.008382 1.210564 180)
			(unlocked yes)
			(layer "B.Fab")
			(hide yes)
			(effects
				(font
					(size 0.7874 0.5842)
					(thickness 0.1524)
				)
				(justify mirror)
			)
		)
		(property "User Part Number" "PARTNUM*"
			(at -0.02032 4.024884 180)
			(unlocked yes)
			(layer "Cmts.User")
			(hide yes)
			(effects
				(font
					(size 0.7874 0.5842)
					(thickness 0.1524)
				)
				(justify mirror)
			)
		)
		(property "Tolerance" "TOL*"
			(at -0.044704 3.05435 180)
			(unlocked yes)
			(layer "Cmts.User")
			(hide yes)
			(effects
				(font
					(size 0.7874 0.5842)
					(thickness 0.1524)
				)
				(justify mirror)
			)
		)
		(duplicate_pad_numbers_are_jumpers no)
		(fp_line
			(start 1.143 0.5588)
			(end -1.143 0.5588)
			(stroke
				(width 0.1)
				(type default)
			)
			(layer "B.SilkS")
		)
		(fp_line
			(start 1.143 -0.5588)
			(end 1.143 0.5588)
			(stroke
				(width 0.1)
				(type default)
			)
			(layer "B.SilkS")
		)
		(fp_line
			(start -1.143 0.5588)
			(end -1.143 -0.5588)
			(stroke
				(width 0.1)
				(type default)
			)
			(layer "B.SilkS")
		)
		(fp_line
			(start -1.143 -0.5588)
			(end 1.143 -0.5588)
			(stroke
				(width 0.1)
				(type default)
			)
			(layer "B.SilkS")
		)
		(fp_rect
			(start 1.143 -0.5588)
			(end -1.143 0.5588)
			(stroke
				(width 0)
				(type default)
			)
			(fill no)
			(layer "B.CrtYd")
		)
		(fp_line
			(start 0.508 0.3048)
			(end -0.508 0.3048)
			(stroke
				(width 0.1)
				(type default)
			)
			(layer "B.Fab")
		)
		(fp_line
			(start 0.508 -0.3048)
			(end 0.508 0.3048)
			(stroke
				(width 0.1)
				(type default)
			)
			(layer "B.Fab")
		)
		(fp_line
			(start -0.508 0.3048)
			(end -0.508 -0.3048)
			(stroke
				(width 0.1)
				(type default)
			)
			(layer "B.Fab")
		)
		(fp_line
			(start -0.508 -0.3048)
			(end 0.508 -0.3048)
			(stroke
				(width 0.1)
				(type default)
			)
			(layer "B.Fab")
		)
		(pad "1" smd rect
			(at 0.5334 0)
			(size 0.7112 0.6096)
			(layers "B.Cu" "B.Mask" "B.Paste")
			(net "BNO080_I2C_SCL")
		)
		(pad "2" smd rect
			(at -0.5334 0)
			(size 0.7112 0.6096)
			(layers "B.Cu" "B.Mask" "B.Paste")
			(net "R_BNO080_I2C_SCL")
		)
		(zone
			(layer "B.Cu")
			(hatch none 0.5)
			(connect_pads
				(clearance 0)
			)
			(min_thickness 0.25)
			(keepout
				(tracks allowed)
				(vias not_allowed)
				(pads allowed)
				(copperpour not_allowed)
				(footprints allowed)
			)
			(placement
				(enabled no)
				(sheetname "")
			)
			(fill
				(thermal_gap 0.5)
				(thermal_bridge_width 0.5)
				(island_removal_mode 0)
			)
			(polygon
				(pts
					(xy 85.0138 -55.8292) (xy 85.1662 -55.8292) (xy 85.1662 -56.4388) (xy 85.0138 -56.4388)
				)
			)
		)
	)
	(footprint ""
		(layer "B.Cu")
		(at 36.7284 -97.8154 180)
		(property "Reference" "R47"
			(at 3.8354 -0.69977 0)
			(unlocked yes)
			(layer "B.SilkS")
			(effects
				(font
					(size 0.7874 0.5842)
					(thickness 0.1524)
				)
				(justify mirror)
			)
		)
		(property "Value" "VAL*"
			(at -0.02032 2.13233 180)
			(unlocked yes)
			(layer "B.Fab")
			(hide yes)
			(effects
				(font
					(size 0.7874 0.5842)
					(thickness 0.1524)
				)
				(justify mirror)
			)
		)
		(property "Tolerance" "TOL*"
			(at -0.044704 3.05435 180)
			(unlocked yes)
			(layer "Cmts.User")
			(hide yes)
			(effects
				(font
					(size 0.7874 0.5842)
					(thickness 0.1524)
				)
				(justify mirror)
			)
		)
		(property "User Part Number" "PARTNUM*"
			(at -0.02032 4.024884 180)
			(unlocked yes)
			(layer "Cmts.User")
			(hide yes)
			(effects
				(font
					(size 0.7874 0.5842)
					(thickness 0.1524)
				)
				(justify mirror)
			)
		)
		(property "Device Type" "RESISTOR-G155-11002-01,10KOHM,A"
			(at -0.008382 1.210564 180)
			(unlocked yes)
			(layer "B.Fab")
			(hide yes)
			(effects
				(font
					(size 0.7874 0.5842)
					(thickness 0.1524)
				)
				(justify mirror)
			)
		)
		(duplicate_pad_numbers_are_jumpers no)
		(fp_line
			(start 1.143 0.5588)
			(end -1.143 0.5588)
			(stroke
				(width 0.1)
				(type default)
			)
			(layer "B.SilkS")
		)
		(fp_line
			(start 1.143 -0.5588)
			(end 1.143 0.5588)
			(stroke
				(width 0.1)
				(type default)
			)
			(layer "B.SilkS")
		)
		(fp_line
			(start -1.143 0.5588)
			(end -1.143 -0.5588)
			(stroke
				(width 0.1)
				(type default)
			)
			(layer "B.SilkS")
		)
		(fp_line
			(start -1.143 -0.5588)
			(end 1.143 -0.5588)
			(stroke
				(width 0.1)
				(type default)
			)
			(layer "B.SilkS")
		)
		(fp_poly
			(pts
				(xy 1.143 0.5588) (xy -1.143 0.5588) (xy -1.143 -0.5588) (xy 1.143 -0.5588)
			)
			(stroke
				(width 0)
				(type default)
			)
			(fill no)
			(layer "B.CrtYd")
		)
		(fp_line
			(start 0.508 0.3048)
			(end -0.508 0.3048)
			(stroke
				(width 0.1)
				(type default)
			)
			(layer "B.Fab")
		)
		(fp_line
			(start 0.508 -0.3048)
			(end 0.508 0.3048)
			(stroke
				(width 0.1)
				(type default)
			)
			(layer "B.Fab")
		)
		(fp_line
			(start -0.508 0.3048)
			(end -0.508 -0.3048)
			(stroke
				(width 0.1)
				(type default)
			)
			(layer "B.Fab")
		)
		(fp_line
			(start -0.508 -0.3048)
			(end 0.508 -0.3048)
			(stroke
				(width 0.1)
				(type default)
			)
			(layer "B.Fab")
		)
		(pad "1" smd rect
			(at 0.5334 0)
			(size 0.7112 0.6096)
			(layers "B.Cu" "B.Mask" "B.Paste")
			(net "XP3R3V")
		)
		(pad "2" smd rect
			(at -0.5334 0)
			(size 0.7112 0.6096)
			(layers "B.Cu" "B.Mask" "B.Paste")
			(net "XP5R0V_PG")
		)
		(zone
			(layer "B.Cu")
			(hatch none 0.5)
			(connect_pads
				(clearance 0)
			)
			(min_thickness 0.25)
			(keepout
				(tracks allowed)
				(vias not_allowed)
				(pads allowed)
				(copperpour not_allowed)
				(footprints allowed)
			)
			(placement
				(enabled no)
				(sheetname "")
			)
			(fill
				(thermal_gap 0.5)
				(thermal_bridge_width 0.5)
				(island_removal_mode 0)
			)
			(polygon
				(pts
					(xy 36.6522 -98.1202) (xy 36.6522 -97.5106) (xy 36.8046 -97.5106) (xy 36.8046 -98.1202)
				)
			)
		)
		(zone
			(layer "B.Cu")
			(hatch none 0.5)
			(connect_pads
				(clearance 0)
			)
			(min_thickness 0.25)
			(keepout
				(tracks not_allowed)
				(vias allowed)
				(pads allowed)
				(copperpour not_allowed)
				(footprints allowed)
			)
			(placement
				(enabled no)
				(sheetname "")
			)
			(fill
				(thermal_gap 0.5)
				(thermal_bridge_width 0.5)
				(island_removal_mode 0)
			)
			(polygon
				(pts
					(xy 36.6522 -98.1202) (xy 36.6522 -97.5106) (xy 36.8046 -97.5106) (xy 36.8046 -98.1202)
				)
			)
		)
	)
	(footprint ""
		(layer "B.Cu")
		(at 117.348 -61.976 90)
		(property "Reference" "R224"
			(at 3.429 0.08763 270)
			(unlocked yes)
			(layer "B.SilkS")
			(effects
				(font
					(size 0.7874 0.5842)
					(thickness 0.1524)
				)
				(justify mirror)
			)
		)
		(property "Value" "VAL*"
			(at -0.02032 2.13233 90)
			(unlocked yes)
			(layer "B.Fab")
			(hide yes)
			(effects
				(font
					(size 0.7874 0.5842)
					(thickness 0.1524)
				)
				(justify mirror)
			)
		)
		(property "Device Type" "RESISTOR-G155-11001-01,1KOHM,1%"
			(at -0.008382 1.210564 90)
			(unlocked yes)
			(layer "B.Fab")
			(hide yes)
			(effects
				(font
					(size 0.7874 0.5842)
					(thickness 0.1524)
				)
				(justify mirror)
			)
		)
		(property "User Part Number" "PARTNUM*"
			(at -0.02032 4.024884 90)
			(unlocked yes)
			(layer "Cmts.User")
			(hide yes)
			(effects
				(font
					(size 0.7874 0.5842)
					(thickness 0.1524)
				)
				(justify mirror)
			)
		)
		(property "Tolerance" "TOL*"
			(at -0.044704 3.05435 90)
			(unlocked yes)
			(layer "Cmts.User")
			(hide yes)
			(effects
				(font
					(size 0.7874 0.5842)
					(thickness 0.1524)
				)
				(justify mirror)
			)
		)
		(duplicate_pad_numbers_are_jumpers no)
		(fp_line
			(start 1.143 -0.5588)
			(end 1.143 0.5588)
			(stroke
				(width 0.1)
				(type default)
			)
			(layer "B.SilkS")
		)
		(fp_line
			(start -1.143 -0.5588)
			(end 1.143 -0.5588)
			(stroke
				(width 0.1)
				(type default)
			)
			(layer "B.SilkS")
		)
		(fp_line
			(start 1.143 0.5588)
			(end -1.143 0.5588)
			(stroke
				(width 0.1)
				(type default)
			)
			(layer "B.SilkS")
		)
		(fp_line
			(start -1.143 0.5588)
			(end -1.143 -0.5588)
			(stroke
				(width 0.1)
				(type default)
			)
			(layer "B.SilkS")
		)
		(fp_rect
			(start -1.143 -0.5588)
			(end 1.143 0.5588)
			(stroke
				(width 0)
				(type default)
			)
			(fill no)
			(layer "B.CrtYd")
		)
		(fp_line
			(start 0.508 -0.3048)
			(end 0.508 0.3048)
			(stroke
				(width 0.1)
				(type default)
			)
			(layer "B.Fab")
		)
		(fp_line
			(start -0.508 -0.3048)
			(end 0.508 -0.3048)
			(stroke
				(width 0.1)
				(type default)
			)
			(layer "B.Fab")
		)
		(fp_line
			(start 0.508 0.3048)
			(end -0.508 0.3048)
			(stroke
				(width 0.1)
				(type default)
			)
			(layer "B.Fab")
		)
		(fp_line
			(start -0.508 0.3048)
			(end -0.508 -0.3048)
			(stroke
				(width 0.1)
				(type default)
			)
			(layer "B.Fab")
		)
		(pad "1" smd rect
			(at 0.5334 0 270)
			(size 0.7112 0.6096)
			(layers "B.Cu" "B.Mask" "B.Paste")
			(net "SG")
		)
		(pad "2" smd rect
			(at -0.5334 0 270)
			(size 0.7112 0.6096)
			(layers "B.Cu" "B.Mask" "B.Paste")
			(net "PUDC")
		)
		(zone
			(layer "B.Cu")
			(hatch none 0.5)
			(connect_pads
				(clearance 0)
			)
			(min_thickness 0.25)
			(keepout
				(tracks allowed)
				(vias not_allowed)
				(pads allowed)
				(copperpour not_allowed)
				(footprints allowed)
			)
			(placement
				(enabled no)
				(sheetname "")
			)
			(fill
				(thermal_gap 0.5)
				(thermal_bridge_width 0.5)
				(island_removal_mode 0)
			)
			(polygon
				(pts
					(xy 117.0432 -61.8998) (xy 117.6528 -61.8998) (xy 117.6528 -62.0522) (xy 117.0432 -62.0522)
				)
			)
		)
	)
	(footprint ""
		(layer "B.Cu")
		(at 13.462 -17.1704 -90)
		(property "Reference" "R123"
			(at -2.2606 -0.22225 270)
			(unlocked yes)
			(layer "B.SilkS")
			(effects
				(font
					(size 0.635 0.4064)
					(thickness 0.1524)
				)
				(justify mirror)
			)
		)
		(property "Value" "VAL*"
			(at -0.02032 2.13233 270)
			(unlocked yes)
			(layer "B.Fab")
			(hide yes)
			(effects
				(font
					(size 0.7874 0.5842)
					(thickness 0.1524)
				)
				(justify mirror)
			)
		)
		(property "Tolerance" "TOL*"
			(at -0.044704 3.05435 270)
			(unlocked yes)
			(layer "Cmts.User")
			(hide yes)
			(effects
				(font
					(size 0.7874 0.5842)
					(thickness 0.1524)
				)
				(justify mirror)
			)
		)
		(property "User Part Number" "PARTNUM*"
			(at -0.02032 4.024884 270)
			(unlocked yes)
			(layer "Cmts.User")
			(hide yes)
			(effects
				(font
					(size 0.7874 0.5842)
					(thickness 0.1524)
				)
				(justify mirror)
			)
		)
		(property "Device Type" "RESISTOR-G155-149R9-01,49.9OHMA"
			(at -0.008382 1.210564 270)
			(unlocked yes)
			(layer "B.Fab")
			(hide yes)
			(effects
				(font
					(size 0.7874 0.5842)
					(thickness 0.1524)
				)
				(justify mirror)
			)
		)
		(duplicate_pad_numbers_are_jumpers no)
		(fp_line
			(start -1.143 0.5588)
			(end -1.143 -0.5588)
			(stroke
				(width 0.1)
				(type default)
			)
			(layer "B.SilkS")
		)
		(fp_line
			(start 1.143 0.5588)
			(end -1.143 0.5588)
			(stroke
				(width 0.1)
				(type default)
			)
			(layer "B.SilkS")
		)
		(fp_line
			(start -1.143 -0.5588)
			(end 1.143 -0.5588)
			(stroke
				(width 0.1)
				(type default)
			)
			(layer "B.SilkS")
		)
		(fp_line
			(start 1.143 -0.5588)
			(end 1.143 0.5588)
			(stroke
				(width 0.1)
				(type default)
			)
			(layer "B.SilkS")
		)
		(fp_poly
			(pts
				(xy 1.143 0.5588) (xy -1.143 0.5588) (xy -1.143 -0.5588) (xy 1.143 -0.5588)
			)
			(stroke
				(width 0)
				(type default)
			)
			(fill no)
			(layer "B.CrtYd")
		)
		(fp_line
			(start -0.508 0.3048)
			(end -0.508 -0.3048)
			(stroke
				(width 0.1)
				(type default)
			)
			(layer "B.Fab")
		)
		(fp_line
			(start 0.508 0.3048)
			(end -0.508 0.3048)
			(stroke
				(width 0.1)
				(type default)
			)
			(layer "B.Fab")
		)
		(fp_line
			(start -0.508 -0.3048)
			(end 0.508 -0.3048)
			(stroke
				(width 0.1)
				(type default)
			)
			(layer "B.Fab")
		)
		(fp_line
			(start 0.508 -0.3048)
			(end 0.508 0.3048)
			(stroke
				(width 0.1)
				(type default)
			)
			(layer "B.Fab")
		)
		(pad "1" smd rect
			(at 0.5334 0 90)
			(size 0.7112 0.6096)
			(layers "B.Cu" "B.Mask" "B.Paste")
			(net "BF_SMA4_SIG_IO_CONN")
		)
		(pad "2" smd rect
			(at -0.5334 0 90)
			(size 0.7112 0.6096)
			(layers "B.Cu" "B.Mask" "B.Paste")
			(net "SMA4_SIG_IO_CONN")
		)
		(zone
			(layer "B.Cu")
			(hatch none 0.5)
			(connect_pads
				(clearance 0)
			)
			(min_thickness 0.25)
			(keepout
				(tracks allowed)
				(vias not_allowed)
				(pads allowed)
				(copperpour not_allowed)
				(footprints allowed)
			)
			(placement
				(enabled no)
				(sheetname "")
			)
			(fill
				(thermal_gap 0.5)
				(thermal_bridge_width 0.5)
				(island_removal_mode 0)
			)
			(polygon
				(pts
					(xy 13.1572 -17.0942) (xy 13.7668 -17.0942) (xy 13.7668 -17.2466) (xy 13.1572 -17.2466)
				)
			)
		)
		(zone
			(layer "B.Cu")
			(hatch none 0.5)
			(connect_pads
				(clearance 0)
			)
			(min_thickness 0.25)
			(keepout
				(tracks not_allowed)
				(vias allowed)
				(pads allowed)
				(copperpour not_allowed)
				(footprints allowed)
			)
			(placement
				(enabled no)
				(sheetname "")
			)
			(fill
				(thermal_gap 0.5)
				(thermal_bridge_width 0.5)
				(island_removal_mode 0)
			)
			(polygon
				(pts
					(xy 13.1572 -17.0942) (xy 13.7668 -17.0942) (xy 13.7668 -17.2466) (xy 13.1572 -17.2466)
				)
			)
		)
	)
	(footprint ""
		(layer "B.Cu")
		(at 102.743 -56.261)
		(property "Reference" "C159"
			(at 2.667 -0.01905 0)
			(unlocked yes)
			(layer "B.SilkS")
			(effects
				(font
					(size 0.635 0.4064)
					(thickness 0.1524)
				)
				(justify mirror)
			)
		)
		(property "Value" "VAL*"
			(at -0.02032 2.13233 0)
			(unlocked yes)
			(layer "B.Fab")
			(hide yes)
			(effects
				(font
					(size 0.7874 0.5842)
					(thickness 0.1524)
				)
				(justify mirror)
			)
		)
		(property "Device Type" "CAPACITOR-G105-0F475-BM,4.7UF,A"
			(at -0.008382 1.210564 0)
			(unlocked yes)
			(layer "B.Fab")
			(hide yes)
			(effects
				(font
					(size 0.7874 0.5842)
					(thickness 0.1524)
				)
				(justify mirror)
			)
		)
		(property "User Part Number" "PARTNUM*"
			(at -0.02032 4.024884 0)
			(unlocked yes)
			(layer "Cmts.User")
			(hide yes)
			(effects
				(font
					(size 0.7874 0.5842)
					(thickness 0.1524)
				)
				(justify mirror)
			)
		)
		(property "Tolerance" "TOL*"
			(at -0.044704 3.05435 0)
			(unlocked yes)
			(layer "Cmts.User")
			(hide yes)
			(effects
				(font
					(size 0.7874 0.5842)
					(thickness 0.1524)
				)
				(justify mirror)
			)
		)
		(duplicate_pad_numbers_are_jumpers no)
		(fp_line
			(start -1.143 -0.5588)
			(end 1.143 -0.5588)
			(stroke
				(width 0.1)
				(type default)
			)
			(layer "B.SilkS")
		)
		(fp_line
			(start -1.143 0.5588)
			(end -1.143 -0.5588)
			(stroke
				(width 0.1)
				(type default)
			)
			(layer "B.SilkS")
		)
		(fp_line
			(start 1.143 -0.5588)
			(end 1.143 0.5588)
			(stroke
				(width 0.1)
				(type default)
			)
			(layer "B.SilkS")
		)
		(fp_line
			(start 1.143 0.5588)
			(end -1.143 0.5588)
			(stroke
				(width 0.1)
				(type default)
			)
			(layer "B.SilkS")
		)
		(fp_rect
			(start -1.143 0.5588)
			(end 1.143 -0.5588)
			(stroke
				(width 0)
				(type default)
			)
			(fill no)
			(layer "B.CrtYd")
		)
		(fp_line
			(start -0.508 -0.3048)
			(end 0.508 -0.3048)
			(stroke
				(width 0.1)
				(type default)
			)
			(layer "B.Fab")
		)
		(fp_line
			(start -0.508 0.3048)
			(end -0.508 -0.3048)
			(stroke
				(width 0.1)
				(type default)
			)
			(layer "B.Fab")
		)
		(fp_line
			(start 0.508 -0.3048)
			(end 0.508 0.3048)
			(stroke
				(width 0.1)
				(type default)
			)
			(layer "B.Fab")
		)
		(fp_line
			(start 0.508 0.3048)
			(end -0.508 0.3048)
			(stroke
				(width 0.1)
				(type default)
			)
			(layer "B.Fab")
		)
		(pad "1" smd rect
			(at 0.5334 0 180)
			(size 0.7112 0.6096)
			(layers "B.Cu" "B.Mask" "B.Paste")
			(net "XP3R3V_FPGA")
		)
		(pad "2" smd rect
			(at -0.5334 0 180)
			(size 0.7112 0.6096)
			(layers "B.Cu" "B.Mask" "B.Paste")
			(net "SG")
		)
		(zone
			(layer "B.Cu")
			(hatch none 0.5)
			(connect_pads
				(clearance 0)
			)
			(min_thickness 0.25)
			(keepout
				(tracks allowed)
				(vias not_allowed)
				(pads allowed)
				(copperpour not_allowed)
				(footprints allowed)
			)
			(placement
				(enabled no)
				(sheetname "")
			)
			(fill
				(thermal_gap 0.5)
				(thermal_bridge_width 0.5)
				(island_removal_mode 0)
			)
			(polygon
				(pts
					(xy 102.6668 -55.9562) (xy 102.8192 -55.9562) (xy 102.8192 -56.5658) (xy 102.6668 -56.5658)
				)
			)
		)
	)
	(footprint ""
		(layer "B.Cu")
		(at 36.9824 -102.5144 180)
		(property "Reference" "C42"
			(at 4.0386 -0.64897 0)
			(unlocked yes)
			(layer "B.SilkS")
			(effects
				(font
					(size 0.7874 0.5842)
					(thickness 0.1524)
				)
				(justify mirror)
			)
		)
		(property "Value" "VAL*"
			(at -0.0762 2.067306 180)
			(unlocked yes)
			(layer "B.Fab")
			(hide yes)
			(effects
				(font
					(size 0.7874 0.5842)
					(thickness 0.1524)
				)
				(justify mirror)
			)
		)
		(property "Device Type" "CAPACITOR-G105-0B222-FK,2200PFA"
			(at -0.0508 1.127506 180)
			(unlocked yes)
			(layer "B.Fab")
			(hide yes)
			(effects
				(font
					(size 0.7874 0.5842)
					(thickness 0.1524)
				)
				(justify mirror)
			)
		)
		(property "User Part Number" "PARTNUM*"
			(at -0.1016 4.023106 180)
			(unlocked yes)
			(layer "Cmts.User")
			(hide yes)
			(effects
				(font
					(size 0.7874 0.5842)
					(thickness 0.1524)
				)
				(justify mirror)
			)
		)
		(property "Tolerance" "TOL*"
			(at -0.0762 3.032506 180)
			(unlocked yes)
			(layer "Cmts.User")
			(hide yes)
			(effects
				(font
					(size 0.7874 0.5842)
					(thickness 0.1524)
				)
				(justify mirror)
			)
		)
		(duplicate_pad_numbers_are_jumpers no)
		(fp_line
			(start 1.143 0.5588)
			(end -1.143 0.5588)
			(stroke
				(width 0.1)
				(type default)
			)
			(layer "B.SilkS")
		)
		(fp_line
			(start 1.143 -0.5588)
			(end 1.143 0.5588)
			(stroke
				(width 0.1)
				(type default)
			)
			(layer "B.SilkS")
		)
		(fp_line
			(start -1.143 0.5588)
			(end -1.143 -0.5588)
			(stroke
				(width 0.1)
				(type default)
			)
			(layer "B.SilkS")
		)
		(fp_line
			(start -1.143 -0.5588)
			(end 1.143 -0.5588)
			(stroke
				(width 0.1)
				(type default)
			)
			(layer "B.SilkS")
		)
		(fp_rect
			(start -1.143 0.5588)
			(end 1.143 -0.5588)
			(stroke
				(width 0)
				(type default)
			)
			(fill no)
			(layer "B.CrtYd")
		)
		(fp_line
			(start 0.508 0.3048)
			(end -0.508 0.3048)
			(stroke
				(width 0.1)
				(type default)
			)
			(layer "B.Fab")
		)
		(fp_line
			(start 0.508 -0.3048)
			(end 0.508 0.3048)
			(stroke
				(width 0.1)
				(type default)
			)
			(layer "B.Fab")
		)
		(fp_line
			(start -0.508 0.3048)
			(end -0.508 -0.3048)
			(stroke
				(width 0.1)
				(type default)
			)
			(layer "B.Fab")
		)
		(fp_line
			(start -0.508 -0.3048)
			(end 0.508 -0.3048)
			(stroke
				(width 0.1)
				(type default)
			)
			(layer "B.Fab")
		)
		(pad "1" smd rect
			(at 0.5334 0)
			(size 0.7112 0.6096)
			(layers "B.Cu" "B.Mask" "B.Paste")
			(net "UNNAMED_516_CAPACITOR_I13_1")
		)
		(pad "2" smd rect
			(at -0.5334 0)
			(size 0.7112 0.6096)
			(layers "B.Cu" "B.Mask" "B.Paste")
			(net "XP5R0V_AGND")
		)
		(zone
			(layer "B.Cu")
			(hatch none 0.5)
			(connect_pads
				(clearance 0)
			)
			(min_thickness 0.25)
			(keepout
				(tracks allowed)
				(vias not_allowed)
				(pads allowed)
				(copperpour not_allowed)
				(footprints allowed)
			)
			(placement
				(enabled no)
				(sheetname "")
			)
			(fill
				(thermal_gap 0.5)
				(thermal_bridge_width 0.5)
				(island_removal_mode 0)
			)
			(polygon
				(pts
					(xy 37.0586 -102.8192) (xy 36.9062 -102.8192) (xy 36.9062 -102.2096) (xy 37.0586 -102.2096)
				)
			)
		)
	)
	(footprint ""
		(layer "B.Cu")
		(at 5.588 -76.835)
		(property "Reference" "R338"
			(at -3.048 -0.46863 0)
			(unlocked yes)
			(layer "B.SilkS")
			(effects
				(font
					(size 0.7874 0.5842)
					(thickness 0.1524)
				)
				(justify mirror)
			)
		)
		(property "Value" "VAL*"
			(at -0.02032 2.13233 0)
			(unlocked yes)
			(layer "B.Fab")
			(hide yes)
			(effects
				(font
					(size 0.7874 0.5842)
					(thickness 0.1524)
				)
				(justify mirror)
			)
		)
		(property "Tolerance" "TOL*"
			(at -0.044704 3.05435 0)
			(unlocked yes)
			(layer "Cmts.User")
			(hide yes)
			(effects
				(font
					(size 0.7874 0.5842)
					(thickness 0.1524)
				)
				(justify mirror)
			)
		)
		(property "User Part Number" "PARTNUM*"
			(at -0.02032 4.024884 0)
			(unlocked yes)
			(layer "Cmts.User")
			(hide yes)
			(effects
				(font
					(size 0.7874 0.5842)
					(thickness 0.1524)
				)
				(justify mirror)
			)
		)
		(property "Device Type" "RESISTOR-G155-11001-01,1KOHM,1%"
			(at -0.008382 1.210564 0)
			(unlocked yes)
			(layer "B.Fab")
			(hide yes)
			(effects
				(font
					(size 0.7874 0.5842)
					(thickness 0.1524)
				)
				(justify mirror)
			)
		)
		(duplicate_pad_numbers_are_jumpers no)
		(fp_line
			(start -1.143 -0.5588)
			(end 1.143 -0.5588)
			(stroke
				(width 0.1)
				(type default)
			)
			(layer "B.SilkS")
		)
		(fp_line
			(start -1.143 0.5588)
			(end -1.143 -0.5588)
			(stroke
				(width 0.1)
				(type default)
			)
			(layer "B.SilkS")
		)
		(fp_line
			(start 1.143 -0.5588)
			(end 1.143 0.5588)
			(stroke
				(width 0.1)
				(type default)
			)
			(layer "B.SilkS")
		)
		(fp_line
			(start 1.143 0.5588)
			(end -1.143 0.5588)
			(stroke
				(width 0.1)
				(type default)
			)
			(layer "B.SilkS")
		)
		(fp_rect
			(start 1.143 0.5588)
			(end -1.143 -0.5588)
			(stroke
				(width 0)
				(type default)
			)
			(fill no)
			(layer "B.CrtYd")
		)
		(fp_line
			(start -0.508 -0.3048)
			(end 0.508 -0.3048)
			(stroke
				(width 0.1)
				(type default)
			)
			(layer "B.Fab")
		)
		(fp_line
			(start -0.508 0.3048)
			(end -0.508 -0.3048)
			(stroke
				(width 0.1)
				(type default)
			)
			(layer "B.Fab")
		)
		(fp_line
			(start 0.508 -0.3048)
			(end 0.508 0.3048)
			(stroke
				(width 0.1)
				(type default)
			)
			(layer "B.Fab")
		)
		(fp_line
			(start 0.508 0.3048)
			(end -0.508 0.3048)
			(stroke
				(width 0.1)
				(type default)
			)
			(layer "B.Fab")
		)
		(pad "1" smd rect
			(at 0.5334 0 180)
			(size 0.7112 0.6096)
			(layers "B.Cu" "B.Mask" "B.Paste")
			(net "UNNAMED_6_LM75BDPTSSOP8_I34_A0")
		)
		(pad "2" smd rect
			(at -0.5334 0 180)
			(size 0.7112 0.6096)
			(layers "B.Cu" "B.Mask" "B.Paste")
			(net "SG")
		)
		(zone
			(layer "B.Cu")
			(hatch none 0.5)
			(connect_pads
				(clearance 0)
			)
			(min_thickness 0.25)
			(keepout
				(tracks allowed)
				(vias not_allowed)
				(pads allowed)
				(copperpour not_allowed)
				(footprints allowed)
			)
			(placement
				(enabled no)
				(sheetname "")
			)
			(fill
				(thermal_gap 0.5)
				(thermal_bridge_width 0.5)
				(island_removal_mode 0)
			)
			(polygon
				(pts
					(xy 5.6642 -76.5302) (xy 5.6642 -77.1398) (xy 5.5118 -77.1398) (xy 5.5118 -76.5302)
				)
			)
		)
	)
	(footprint ""
		(layer "B.Cu")
		(at 115.443 -74.803)
		(property "Reference" "R226"
			(at -0.127 -2.11963 0)
			(unlocked yes)
			(layer "B.SilkS")
			(effects
				(font
					(size 0.7874 0.5842)
					(thickness 0.1524)
				)
				(justify mirror)
			)
		)
		(property "Value" "VAL*"
			(at -0.02032 2.13233 0)
			(unlocked yes)
			(layer "B.Fab")
			(hide yes)
			(effects
				(font
					(size 0.7874 0.5842)
					(thickness 0.1524)
				)
				(justify mirror)
			)
		)
		(property "Device Type" "RESISTOR-G155-13300-01,330OHM,A"
			(at -0.008382 1.210564 0)
			(unlocked yes)
			(layer "B.Fab")
			(hide yes)
			(effects
				(font
					(size 0.7874 0.5842)
					(thickness 0.1524)
				)
				(justify mirror)
			)
		)
		(property "User Part Number" "PARTNUM*"
			(at -0.02032 4.024884 0)
			(unlocked yes)
			(layer "Cmts.User")
			(hide yes)
			(effects
				(font
					(size 0.7874 0.5842)
					(thickness 0.1524)
				)
				(justify mirror)
			)
		)
		(property "Tolerance" "TOL*"
			(at -0.044704 3.05435 0)
			(unlocked yes)
			(layer "Cmts.User")
			(hide yes)
			(effects
				(font
					(size 0.7874 0.5842)
					(thickness 0.1524)
				)
				(justify mirror)
			)
		)
		(duplicate_pad_numbers_are_jumpers no)
		(fp_line
			(start -1.143 -0.5588)
			(end 1.143 -0.5588)
			(stroke
				(width 0.1)
				(type default)
			)
			(layer "B.SilkS")
		)
		(fp_line
			(start -1.143 0.5588)
			(end -1.143 -0.5588)
			(stroke
				(width 0.1)
				(type default)
			)
			(layer "B.SilkS")
		)
		(fp_line
			(start 1.143 -0.5588)
			(end 1.143 0.5588)
			(stroke
				(width 0.1)
				(type default)
			)
			(layer "B.SilkS")
		)
		(fp_line
			(start 1.143 0.5588)
			(end -1.143 0.5588)
			(stroke
				(width 0.1)
				(type default)
			)
			(layer "B.SilkS")
		)
		(fp_rect
			(start -1.143 0.5588)
			(end 1.143 -0.5588)
			(stroke
				(width 0)
				(type default)
			)
			(fill no)
			(layer "B.CrtYd")
		)
		(fp_line
			(start -0.508 -0.3048)
			(end 0.508 -0.3048)
			(stroke
				(width 0.1)
				(type default)
			)
			(layer "B.Fab")
		)
		(fp_line
			(start -0.508 0.3048)
			(end -0.508 -0.3048)
			(stroke
				(width 0.1)
				(type default)
			)
			(layer "B.Fab")
		)
		(fp_line
			(start 0.508 -0.3048)
			(end 0.508 0.3048)
			(stroke
				(width 0.1)
				(type default)
			)
			(layer "B.Fab")
		)
		(fp_line
			(start 0.508 0.3048)
			(end -0.508 0.3048)
			(stroke
				(width 0.1)
				(type default)
			)
			(layer "B.Fab")
		)
		(pad "1" smd rect
			(at 0.5334 0 180)
			(size 0.7112 0.6096)
			(layers "B.Cu" "B.Mask" "B.Paste")
			(net "XP1R8V_FPGA_PG")
		)
		(pad "2" smd rect
			(at -0.5334 0 180)
			(size 0.7112 0.6096)
			(layers "B.Cu" "B.Mask" "B.Paste")
			(net "XP3R3V_FPGA_EN_R")
		)
		(zone
			(layer "B.Cu")
			(hatch none 0.5)
			(connect_pads
				(clearance 0)
			)
			(min_thickness 0.25)
			(keepout
				(tracks allowed)
				(vias not_allowed)
				(pads allowed)
				(copperpour not_allowed)
				(footprints allowed)
			)
			(placement
				(enabled no)
				(sheetname "")
			)
			(fill
				(thermal_gap 0.5)
				(thermal_bridge_width 0.5)
				(island_removal_mode 0)
			)
			(polygon
				(pts
					(xy 115.3668 -74.4982) (xy 115.5192 -74.4982) (xy 115.5192 -75.1078) (xy 115.3668 -75.1078)
				)
			)
		)
	)
	(footprint ""
		(layer "B.Cu")
		(at 112.776 -61.976 -90)
		(property "Reference" "R220"
			(at -3.302 0.03937 270)
			(unlocked yes)
			(layer "B.SilkS")
			(effects
				(font
					(size 0.7874 0.5842)
					(thickness 0.1524)
				)
				(justify mirror)
			)
		)
		(property "Value" "VAL*"
			(at -0.02032 2.13233 270)
			(unlocked yes)
			(layer "B.Fab")
			(hide yes)
			(effects
				(font
					(size 0.7874 0.5842)
					(thickness 0.1524)
				)
				(justify mirror)
			)
		)
		(property "Device Type" "RESISTOR-G155-11001-01,1KOHM,1%"
			(at -0.008382 1.210564 270)
			(unlocked yes)
			(layer "B.Fab")
			(hide yes)
			(effects
				(font
					(size 0.7874 0.5842)
					(thickness 0.1524)
				)
				(justify mirror)
			)
		)
		(property "User Part Number" "PARTNUM*"
			(at -0.02032 4.024884 270)
			(unlocked yes)
			(layer "Cmts.User")
			(hide yes)
			(effects
				(font
					(size 0.7874 0.5842)
					(thickness 0.1524)
				)
				(justify mirror)
			)
		)
		(property "Tolerance" "TOL*"
			(at -0.044704 3.05435 270)
			(unlocked yes)
			(layer "Cmts.User")
			(hide yes)
			(effects
				(font
					(size 0.7874 0.5842)
					(thickness 0.1524)
				)
				(justify mirror)
			)
		)
		(duplicate_pad_numbers_are_jumpers no)
		(fp_line
			(start -1.143 0.5588)
			(end -1.143 -0.5588)
			(stroke
				(width 0.1)
				(type default)
			)
			(layer "B.SilkS")
		)
		(fp_line
			(start 1.143 0.5588)
			(end -1.143 0.5588)
			(stroke
				(width 0.1)
				(type default)
			)
			(layer "B.SilkS")
		)
		(fp_line
			(start -1.143 -0.5588)
			(end 1.143 -0.5588)
			(stroke
				(width 0.1)
				(type default)
			)
			(layer "B.SilkS")
		)
		(fp_line
			(start 1.143 -0.5588)
			(end 1.143 0.5588)
			(stroke
				(width 0.1)
				(type default)
			)
			(layer "B.SilkS")
		)
		(fp_rect
			(start 1.143 0.5588)
			(end -1.143 -0.5588)
			(stroke
				(width 0)
				(type default)
			)
			(fill no)
			(layer "B.CrtYd")
		)
		(fp_line
			(start -0.508 0.3048)
			(end -0.508 -0.3048)
			(stroke
				(width 0.1)
				(type default)
			)
			(layer "B.Fab")
		)
		(fp_line
			(start 0.508 0.3048)
			(end -0.508 0.3048)
			(stroke
				(width 0.1)
				(type default)
			)
			(layer "B.Fab")
		)
		(fp_line
			(start -0.508 -0.3048)
			(end 0.508 -0.3048)
			(stroke
				(width 0.1)
				(type default)
			)
			(layer "B.Fab")
		)
		(fp_line
			(start 0.508 -0.3048)
			(end 0.508 0.3048)
			(stroke
				(width 0.1)
				(type default)
			)
			(layer "B.Fab")
		)
		(pad "1" smd rect
			(at 0.5334 0 90)
			(size 0.7112 0.6096)
			(layers "B.Cu" "B.Mask" "B.Paste")
			(net "FPGA_BRD_REV0")
		)
		(pad "2" smd rect
			(at -0.5334 0 90)
			(size 0.7112 0.6096)
			(layers "B.Cu" "B.Mask" "B.Paste")
			(net "SG")
		)
		(zone
			(layer "B.Cu")
			(hatch none 0.5)
			(connect_pads
				(clearance 0)
			)
			(min_thickness 0.25)
			(keepout
				(tracks allowed)
				(vias not_allowed)
				(pads allowed)
				(copperpour not_allowed)
				(footprints allowed)
			)
			(placement
				(enabled no)
				(sheetname "")
			)
			(fill
				(thermal_gap 0.5)
				(thermal_bridge_width 0.5)
				(island_removal_mode 0)
			)
			(polygon
				(pts
					(xy 112.4712 -61.8998) (xy 113.0808 -61.8998) (xy 113.0808 -62.0522) (xy 112.4712 -62.0522)
				)
			)
		)
	)
	(footprint ""
		(layer "B.Cu")
		(at 88.519 -82.169 180)
		(property "Reference" "R206"
			(at -0.254 5.67563 0)
			(unlocked yes)
			(layer "B.SilkS")
			(effects
				(font
					(size 0.7874 0.5842)
					(thickness 0.1524)
				)
				(justify mirror)
			)
		)
		(property "Value" "VAL*"
			(at -0.02032 2.13233 180)
			(unlocked yes)
			(layer "B.Fab")
			(hide yes)
			(effects
				(font
					(size 0.7874 0.5842)
					(thickness 0.1524)
				)
				(justify mirror)
			)
		)
		(property "Device Type" "RESISTOR-G155-133R0-01,33OHM,1%"
			(at -0.008382 1.210564 180)
			(unlocked yes)
			(layer "B.Fab")
			(hide yes)
			(effects
				(font
					(size 0.7874 0.5842)
					(thickness 0.1524)
				)
				(justify mirror)
			)
		)
		(property "User Part Number" "PARTNUM*"
			(at -0.02032 4.024884 180)
			(unlocked yes)
			(layer "Cmts.User")
			(hide yes)
			(effects
				(font
					(size 0.7874 0.5842)
					(thickness 0.1524)
				)
				(justify mirror)
			)
		)
		(property "Tolerance" "TOL*"
			(at -0.044704 3.05435 180)
			(unlocked yes)
			(layer "Cmts.User")
			(hide yes)
			(effects
				(font
					(size 0.7874 0.5842)
					(thickness 0.1524)
				)
				(justify mirror)
			)
		)
		(duplicate_pad_numbers_are_jumpers no)
		(fp_line
			(start 1.143 0.5588)
			(end -1.143 0.5588)
			(stroke
				(width 0.1)
				(type default)
			)
			(layer "B.SilkS")
		)
		(fp_line
			(start 1.143 -0.5588)
			(end 1.143 0.5588)
			(stroke
				(width 0.1)
				(type default)
			)
			(layer "B.SilkS")
		)
		(fp_line
			(start -1.143 0.5588)
			(end -1.143 -0.5588)
			(stroke
				(width 0.1)
				(type default)
			)
			(layer "B.SilkS")
		)
		(fp_line
			(start -1.143 -0.5588)
			(end 1.143 -0.5588)
			(stroke
				(width 0.1)
				(type default)
			)
			(layer "B.SilkS")
		)
		(fp_rect
			(start 1.143 -0.5588)
			(end -1.143 0.5588)
			(stroke
				(width 0)
				(type default)
			)
			(fill no)
			(layer "B.CrtYd")
		)
		(fp_line
			(start 0.508 0.3048)
			(end -0.508 0.3048)
			(stroke
				(width 0.1)
				(type default)
			)
			(layer "B.Fab")
		)
		(fp_line
			(start 0.508 -0.3048)
			(end 0.508 0.3048)
			(stroke
				(width 0.1)
				(type default)
			)
			(layer "B.Fab")
		)
		(fp_line
			(start -0.508 0.3048)
			(end -0.508 -0.3048)
			(stroke
				(width 0.1)
				(type default)
			)
			(layer "B.Fab")
		)
		(fp_line
			(start -0.508 -0.3048)
			(end 0.508 -0.3048)
			(stroke
				(width 0.1)
				(type default)
			)
			(layer "B.Fab")
		)
		(pad "1" smd rect
			(at 0.5334 0)
			(size 0.7112 0.6096)
			(layers "B.Cu" "B.Mask" "B.Paste")
			(net "UNNAMED_127_MT25QL128ABA1ESES_2")
		)
		(pad "2" smd rect
			(at -0.5334 0)
			(size 0.7112 0.6096)
			(layers "B.Cu" "B.Mask" "B.Paste")
			(net "FLASH_DQ3")
		)
		(zone
			(layer "B.Cu")
			(hatch none 0.5)
			(connect_pads
				(clearance 0)
			)
			(min_thickness 0.25)
			(keepout
				(tracks allowed)
				(vias not_allowed)
				(pads allowed)
				(copperpour not_allowed)
				(footprints allowed)
			)
			(placement
				(enabled no)
				(sheetname "")
			)
			(fill
				(thermal_gap 0.5)
				(thermal_bridge_width 0.5)
				(island_removal_mode 0)
			)
			(polygon
				(pts
					(xy 88.4428 -81.8642) (xy 88.5952 -81.8642) (xy 88.5952 -82.4738) (xy 88.4428 -82.4738)
				)
			)
		)
	)
	(footprint ""
		(layer "B.Cu")
		(at 106.9086 -64.2874 90)
		(property "Reference" "R326"
			(at 3.5306 -0.14097 270)
			(unlocked yes)
			(layer "B.SilkS")
			(effects
				(font
					(size 0.7874 0.5842)
					(thickness 0.1524)
				)
				(justify mirror)
			)
		)
		(property "Value" "VAL*"
			(at -0.02032 2.13233 90)
			(unlocked yes)
			(layer "B.Fab")
			(hide yes)
			(effects
				(font
					(size 0.7874 0.5842)
					(thickness 0.1524)
				)
				(justify mirror)
			)
		)
		(property "Tolerance" "TOL*"
			(at -0.044704 3.05435 90)
			(unlocked yes)
			(layer "Cmts.User")
			(hide yes)
			(effects
				(font
					(size 0.7874 0.5842)
					(thickness 0.1524)
				)
				(justify mirror)
			)
		)
		(property "User Part Number" "PARTNUM*"
			(at -0.02032 4.024884 90)
			(unlocked yes)
			(layer "Cmts.User")
			(hide yes)
			(effects
				(font
					(size 0.7874 0.5842)
					(thickness 0.1524)
				)
				(justify mirror)
			)
		)
		(property "Device Type" "RESISTOR-G155-14701-01,4.7KOHMA"
			(at -0.008382 1.210564 90)
			(unlocked yes)
			(layer "B.Fab")
			(hide yes)
			(effects
				(font
					(size 0.7874 0.5842)
					(thickness 0.1524)
				)
				(justify mirror)
			)
		)
		(duplicate_pad_numbers_are_jumpers no)
		(fp_line
			(start 1.143 -0.5588)
			(end 1.143 0.5588)
			(stroke
				(width 0.1)
				(type default)
			)
			(layer "B.SilkS")
		)
		(fp_line
			(start -1.143 -0.5588)
			(end 1.143 -0.5588)
			(stroke
				(width 0.1)
				(type default)
			)
			(layer "B.SilkS")
		)
		(fp_line
			(start 1.143 0.5588)
			(end -1.143 0.5588)
			(stroke
				(width 0.1)
				(type default)
			)
			(layer "B.SilkS")
		)
		(fp_line
			(start -1.143 0.5588)
			(end -1.143 -0.5588)
			(stroke
				(width 0.1)
				(type default)
			)
			(layer "B.SilkS")
		)
		(fp_poly
			(pts
				(xy 1.143 0.5588) (xy -1.143 0.5588) (xy -1.143 -0.5588) (xy 1.143 -0.5588)
			)
			(stroke
				(width 0)
				(type default)
			)
			(fill no)
			(layer "B.CrtYd")
		)
		(fp_line
			(start 0.508 -0.3048)
			(end 0.508 0.3048)
			(stroke
				(width 0.1)
				(type default)
			)
			(layer "B.Fab")
		)
		(fp_line
			(start -0.508 -0.3048)
			(end 0.508 -0.3048)
			(stroke
				(width 0.1)
				(type default)
			)
			(layer "B.Fab")
		)
		(fp_line
			(start 0.508 0.3048)
			(end -0.508 0.3048)
			(stroke
				(width 0.1)
				(type default)
			)
			(layer "B.Fab")
		)
		(fp_line
			(start -0.508 0.3048)
			(end -0.508 -0.3048)
			(stroke
				(width 0.1)
				(type default)
			)
			(layer "B.Fab")
		)
		(pad "1" smd rect
			(at 0.5334 0 270)
			(size 0.7112 0.6096)
			(layers "B.Cu" "B.Mask" "B.Paste")
			(net "SG")
		)
		(pad "2" smd rect
			(at -0.5334 0 270)
			(size 0.7112 0.6096)
			(layers "B.Cu" "B.Mask" "B.Paste")
			(net "FPGA_IO_6")
		)
		(zone
			(layer "B.Cu")
			(hatch none 0.5)
			(connect_pads
				(clearance 0)
			)
			(min_thickness 0.25)
			(keepout
				(tracks not_allowed)
				(vias allowed)
				(pads allowed)
				(copperpour not_allowed)
				(footprints allowed)
			)
			(placement
				(enabled no)
				(sheetname "")
			)
			(fill
				(thermal_gap 0.5)
				(thermal_bridge_width 0.5)
				(island_removal_mode 0)
			)
			(polygon
				(pts
					(xy 107.2134 -64.3636) (xy 106.6038 -64.3636) (xy 106.6038 -64.2112) (xy 107.2134 -64.2112)
				)
			)
		)
		(zone
			(layer "B.Cu")
			(hatch none 0.5)
			(connect_pads
				(clearance 0)
			)
			(min_thickness 0.25)
			(keepout
				(tracks allowed)
				(vias not_allowed)
				(pads allowed)
				(copperpour not_allowed)
				(footprints allowed)
			)
			(placement
				(enabled no)
				(sheetname "")
			)
			(fill
				(thermal_gap 0.5)
				(thermal_bridge_width 0.5)
				(island_removal_mode 0)
			)
			(polygon
				(pts
					(xy 107.2134 -64.3636) (xy 106.6038 -64.3636) (xy 106.6038 -64.2112) (xy 107.2134 -64.2112)
				)
			)
		)
	)
	(footprint ""
		(layer "B.Cu")
		(at 160.02 -50.513996 90)
		(property "Reference" "R101"
			(at -7.874 1.35763 270)
			(unlocked yes)
			(layer "B.SilkS")
			(effects
				(font
					(size 0.7874 0.5842)
					(thickness 0.1524)
				)
				(justify mirror)
			)
		)
		(property "Value" "VAL*"
			(at -0.02032 2.13233 90)
			(unlocked yes)
			(layer "B.Fab")
			(hide yes)
			(effects
				(font
					(size 0.7874 0.5842)
					(thickness 0.1524)
				)
				(justify mirror)
			)
		)
		(property "Tolerance" "TOL*"
			(at -0.044704 3.05435 90)
			(unlocked yes)
			(layer "Cmts.User")
			(hide yes)
			(effects
				(font
					(size 0.7874 0.5842)
					(thickness 0.1524)
				)
				(justify mirror)
			)
		)
		(property "User Part Number" "PARTNUM*"
			(at -0.02032 4.024884 90)
			(unlocked yes)
			(layer "Cmts.User")
			(hide yes)
			(effects
				(font
					(size 0.7874 0.5842)
					(thickness 0.1524)
				)
				(justify mirror)
			)
		)
		(property "Device Type" "RESISTOR-G155-11001-01,1KOHM,1%"
			(at -0.008382 1.210564 90)
			(unlocked yes)
			(layer "B.Fab")
			(hide yes)
			(effects
				(font
					(size 0.7874 0.5842)
					(thickness 0.1524)
				)
				(justify mirror)
			)
		)
		(duplicate_pad_numbers_are_jumpers no)
		(fp_line
			(start 1.143 -0.5588)
			(end 1.143 0.5588)
			(stroke
				(width 0.1)
				(type default)
			)
			(layer "B.SilkS")
		)
		(fp_line
			(start -1.143 -0.5588)
			(end 1.143 -0.5588)
			(stroke
				(width 0.1)
				(type default)
			)
			(layer "B.SilkS")
		)
		(fp_line
			(start 1.143 0.5588)
			(end -1.143 0.5588)
			(stroke
				(width 0.1)
				(type default)
			)
			(layer "B.SilkS")
		)
		(fp_line
			(start -1.143 0.5588)
			(end -1.143 -0.5588)
			(stroke
				(width 0.1)
				(type default)
			)
			(layer "B.SilkS")
		)
		(fp_rect
			(start 1.143 0.5588)
			(end -1.143 -0.5588)
			(stroke
				(width 0)
				(type default)
			)
			(fill no)
			(layer "B.CrtYd")
		)
		(fp_line
			(start 0.508 -0.3048)
			(end 0.508 0.3048)
			(stroke
				(width 0.1)
				(type default)
			)
			(layer "B.Fab")
		)
		(fp_line
			(start -0.508 -0.3048)
			(end 0.508 -0.3048)
			(stroke
				(width 0.1)
				(type default)
			)
			(layer "B.Fab")
		)
		(fp_line
			(start 0.508 0.3048)
			(end -0.508 0.3048)
			(stroke
				(width 0.1)
				(type default)
			)
			(layer "B.Fab")
		)
		(fp_line
			(start -0.508 0.3048)
			(end -0.508 -0.3048)
			(stroke
				(width 0.1)
				(type default)
			)
			(layer "B.Fab")
		)
		(pad "1" smd rect
			(at 0.5334 0 270)
			(size 0.7112 0.6096)
			(layers "B.Cu" "B.Mask" "B.Paste")
			(net "XP5R0V_USB_CONN")
		)
		(pad "2" smd rect
			(at -0.5334 0 270)
			(size 0.7112 0.6096)
			(layers "B.Cu" "B.Mask" "B.Paste")
			(net "XP5R0V_USB_CONN_DET")
		)
		(zone
			(layer "B.Cu")
			(hatch none 0.5)
			(connect_pads
				(clearance 0)
			)
			(min_thickness 0.25)
			(keepout
				(tracks allowed)
				(vias not_allowed)
				(pads allowed)
				(copperpour not_allowed)
				(footprints allowed)
			)
			(placement
				(enabled no)
				(sheetname "")
			)
			(fill
				(thermal_gap 0.5)
				(thermal_bridge_width 0.5)
				(island_removal_mode 0)
			)
			(polygon
				(pts
					(xy 160.3248 -50.590196) (xy 159.7152 -50.590196) (xy 159.7152 -50.437796) (xy 160.3248 -50.437796)
				)
			)
		)
	)
	(footprint ""
		(layer "B.Cu")
		(at 53.975 -85.344)
		(property "Reference" "R444"
			(at 0.127 -5.92963 0)
			(unlocked yes)
			(layer "B.SilkS")
			(effects
				(font
					(size 0.7874 0.5842)
					(thickness 0.1524)
				)
				(justify mirror)
			)
		)
		(property "Value" "VAL*"
			(at -0.02032 2.13233 0)
			(unlocked yes)
			(layer "B.Fab")
			(hide yes)
			(effects
				(font
					(size 0.7874 0.5842)
					(thickness 0.1524)
				)
				(justify mirror)
			)
		)
		(property "Tolerance" "TOL*"
			(at -0.044704 3.05435 0)
			(unlocked yes)
			(layer "Cmts.User")
			(hide yes)
			(effects
				(font
					(size 0.7874 0.5842)
					(thickness 0.1524)
				)
				(justify mirror)
			)
		)
		(property "User Part Number" "PARTNUM*"
			(at -0.02032 4.024884 0)
			(unlocked yes)
			(layer "Cmts.User")
			(hide yes)
			(effects
				(font
					(size 0.7874 0.5842)
					(thickness 0.1524)
				)
				(justify mirror)
			)
		)
		(property "Device Type" "RESISTOR-G155-11002-01,10KOHM,A"
			(at -0.008382 1.210564 0)
			(unlocked yes)
			(layer "B.Fab")
			(hide yes)
			(effects
				(font
					(size 0.7874 0.5842)
					(thickness 0.1524)
				)
				(justify mirror)
			)
		)
		(duplicate_pad_numbers_are_jumpers no)
		(fp_line
			(start -1.143 -0.5588)
			(end 1.143 -0.5588)
			(stroke
				(width 0.1)
				(type default)
			)
			(layer "B.SilkS")
		)
		(fp_line
			(start -1.143 0.5588)
			(end -1.143 -0.5588)
			(stroke
				(width 0.1)
				(type default)
			)
			(layer "B.SilkS")
		)
		(fp_line
			(start 1.143 -0.5588)
			(end 1.143 0.5588)
			(stroke
				(width 0.1)
				(type default)
			)
			(layer "B.SilkS")
		)
		(fp_line
			(start 1.143 0.5588)
			(end -1.143 0.5588)
			(stroke
				(width 0.1)
				(type default)
			)
			(layer "B.SilkS")
		)
		(fp_poly
			(pts
				(xy 1.143 0.5588) (xy -1.143 0.5588) (xy -1.143 -0.5588) (xy 1.143 -0.5588)
			)
			(stroke
				(width 0)
				(type default)
			)
			(fill no)
			(layer "B.CrtYd")
		)
		(fp_line
			(start -0.508 -0.3048)
			(end 0.508 -0.3048)
			(stroke
				(width 0.1)
				(type default)
			)
			(layer "B.Fab")
		)
		(fp_line
			(start -0.508 0.3048)
			(end -0.508 -0.3048)
			(stroke
				(width 0.1)
				(type default)
			)
			(layer "B.Fab")
		)
		(fp_line
			(start 0.508 -0.3048)
			(end 0.508 0.3048)
			(stroke
				(width 0.1)
				(type default)
			)
			(layer "B.Fab")
		)
		(fp_line
			(start 0.508 0.3048)
			(end -0.508 0.3048)
			(stroke
				(width 0.1)
				(type default)
			)
			(layer "B.Fab")
		)
		(pad "1" smd rect
			(at 0.5334 0 180)
			(size 0.7112 0.6096)
			(layers "B.Cu" "B.Mask" "B.Paste")
			(net "XP3R3V_FT4232")
		)
		(pad "2" smd rect
			(at -0.5334 0 180)
			(size 0.7112 0.6096)
			(layers "B.Cu" "B.Mask" "B.Paste")
			(net "FTDI_EE_DO")
		)
		(zone
			(layer "B.Cu")
			(hatch none 0.5)
			(connect_pads
				(clearance 0)
			)
			(min_thickness 0.25)
			(keepout
				(tracks allowed)
				(vias not_allowed)
				(pads allowed)
				(copperpour not_allowed)
				(footprints allowed)
			)
			(placement
				(enabled no)
				(sheetname "")
			)
			(fill
				(thermal_gap 0.5)
				(thermal_bridge_width 0.5)
				(island_removal_mode 0)
			)
			(polygon
				(pts
					(xy 54.0512 -85.0392) (xy 54.0512 -85.6488) (xy 53.8988 -85.6488) (xy 53.8988 -85.0392)
				)
			)
		)
		(zone
			(layer "B.Cu")
			(hatch none 0.5)
			(connect_pads
				(clearance 0)
			)
			(min_thickness 0.25)
			(keepout
				(tracks not_allowed)
				(vias allowed)
				(pads allowed)
				(copperpour not_allowed)
				(footprints allowed)
			)
			(placement
				(enabled no)
				(sheetname "")
			)
			(fill
				(thermal_gap 0.5)
				(thermal_bridge_width 0.5)
				(island_removal_mode 0)
			)
			(polygon
				(pts
					(xy 54.0512 -85.0392) (xy 54.0512 -85.6488) (xy 53.8988 -85.6488) (xy 53.8988 -85.0392)
				)
			)
		)
	)
	(footprint ""
		(layer "B.Cu")
		(at 96.8756 -78.5368 180)
		(property "Reference" "R177"
			(at 0.3556 1.30683 0)
			(unlocked yes)
			(layer "B.SilkS")
			(effects
				(font
					(size 0.7874 0.5842)
					(thickness 0.1524)
				)
				(justify mirror)
			)
		)
		(property "Value" "VAL*"
			(at -0.0508 2.245106 180)
			(unlocked yes)
			(layer "B.Fab")
			(hide yes)
			(effects
				(font
					(size 0.7874 0.5842)
					(thickness 0.1524)
				)
				(justify mirror)
			)
		)
		(property "Tolerance" "TOL*"
			(at -0.0508 3.261106 180)
			(unlocked yes)
			(layer "Cmts.User")
			(hide yes)
			(effects
				(font
					(size 0.7874 0.5842)
					(thickness 0.1524)
				)
				(justify mirror)
			)
		)
		(property "Device Type" "RESISTOR-G152-00055-01,1.13KOHA"
			(at -0.0762 1.254506 180)
			(unlocked yes)
			(layer "B.Fab")
			(hide yes)
			(effects
				(font
					(size 0.7874 0.5842)
					(thickness 0.1524)
				)
				(justify mirror)
			)
		)
		(property "User Part Number" "PARTNUM*"
			(at -0.0762 4.302506 180)
			(unlocked yes)
			(layer "Cmts.User")
			(hide yes)
			(effects
				(font
					(size 0.7874 0.5842)
					(thickness 0.1524)
				)
				(justify mirror)
			)
		)
		(duplicate_pad_numbers_are_jumpers no)
		(fp_line
			(start 1.143 0.5588)
			(end -1.143 0.5588)
			(stroke
				(width 0.1)
				(type default)
			)
			(layer "B.SilkS")
		)
		(fp_line
			(start 1.143 -0.5588)
			(end 1.143 0.5588)
			(stroke
				(width 0.1)
				(type default)
			)
			(layer "B.SilkS")
		)
		(fp_line
			(start -1.143 0.5588)
			(end -1.143 -0.5588)
			(stroke
				(width 0.1)
				(type default)
			)
			(layer "B.SilkS")
		)
		(fp_line
			(start -1.143 -0.5588)
			(end 1.143 -0.5588)
			(stroke
				(width 0.1)
				(type default)
			)
			(layer "B.SilkS")
		)
		(fp_rect
			(start 1.143 0.5588)
			(end -1.143 -0.5588)
			(stroke
				(width 0)
				(type default)
			)
			(fill no)
			(layer "B.CrtYd")
		)
		(fp_line
			(start 0.508 0.3048)
			(end -0.508 0.3048)
			(stroke
				(width 0.1)
				(type default)
			)
			(layer "B.Fab")
		)
		(fp_line
			(start 0.508 -0.3048)
			(end 0.508 0.3048)
			(stroke
				(width 0.1)
				(type default)
			)
			(layer "B.Fab")
		)
		(fp_line
			(start -0.508 0.3048)
			(end -0.508 -0.3048)
			(stroke
				(width 0.1)
				(type default)
			)
			(layer "B.Fab")
		)
		(fp_line
			(start -0.508 -0.3048)
			(end 0.508 -0.3048)
			(stroke
				(width 0.1)
				(type default)
			)
			(layer "B.Fab")
		)
		(pad "1" smd rect
			(at 0.5334 0)
			(size 0.7112 0.6096)
			(layers "B.Cu" "B.Mask" "B.Paste")
			(net "XP1R2V_VIN")
		)
		(pad "2" smd rect
			(at -0.5334 0)
			(size 0.7112 0.6096)
			(layers "B.Cu" "B.Mask" "B.Paste")
			(net "XP1R2V_EN_R")
		)
		(zone
			(layer "B.Cu")
			(hatch none 0.5)
			(connect_pads
				(clearance 0)
			)
			(min_thickness 0.25)
			(keepout
				(tracks allowed)
				(vias not_allowed)
				(pads allowed)
				(copperpour not_allowed)
				(footprints allowed)
			)
			(placement
				(enabled no)
				(sheetname "")
			)
			(fill
				(thermal_gap 0.5)
				(thermal_bridge_width 0.5)
				(island_removal_mode 0)
			)
			(polygon
				(pts
					(xy 96.7994 -78.8416) (xy 96.7994 -78.232) (xy 96.9518 -78.232) (xy 96.9518 -78.8416)
				)
			)
		)
	)
	(footprint ""
		(layer "B.Cu")
		(at 103.9622 -64.2874 90)
		(property "Reference" "R309"
			(at 3.5306 -0.11557 270)
			(unlocked yes)
			(layer "B.SilkS")
			(effects
				(font
					(size 0.7874 0.5842)
					(thickness 0.1524)
				)
				(justify mirror)
			)
		)
		(property "Value" "VAL*"
			(at -0.02032 2.13233 90)
			(unlocked yes)
			(layer "B.Fab")
			(hide yes)
			(effects
				(font
					(size 0.7874 0.5842)
					(thickness 0.1524)
				)
				(justify mirror)
			)
		)
		(property "Tolerance" "TOL*"
			(at -0.044704 3.05435 90)
			(unlocked yes)
			(layer "Cmts.User")
			(hide yes)
			(effects
				(font
					(size 0.7874 0.5842)
					(thickness 0.1524)
				)
				(justify mirror)
			)
		)
		(property "User Part Number" "PARTNUM*"
			(at -0.02032 4.024884 90)
			(unlocked yes)
			(layer "Cmts.User")
			(hide yes)
			(effects
				(font
					(size 0.7874 0.5842)
					(thickness 0.1524)
				)
				(justify mirror)
			)
		)
		(property "Device Type" "RESISTOR-G155-14701-01,4.7KOHMA"
			(at -0.008382 1.210564 90)
			(unlocked yes)
			(layer "B.Fab")
			(hide yes)
			(effects
				(font
					(size 0.7874 0.5842)
					(thickness 0.1524)
				)
				(justify mirror)
			)
		)
		(duplicate_pad_numbers_are_jumpers no)
		(fp_line
			(start 1.143 -0.5588)
			(end 1.143 0.5588)
			(stroke
				(width 0.1)
				(type default)
			)
			(layer "B.SilkS")
		)
		(fp_line
			(start -1.143 -0.5588)
			(end 1.143 -0.5588)
			(stroke
				(width 0.1)
				(type default)
			)
			(layer "B.SilkS")
		)
		(fp_line
			(start 1.143 0.5588)
			(end -1.143 0.5588)
			(stroke
				(width 0.1)
				(type default)
			)
			(layer "B.SilkS")
		)
		(fp_line
			(start -1.143 0.5588)
			(end -1.143 -0.5588)
			(stroke
				(width 0.1)
				(type default)
			)
			(layer "B.SilkS")
		)
		(fp_poly
			(pts
				(xy 1.143 0.5588) (xy -1.143 0.5588) (xy -1.143 -0.5588) (xy 1.143 -0.5588)
			)
			(stroke
				(width 0)
				(type default)
			)
			(fill no)
			(layer "B.CrtYd")
		)
		(fp_line
			(start 0.508 -0.3048)
			(end 0.508 0.3048)
			(stroke
				(width 0.1)
				(type default)
			)
			(layer "B.Fab")
		)
		(fp_line
			(start -0.508 -0.3048)
			(end 0.508 -0.3048)
			(stroke
				(width 0.1)
				(type default)
			)
			(layer "B.Fab")
		)
		(fp_line
			(start 0.508 0.3048)
			(end -0.508 0.3048)
			(stroke
				(width 0.1)
				(type default)
			)
			(layer "B.Fab")
		)
		(fp_line
			(start -0.508 0.3048)
			(end -0.508 -0.3048)
			(stroke
				(width 0.1)
				(type default)
			)
			(layer "B.Fab")
		)
		(pad "1" smd rect
			(at 0.5334 0 270)
			(size 0.7112 0.6096)
			(layers "B.Cu" "B.Mask" "B.Paste")
			(net "SG")
		)
		(pad "2" smd rect
			(at -0.5334 0 270)
			(size 0.7112 0.6096)
			(layers "B.Cu" "B.Mask" "B.Paste")
			(net "FPGA_IO_5")
		)
		(zone
			(layer "B.Cu")
			(hatch none 0.5)
			(connect_pads
				(clearance 0)
			)
			(min_thickness 0.25)
			(keepout
				(tracks not_allowed)
				(vias allowed)
				(pads allowed)
				(copperpour not_allowed)
				(footprints allowed)
			)
			(placement
				(enabled no)
				(sheetname "")
			)
			(fill
				(thermal_gap 0.5)
				(thermal_bridge_width 0.5)
				(island_removal_mode 0)
			)
			(polygon
				(pts
					(xy 104.267 -64.3636) (xy 103.6574 -64.3636) (xy 103.6574 -64.2112) (xy 104.267 -64.2112)
				)
			)
		)
		(zone
			(layer "B.Cu")
			(hatch none 0.5)
			(connect_pads
				(clearance 0)
			)
			(min_thickness 0.25)
			(keepout
				(tracks allowed)
				(vias not_allowed)
				(pads allowed)
				(copperpour not_allowed)
				(footprints allowed)
			)
			(placement
				(enabled no)
				(sheetname "")
			)
			(fill
				(thermal_gap 0.5)
				(thermal_bridge_width 0.5)
				(island_removal_mode 0)
			)
			(polygon
				(pts
					(xy 104.267 -64.3636) (xy 103.6574 -64.3636) (xy 103.6574 -64.2112) (xy 104.267 -64.2112)
				)
			)
		)
	)
	(footprint ""
		(layer "B.Cu")
		(at 109.347 -42.418 90)
		(property "Reference" "C114"
			(at -1.905 -41.56075 270)
			(unlocked yes)
			(layer "B.SilkS")
			(effects
				(font
					(size 0.635 0.4064)
					(thickness 0.1524)
				)
				(justify mirror)
			)
		)
		(property "Value" "VAL*"
			(at -0.0762 2.067306 90)
			(unlocked yes)
			(layer "B.Fab")
			(hide yes)
			(effects
				(font
					(size 0.7874 0.5842)
					(thickness 0.1524)
				)
				(justify mirror)
			)
		)
		(property "Device Type" "CAPACITOR-G105-0B104-CK,0.1UF,A"
			(at -0.0508 1.127506 90)
			(unlocked yes)
			(layer "B.Fab")
			(hide yes)
			(effects
				(font
					(size 0.7874 0.5842)
					(thickness 0.1524)
				)
				(justify mirror)
			)
		)
		(property "User Part Number" "PARTNUM*"
			(at -0.1016 4.023106 90)
			(unlocked yes)
			(layer "Cmts.User")
			(hide yes)
			(effects
				(font
					(size 0.7874 0.5842)
					(thickness 0.1524)
				)
				(justify mirror)
			)
		)
		(property "Tolerance" "TOL*"
			(at -0.0762 3.032506 90)
			(unlocked yes)
			(layer "Cmts.User")
			(hide yes)
			(effects
				(font
					(size 0.7874 0.5842)
					(thickness 0.1524)
				)
				(justify mirror)
			)
		)
		(duplicate_pad_numbers_are_jumpers no)
		(fp_line
			(start 1.143 -0.5588)
			(end 1.143 0.5588)
			(stroke
				(width 0.1)
				(type default)
			)
			(layer "B.SilkS")
		)
		(fp_line
			(start -1.143 -0.5588)
			(end 1.143 -0.5588)
			(stroke
				(width 0.1)
				(type default)
			)
			(layer "B.SilkS")
		)
		(fp_line
			(start 1.143 0.5588)
			(end -1.143 0.5588)
			(stroke
				(width 0.1)
				(type default)
			)
			(layer "B.SilkS")
		)
		(fp_line
			(start -1.143 0.5588)
			(end -1.143 -0.5588)
			(stroke
				(width 0.1)
				(type default)
			)
			(layer "B.SilkS")
		)
		(fp_rect
			(start -1.143 -0.5588)
			(end 1.143 0.5588)
			(stroke
				(width 0)
				(type default)
			)
			(fill no)
			(layer "B.CrtYd")
		)
		(fp_line
			(start 0.508 -0.3048)
			(end 0.508 0.3048)
			(stroke
				(width 0.1)
				(type default)
			)
			(layer "B.Fab")
		)
		(fp_line
			(start -0.508 -0.3048)
			(end 0.508 -0.3048)
			(stroke
				(width 0.1)
				(type default)
			)
			(layer "B.Fab")
		)
		(fp_line
			(start 0.508 0.3048)
			(end -0.508 0.3048)
			(stroke
				(width 0.1)
				(type default)
			)
			(layer "B.Fab")
		)
		(fp_line
			(start -0.508 0.3048)
			(end -0.508 -0.3048)
			(stroke
				(width 0.1)
				(type default)
			)
			(layer "B.Fab")
		)
		(pad "1" smd rect
			(at 0.5334 0 270)
			(size 0.7112 0.6096)
			(layers "B.Cu" "B.Mask" "B.Paste")
			(net "XP1R0V_FPGA_VCCINT")
		)
		(pad "2" smd rect
			(at -0.5334 0 270)
			(size 0.7112 0.6096)
			(layers "B.Cu" "B.Mask" "B.Paste")
			(net "SG")
		)
		(zone
			(layer "B.Cu")
			(hatch none 0.5)
			(connect_pads
				(clearance 0)
			)
			(min_thickness 0.25)
			(keepout
				(tracks allowed)
				(vias not_allowed)
				(pads allowed)
				(copperpour not_allowed)
				(footprints allowed)
			)
			(placement
				(enabled no)
				(sheetname "")
			)
			(fill
				(thermal_gap 0.5)
				(thermal_bridge_width 0.5)
				(island_removal_mode 0)
			)
			(polygon
				(pts
					(xy 109.0422 -42.3418) (xy 109.6518 -42.3418) (xy 109.6518 -42.4942) (xy 109.0422 -42.4942)
				)
			)
		)
	)
	(footprint ""
		(layer "B.Cu")
		(at 129.159 -98.425 90)
		(property "Reference" "C73"
			(at -2.667 0.08763 270)
			(unlocked yes)
			(layer "B.SilkS")
			(effects
				(font
					(size 0.7874 0.5842)
					(thickness 0.1524)
				)
				(justify mirror)
			)
		)
		(property "Value" "VAL*"
			(at -0.0762 2.067306 90)
			(unlocked yes)
			(layer "B.Fab")
			(hide yes)
			(effects
				(font
					(size 0.7874 0.5842)
					(thickness 0.1524)
				)
				(justify mirror)
			)
		)
		(property "Device Type" "CAPACITOR-G105-0B104-EK,0.1UF,A"
			(at -0.0508 1.127506 90)
			(unlocked yes)
			(layer "B.Fab")
			(hide yes)
			(effects
				(font
					(size 0.7874 0.5842)
					(thickness 0.1524)
				)
				(justify mirror)
			)
		)
		(property "User Part Number" "PARTNUM*"
			(at -0.1016 4.023106 90)
			(unlocked yes)
			(layer "Cmts.User")
			(hide yes)
			(effects
				(font
					(size 0.7874 0.5842)
					(thickness 0.1524)
				)
				(justify mirror)
			)
		)
		(property "Tolerance" "TOL*"
			(at -0.0762 3.032506 90)
			(unlocked yes)
			(layer "Cmts.User")
			(hide yes)
			(effects
				(font
					(size 0.7874 0.5842)
					(thickness 0.1524)
				)
				(justify mirror)
			)
		)
		(duplicate_pad_numbers_are_jumpers no)
		(fp_line
			(start 1.143 -0.5588)
			(end 1.143 0.5588)
			(stroke
				(width 0.1)
				(type default)
			)
			(layer "B.SilkS")
		)
		(fp_line
			(start -1.143 -0.5588)
			(end 1.143 -0.5588)
			(stroke
				(width 0.1)
				(type default)
			)
			(layer "B.SilkS")
		)
		(fp_line
			(start 1.143 0.5588)
			(end -1.143 0.5588)
			(stroke
				(width 0.1)
				(type default)
			)
			(layer "B.SilkS")
		)
		(fp_line
			(start -1.143 0.5588)
			(end -1.143 -0.5588)
			(stroke
				(width 0.1)
				(type default)
			)
			(layer "B.SilkS")
		)
		(fp_rect
			(start -1.143 -0.5588)
			(end 1.143 0.5588)
			(stroke
				(width 0)
				(type default)
			)
			(fill no)
			(layer "B.CrtYd")
		)
		(fp_line
			(start 0.508 -0.3048)
			(end 0.508 0.3048)
			(stroke
				(width 0.1)
				(type default)
			)
			(layer "B.Fab")
		)
		(fp_line
			(start -0.508 -0.3048)
			(end 0.508 -0.3048)
			(stroke
				(width 0.1)
				(type default)
			)
			(layer "B.Fab")
		)
		(fp_line
			(start 0.508 0.3048)
			(end -0.508 0.3048)
			(stroke
				(width 0.1)
				(type default)
			)
			(layer "B.Fab")
		)
		(fp_line
			(start -0.508 0.3048)
			(end -0.508 -0.3048)
			(stroke
				(width 0.1)
				(type default)
			)
			(layer "B.Fab")
		)
		(pad "1" smd rect
			(at 0.5334 0 270)
			(size 0.7112 0.6096)
			(layers "B.Cu" "B.Mask" "B.Paste")
			(net "XP5R0V_VCC_ANT")
		)
		(pad "2" smd rect
			(at -0.5334 0 270)
			(size 0.7112 0.6096)
			(layers "B.Cu" "B.Mask" "B.Paste")
			(net "SG")
		)
		(zone
			(layer "B.Cu")
			(hatch none 0.5)
			(connect_pads
				(clearance 0)
			)
			(min_thickness 0.25)
			(keepout
				(tracks allowed)
				(vias not_allowed)
				(pads allowed)
				(copperpour not_allowed)
				(footprints allowed)
			)
			(placement
				(enabled no)
				(sheetname "")
			)
			(fill
				(thermal_gap 0.5)
				(thermal_bridge_width 0.5)
				(island_removal_mode 0)
			)
			(polygon
				(pts
					(xy 128.8542 -98.3488) (xy 129.4638 -98.3488) (xy 129.4638 -98.5012) (xy 128.8542 -98.5012)
				)
			)
		)
	)
	(footprint ""
		(layer "B.Cu")
		(at 88.138 -59.817 90)
		(property "Reference" "R168"
			(at 2.794 0.21463 270)
			(unlocked yes)
			(layer "B.SilkS")
			(effects
				(font
					(size 0.7874 0.5842)
					(thickness 0.1524)
				)
				(justify mirror)
			)
		)
		(property "Value" "VAL*"
			(at -0.02032 2.13233 90)
			(unlocked yes)
			(layer "B.Fab")
			(hide yes)
			(effects
				(font
					(size 0.7874 0.5842)
					(thickness 0.1524)
				)
				(justify mirror)
			)
		)
		(property "Tolerance" "TOL*"
			(at -0.044704 3.05435 90)
			(unlocked yes)
			(layer "Cmts.User")
			(hide yes)
			(effects
				(font
					(size 0.7874 0.5842)
					(thickness 0.1524)
				)
				(justify mirror)
			)
		)
		(property "User Part Number" "PARTNUM*"
			(at -0.02032 4.024884 90)
			(unlocked yes)
			(layer "Cmts.User")
			(hide yes)
			(effects
				(font
					(size 0.7874 0.5842)
					(thickness 0.1524)
				)
				(justify mirror)
			)
		)
		(property "Device Type" "RESISTOR-G155-11004-01,1MOHM,1%"
			(at -0.008382 1.210564 90)
			(unlocked yes)
			(layer "B.Fab")
			(hide yes)
			(effects
				(font
					(size 0.7874 0.5842)
					(thickness 0.1524)
				)
				(justify mirror)
			)
		)
		(duplicate_pad_numbers_are_jumpers no)
		(fp_line
			(start 1.143 -0.5588)
			(end 1.143 0.5588)
			(stroke
				(width 0.1)
				(type default)
			)
			(layer "B.SilkS")
		)
		(fp_line
			(start -1.143 -0.5588)
			(end 1.143 -0.5588)
			(stroke
				(width 0.1)
				(type default)
			)
			(layer "B.SilkS")
		)
		(fp_line
			(start 1.143 0.5588)
			(end -1.143 0.5588)
			(stroke
				(width 0.1)
				(type default)
			)
			(layer "B.SilkS")
		)
		(fp_line
			(start -1.143 0.5588)
			(end -1.143 -0.5588)
			(stroke
				(width 0.1)
				(type default)
			)
			(layer "B.SilkS")
		)
		(fp_rect
			(start -1.143 -0.5588)
			(end 1.143 0.5588)
			(stroke
				(width 0)
				(type default)
			)
			(fill no)
			(layer "B.CrtYd")
		)
		(fp_line
			(start 0.508 -0.3048)
			(end 0.508 0.3048)
			(stroke
				(width 0.1)
				(type default)
			)
			(layer "B.Fab")
		)
		(fp_line
			(start -0.508 -0.3048)
			(end 0.508 -0.3048)
			(stroke
				(width 0.1)
				(type default)
			)
			(layer "B.Fab")
		)
		(fp_line
			(start 0.508 0.3048)
			(end -0.508 0.3048)
			(stroke
				(width 0.1)
				(type default)
			)
			(layer "B.Fab")
		)
		(fp_line
			(start -0.508 0.3048)
			(end -0.508 -0.3048)
			(stroke
				(width 0.1)
				(type default)
			)
			(layer "B.Fab")
		)
		(pad "1" smd rect
			(at 0.5334 0 270)
			(size 0.7112 0.6096)
			(layers "B.Cu" "B.Mask" "B.Paste")
			(net "UNNAMED_9_CAPACITOR_I17_1")
		)
		(pad "2" smd rect
			(at -0.5334 0 270)
			(size 0.7112 0.6096)
			(layers "B.Cu" "B.Mask" "B.Paste")
			(net "UNNAMED_9_BNO080LGA28_I29_XOUT3")
		)
		(zone
			(layer "B.Cu")
			(hatch none 0.5)
			(connect_pads
				(clearance 0)
			)
			(min_thickness 0.25)
			(keepout
				(tracks allowed)
				(vias not_allowed)
				(pads allowed)
				(copperpour not_allowed)
				(footprints allowed)
			)
			(placement
				(enabled no)
				(sheetname "")
			)
			(fill
				(thermal_gap 0.5)
				(thermal_bridge_width 0.5)
				(island_removal_mode 0)
			)
			(polygon
				(pts
					(xy 87.8332 -59.7408) (xy 88.4428 -59.7408) (xy 88.4428 -59.8932) (xy 87.8332 -59.8932)
				)
			)
		)
	)
	(footprint ""
		(layer "B.Cu")
		(at 95.631 -26.924 180)
		(property "Reference" "C164"
			(at 0 1.73863 0)
			(unlocked yes)
			(layer "B.SilkS")
			(effects
				(font
					(size 0.7874 0.5842)
					(thickness 0.1524)
				)
				(justify mirror)
			)
		)
		(property "Value" "VAL*"
			(at -0.0762 3.134106 180)
			(unlocked yes)
			(layer "B.Fab")
			(hide yes)
			(effects
				(font
					(size 0.7874 0.5842)
					(thickness 0.1524)
				)
				(justify mirror)
			)
		)
		(property "Device Type" "CAPACITOR-G107-0F226-CM,22UF,2A"
			(at -0.0508 2.194306 180)
			(unlocked yes)
			(layer "B.Fab")
			(hide yes)
			(effects
				(font
					(size 0.7874 0.5842)
					(thickness 0.1524)
				)
				(justify mirror)
			)
		)
		(property "User Part Number" "PARTNUM*"
			(at -0.1016 5.013706 180)
			(unlocked yes)
			(layer "Cmts.User")
			(hide yes)
			(effects
				(font
					(size 0.7874 0.5842)
					(thickness 0.1524)
				)
				(justify mirror)
			)
		)
		(property "Tolerance" "TOL*"
			(at -0.0762 4.048506 180)
			(unlocked yes)
			(layer "Cmts.User")
			(hide yes)
			(effects
				(font
					(size 0.7874 0.5842)
					(thickness 0.1524)
				)
				(justify mirror)
			)
		)
		(duplicate_pad_numbers_are_jumpers no)
		(fp_line
			(start 1.5748 0.9398)
			(end -1.5748 0.9398)
			(stroke
				(width 0.1)
				(type default)
			)
			(layer "B.SilkS")
		)
		(fp_line
			(start 1.5748 -0.9398)
			(end 1.5748 0.9398)
			(stroke
				(width 0.1)
				(type default)
			)
			(layer "B.SilkS")
		)
		(fp_line
			(start -1.5748 0.9398)
			(end -1.5748 -0.9398)
			(stroke
				(width 0.1)
				(type default)
			)
			(layer "B.SilkS")
		)
		(fp_line
			(start -1.5748 -0.9398)
			(end 1.5748 -0.9398)
			(stroke
				(width 0.1)
				(type default)
			)
			(layer "B.SilkS")
		)
		(fp_rect
			(start -1.5748 0.9398)
			(end 1.5748 -0.9398)
			(stroke
				(width 0)
				(type default)
			)
			(fill no)
			(layer "B.CrtYd")
		)
		(fp_line
			(start 1.016 0.635)
			(end -1.016 0.635)
			(stroke
				(width 0.1)
				(type default)
			)
			(layer "B.Fab")
		)
		(fp_line
			(start 1.016 -0.635)
			(end 1.016 0.635)
			(stroke
				(width 0.1)
				(type default)
			)
			(layer "B.Fab")
		)
		(fp_line
			(start -1.016 0.635)
			(end -1.016 -0.635)
			(stroke
				(width 0.1)
				(type default)
			)
			(layer "B.Fab")
		)
		(fp_line
			(start -1.016 -0.635)
			(end 1.016 -0.635)
			(stroke
				(width 0.1)
				(type default)
			)
			(layer "B.Fab")
		)
		(pad "1" smd rect
			(at 0.8382 0)
			(size 0.9652 1.3716)
			(layers "B.Cu" "B.Mask" "B.Paste")
			(net "XP2R5V_FPGA")
		)
		(pad "2" smd rect
			(at -0.8382 0)
			(size 0.9652 1.3716)
			(layers "B.Cu" "B.Mask" "B.Paste")
			(net "SG")
		)
		(zone
			(layer "B.Cu")
			(hatch none 0.5)
			(connect_pads
				(clearance 0)
			)
			(min_thickness 0.25)
			(keepout
				(tracks allowed)
				(vias not_allowed)
				(pads allowed)
				(copperpour not_allowed)
				(footprints allowed)
			)
			(placement
				(enabled no)
				(sheetname "")
			)
			(fill
				(thermal_gap 0.5)
				(thermal_bridge_width 0.5)
				(island_removal_mode 0)
			)
			(polygon
				(pts
					(xy 95.8596 -27.559) (xy 95.4024 -27.559) (xy 95.4024 -26.289) (xy 95.8596 -26.289)
				)
			)
		)
	)
	(footprint ""
		(layer "B.Cu")
		(at 152.781 -70.866)
		(property "Reference" "R82"
			(at 0 -0.97663 0)
			(unlocked yes)
			(layer "B.SilkS")
			(effects
				(font
					(size 0.7874 0.5842)
					(thickness 0.1524)
				)
				(justify mirror)
			)
		)
		(property "Value" "VAL*"
			(at -0.02032 2.13233 0)
			(unlocked yes)
			(layer "B.Fab")
			(hide yes)
			(effects
				(font
					(size 0.7874 0.5842)
					(thickness 0.1524)
				)
				(justify mirror)
			)
		)
		(property "Tolerance" "TOL*"
			(at -0.044704 3.05435 0)
			(unlocked yes)
			(layer "Cmts.User")
			(hide yes)
			(effects
				(font
					(size 0.7874 0.5842)
					(thickness 0.1524)
				)
				(justify mirror)
			)
		)
		(property "User Part Number" "PARTNUM*"
			(at -0.02032 4.024884 0)
			(unlocked yes)
			(layer "Cmts.User")
			(hide yes)
			(effects
				(font
					(size 0.7874 0.5842)
					(thickness 0.1524)
				)
				(justify mirror)
			)
		)
		(property "Device Type" "RESISTOR-G155-133R0-01,33OHM,1%"
			(at -0.008382 1.210564 0)
			(unlocked yes)
			(layer "B.Fab")
			(hide yes)
			(effects
				(font
					(size 0.7874 0.5842)
					(thickness 0.1524)
				)
				(justify mirror)
			)
		)
		(duplicate_pad_numbers_are_jumpers no)
		(fp_line
			(start -1.143 -0.5588)
			(end 1.143 -0.5588)
			(stroke
				(width 0.1)
				(type default)
			)
			(layer "B.SilkS")
		)
		(fp_line
			(start -1.143 0.5588)
			(end -1.143 -0.5588)
			(stroke
				(width 0.1)
				(type default)
			)
			(layer "B.SilkS")
		)
		(fp_line
			(start 1.143 -0.5588)
			(end 1.143 0.5588)
			(stroke
				(width 0.1)
				(type default)
			)
			(layer "B.SilkS")
		)
		(fp_line
			(start 1.143 0.5588)
			(end -1.143 0.5588)
			(stroke
				(width 0.1)
				(type default)
			)
			(layer "B.SilkS")
		)
		(fp_rect
			(start 1.143 0.5588)
			(end -1.143 -0.5588)
			(stroke
				(width 0)
				(type default)
			)
			(fill no)
			(layer "B.CrtYd")
		)
		(fp_line
			(start -0.508 -0.3048)
			(end 0.508 -0.3048)
			(stroke
				(width 0.1)
				(type default)
			)
			(layer "B.Fab")
		)
		(fp_line
			(start -0.508 0.3048)
			(end -0.508 -0.3048)
			(stroke
				(width 0.1)
				(type default)
			)
			(layer "B.Fab")
		)
		(fp_line
			(start 0.508 -0.3048)
			(end 0.508 0.3048)
			(stroke
				(width 0.1)
				(type default)
			)
			(layer "B.Fab")
		)
		(fp_line
			(start 0.508 0.3048)
			(end -0.508 0.3048)
			(stroke
				(width 0.1)
				(type default)
			)
			(layer "B.Fab")
		)
		(pad "1" smd rect
			(at 0.5334 0 180)
			(size 0.7112 0.6096)
			(layers "B.Cu" "B.Mask" "B.Paste")
			(net "R_MAC_UART_TX_FPGA_RX")
		)
		(pad "2" smd rect
			(at -0.5334 0 180)
			(size 0.7112 0.6096)
			(layers "B.Cu" "B.Mask" "B.Paste")
			(net "DBG_UART_MAC_TX")
		)
		(zone
			(layer "B.Cu")
			(hatch none 0.5)
			(connect_pads
				(clearance 0)
			)
			(min_thickness 0.25)
			(keepout
				(tracks allowed)
				(vias not_allowed)
				(pads allowed)
				(copperpour not_allowed)
				(footprints allowed)
			)
			(placement
				(enabled no)
				(sheetname "")
			)
			(fill
				(thermal_gap 0.5)
				(thermal_bridge_width 0.5)
				(island_removal_mode 0)
			)
			(polygon
				(pts
					(xy 152.8572 -70.5612) (xy 152.8572 -71.1708) (xy 152.7048 -71.1708) (xy 152.7048 -70.5612)
				)
			)
		)
	)
	(footprint ""
		(layer "B.Cu")
		(at 18.161 -61.5442 -90)
		(property "Reference" "R282"
			(at 0.381 3.72237 270)
			(unlocked yes)
			(layer "B.SilkS")
			(effects
				(font
					(size 0.7874 0.5842)
					(thickness 0.1524)
				)
				(justify mirror)
			)
		)
		(property "Value" "VAL*"
			(at -0.02032 2.13233 270)
			(unlocked yes)
			(layer "B.Fab")
			(hide yes)
			(effects
				(font
					(size 0.7874 0.5842)
					(thickness 0.1524)
				)
				(justify mirror)
			)
		)
		(property "Tolerance" "TOL*"
			(at -0.044704 3.05435 270)
			(unlocked yes)
			(layer "Cmts.User")
			(hide yes)
			(effects
				(font
					(size 0.7874 0.5842)
					(thickness 0.1524)
				)
				(justify mirror)
			)
		)
		(property "User Part Number" "PARTNUM*"
			(at -0.02032 4.024884 270)
			(unlocked yes)
			(layer "Cmts.User")
			(hide yes)
			(effects
				(font
					(size 0.7874 0.5842)
					(thickness 0.1524)
				)
				(justify mirror)
			)
		)
		(property "Device Type" "RESISTOR-G155-14701-01,4.7KOHMA"
			(at -0.008382 1.210564 270)
			(unlocked yes)
			(layer "B.Fab")
			(hide yes)
			(effects
				(font
					(size 0.7874 0.5842)
					(thickness 0.1524)
				)
				(justify mirror)
			)
		)
		(duplicate_pad_numbers_are_jumpers no)
		(fp_line
			(start -1.143 0.5588)
			(end -1.143 -0.5588)
			(stroke
				(width 0.1)
				(type default)
			)
			(layer "B.SilkS")
		)
		(fp_line
			(start 1.143 0.5588)
			(end -1.143 0.5588)
			(stroke
				(width 0.1)
				(type default)
			)
			(layer "B.SilkS")
		)
		(fp_line
			(start -1.143 -0.5588)
			(end 1.143 -0.5588)
			(stroke
				(width 0.1)
				(type default)
			)
			(layer "B.SilkS")
		)
		(fp_line
			(start 1.143 -0.5588)
			(end 1.143 0.5588)
			(stroke
				(width 0.1)
				(type default)
			)
			(layer "B.SilkS")
		)
		(fp_poly
			(pts
				(xy 1.143 0.5588) (xy -1.143 0.5588) (xy -1.143 -0.5588) (xy 1.143 -0.5588)
			)
			(stroke
				(width 0)
				(type default)
			)
			(fill no)
			(layer "B.CrtYd")
		)
		(fp_line
			(start -0.508 0.3048)
			(end -0.508 -0.3048)
			(stroke
				(width 0.1)
				(type default)
			)
			(layer "B.Fab")
		)
		(fp_line
			(start 0.508 0.3048)
			(end -0.508 0.3048)
			(stroke
				(width 0.1)
				(type default)
			)
			(layer "B.Fab")
		)
		(fp_line
			(start -0.508 -0.3048)
			(end 0.508 -0.3048)
			(stroke
				(width 0.1)
				(type default)
			)
			(layer "B.Fab")
		)
		(fp_line
			(start 0.508 -0.3048)
			(end 0.508 0.3048)
			(stroke
				(width 0.1)
				(type default)
			)
			(layer "B.Fab")
		)
		(pad "1" smd rect
			(at 0.5334 0 90)
			(size 0.7112 0.6096)
			(layers "B.Cu" "B.Mask" "B.Paste")
			(net "XP3R3V_FPGA")
		)
		(pad "2" smd rect
			(at -0.5334 0 90)
			(size 0.7112 0.6096)
			(layers "B.Cu" "B.Mask" "B.Paste")
			(net "ICP10100_I2C_SCL")
		)
		(zone
			(layer "B.Cu")
			(hatch none 0.5)
			(connect_pads
				(clearance 0)
			)
			(min_thickness 0.25)
			(keepout
				(tracks allowed)
				(vias not_allowed)
				(pads allowed)
				(copperpour not_allowed)
				(footprints allowed)
			)
			(placement
				(enabled no)
				(sheetname "")
			)
			(fill
				(thermal_gap 0.5)
				(thermal_bridge_width 0.5)
				(island_removal_mode 0)
			)
			(polygon
				(pts
					(xy 17.8562 -61.468) (xy 18.4658 -61.468) (xy 18.4658 -61.6204) (xy 17.8562 -61.6204)
				)
			)
		)
		(zone
			(layer "B.Cu")
			(hatch none 0.5)
			(connect_pads
				(clearance 0)
			)
			(min_thickness 0.25)
			(keepout
				(tracks not_allowed)
				(vias allowed)
				(pads allowed)
				(copperpour not_allowed)
				(footprints allowed)
			)
			(placement
				(enabled no)
				(sheetname "")
			)
			(fill
				(thermal_gap 0.5)
				(thermal_bridge_width 0.5)
				(island_removal_mode 0)
			)
			(polygon
				(pts
					(xy 17.8562 -61.468) (xy 18.4658 -61.468) (xy 18.4658 -61.6204) (xy 17.8562 -61.6204)
				)
			)
		)
	)
	(footprint ""
		(layer "B.Cu")
		(at 121.073164 -35.772344 90)
		(property "Reference" "C122"
			(at 1.184656 1.069086 270)
			(unlocked yes)
			(layer "B.SilkS")
			(effects
				(font
					(size 0.635 0.4064)
					(thickness 0.1524)
				)
				(justify mirror)
			)
		)
		(property "Value" "VAL*"
			(at 0 3.718306 90)
			(unlocked yes)
			(layer "B.Fab")
			(hide yes)
			(effects
				(font
					(size 0.7874 0.5842)
					(thickness 0.127)
				)
				(justify mirror)
			)
		)
		(property "Tolerance" "TOL*"
			(at 0 4.861306 90)
			(unlocked yes)
			(layer "Cmts.User")
			(hide yes)
			(effects
				(font
					(size 0.7874 0.5842)
					(thickness 0.127)
				)
				(justify mirror)
			)
		)
		(property "User Part Number" "PARTNUM*"
			(at 0 2.575306 90)
			(unlocked yes)
			(layer "Cmts.User")
			(hide yes)
			(effects
				(font
					(size 0.7874 0.5842)
					(thickness 0.127)
				)
				(justify mirror)
			)
		)
		(property "Device Type" "CAPACITOR-G105-0B104-CK,0.1UF,A"
			(at 0 1.432306 90)
			(unlocked yes)
			(layer "B.Fab")
			(hide yes)
			(effects
				(font
					(size 0.7874 0.5842)
					(thickness 0.127)
				)
				(justify mirror)
			)
		)
		(duplicate_pad_numbers_are_jumpers no)
		(fp_line
			(start 0.970026 -0.4699)
			(end -0.970026 -0.4699)
			(stroke
				(width 0.1)
				(type default)
			)
			(layer "B.SilkS")
		)
		(fp_line
			(start -0.970026 -0.4699)
			(end -0.970026 0.4699)
			(stroke
				(width 0.1)
				(type default)
			)
			(layer "B.SilkS")
		)
		(fp_line
			(start 0.970026 0.4699)
			(end 0.970026 -0.4699)
			(stroke
				(width 0.1)
				(type default)
			)
			(layer "B.SilkS")
		)
		(fp_line
			(start -0.970026 0.4699)
			(end 0.970026 0.4699)
			(stroke
				(width 0.1)
				(type default)
			)
			(layer "B.SilkS")
		)
		(fp_poly
			(pts
				(xy 0.970026 0.4699) (xy -0.970026 0.4699) (xy -0.970026 -0.4699) (xy 0.970026 -0.4699)
			)
			(stroke
				(width 0)
				(type default)
			)
			(fill no)
			(layer "B.CrtYd")
		)
		(fp_line
			(start 0.508 -0.3048)
			(end -0.508 -0.3048)
			(stroke
				(width 0.1)
				(type default)
			)
			(layer "B.Fab")
		)
		(fp_line
			(start -0.508 -0.3048)
			(end -0.508 0.3048)
			(stroke
				(width 0.1)
				(type default)
			)
			(layer "B.Fab")
		)
		(fp_line
			(start 0.508 0.3048)
			(end 0.508 -0.3048)
			(stroke
				(width 0.1)
				(type default)
			)
			(layer "B.Fab")
		)
		(fp_line
			(start -0.508 0.3048)
			(end 0.508 0.3048)
			(stroke
				(width 0.1)
				(type default)
			)
			(layer "B.Fab")
		)
		(pad "1" smd circle
			(at 0.500126 0 270)
			(size 0.635 0.635)
			(layers "B.Cu" "B.Mask" "B.Paste")
			(net "XP2R5V_FPGA")
		)
		(pad "2" smd circle
			(at -0.500126 0 270)
			(size 0.635 0.635)
			(layers "B.Cu" "B.Mask" "B.Paste")
			(net "SG")
		)
	)
	(footprint ""
		(layer "B.Cu")
		(at 47.36084 -15.82928 -90)
		(property "Reference" "R23"
			(at -2.45872 0.02921 270)
			(unlocked yes)
			(layer "B.SilkS")
			(effects
				(font
					(size 0.7874 0.5842)
					(thickness 0.1524)
				)
				(justify mirror)
			)
		)
		(property "Value" "VAL*"
			(at -0.02032 2.13233 270)
			(unlocked yes)
			(layer "B.Fab")
			(hide yes)
			(effects
				(font
					(size 0.7874 0.5842)
					(thickness 0.1524)
				)
				(justify mirror)
			)
		)
		(property "Device Type" "RESISTOR-G155-100R0-J0,0OHM,-"
			(at -0.008382 1.210564 270)
			(unlocked yes)
			(layer "B.Fab")
			(hide yes)
			(effects
				(font
					(size 0.7874 0.5842)
					(thickness 0.1524)
				)
				(justify mirror)
			)
		)
		(property "User Part Number" "PARTNUM*"
			(at -0.02032 4.024884 270)
			(unlocked yes)
			(layer "Cmts.User")
			(hide yes)
			(effects
				(font
					(size 0.7874 0.5842)
					(thickness 0.1524)
				)
				(justify mirror)
			)
		)
		(property "Tolerance" "TOL*"
			(at -0.044704 3.05435 270)
			(unlocked yes)
			(layer "Cmts.User")
			(hide yes)
			(effects
				(font
					(size 0.7874 0.5842)
					(thickness 0.1524)
				)
				(justify mirror)
			)
		)
		(duplicate_pad_numbers_are_jumpers no)
		(fp_line
			(start -1.143 0.5588)
			(end -1.143 -0.5588)
			(stroke
				(width 0.1)
				(type default)
			)
			(layer "B.SilkS")
		)
		(fp_line
			(start 1.143 0.5588)
			(end -1.143 0.5588)
			(stroke
				(width 0.1)
				(type default)
			)
			(layer "B.SilkS")
		)
		(fp_line
			(start -1.143 -0.5588)
			(end 1.143 -0.5588)
			(stroke
				(width 0.1)
				(type default)
			)
			(layer "B.SilkS")
		)
		(fp_line
			(start 1.143 -0.5588)
			(end 1.143 0.5588)
			(stroke
				(width 0.1)
				(type default)
			)
			(layer "B.SilkS")
		)
		(fp_rect
			(start 1.143 -0.5588)
			(end -1.143 0.5588)
			(stroke
				(width 0)
				(type default)
			)
			(fill no)
			(layer "B.CrtYd")
		)
		(fp_line
			(start -0.508 0.3048)
			(end -0.508 -0.3048)
			(stroke
				(width 0.1)
				(type default)
			)
			(layer "B.Fab")
		)
		(fp_line
			(start 0.508 0.3048)
			(end -0.508 0.3048)
			(stroke
				(width 0.1)
				(type default)
			)
			(layer "B.Fab")
		)
		(fp_line
			(start -0.508 -0.3048)
			(end 0.508 -0.3048)
			(stroke
				(width 0.1)
				(type default)
			)
			(layer "B.Fab")
		)
		(fp_line
			(start 0.508 -0.3048)
			(end 0.508 0.3048)
			(stroke
				(width 0.1)
				(type default)
			)
			(layer "B.Fab")
		)
		(pad "1" smd rect
			(at 0.5334 0 90)
			(size 0.7112 0.6096)
			(layers "B.Cu" "B.Mask" "B.Paste")
			(net "CARD_PRESENT")
		)
		(pad "2" smd rect
			(at -0.5334 0 90)
			(size 0.7112 0.6096)
			(layers "B.Cu" "B.Mask" "B.Paste")
			(net "UNNAMED_3_CONN64PGF_I61_PRSNT22")
		)
		(zone
			(layer "B.Cu")
			(hatch none 0.5)
			(connect_pads
				(clearance 0)
			)
			(min_thickness 0.25)
			(keepout
				(tracks allowed)
				(vias not_allowed)
				(pads allowed)
				(copperpour not_allowed)
				(footprints allowed)
			)
			(placement
				(enabled no)
				(sheetname "")
			)
			(fill
				(thermal_gap 0.5)
				(thermal_bridge_width 0.5)
				(island_removal_mode 0)
			)
			(polygon
				(pts
					(xy 47.66564 -15.75308) (xy 47.66564 -15.90548) (xy 47.05604 -15.90548) (xy 47.05604 -15.75308)
				)
			)
		)
	)
	(footprint ""
		(layer "B.Cu")
		(at 21.1582 -23.6728 90)
		(property "Reference" "R161"
			(at 3.8862 0.13843 270)
			(unlocked yes)
			(layer "B.SilkS")
			(effects
				(font
					(size 0.7874 0.5842)
					(thickness 0.1524)
				)
				(justify mirror)
			)
		)
		(property "Value" "VAL*"
			(at -0.02032 2.13233 90)
			(unlocked yes)
			(layer "B.Fab")
			(hide yes)
			(effects
				(font
					(size 0.7874 0.5842)
					(thickness 0.1524)
				)
				(justify mirror)
			)
		)
		(property "Tolerance" "TOL*"
			(at -0.044704 3.05435 90)
			(unlocked yes)
			(layer "Cmts.User")
			(hide yes)
			(effects
				(font
					(size 0.7874 0.5842)
					(thickness 0.1524)
				)
				(justify mirror)
			)
		)
		(property "User Part Number" "PARTNUM*"
			(at -0.02032 4.024884 90)
			(unlocked yes)
			(layer "Cmts.User")
			(hide yes)
			(effects
				(font
					(size 0.7874 0.5842)
					(thickness 0.1524)
				)
				(justify mirror)
			)
		)
		(property "Device Type" "RESISTOR-G155-14701-01,4.7KOHMA"
			(at -0.008382 1.210564 90)
			(unlocked yes)
			(layer "B.Fab")
			(hide yes)
			(effects
				(font
					(size 0.7874 0.5842)
					(thickness 0.1524)
				)
				(justify mirror)
			)
		)
		(duplicate_pad_numbers_are_jumpers no)
		(fp_line
			(start 1.143 -0.5588)
			(end 1.143 0.5588)
			(stroke
				(width 0.1)
				(type default)
			)
			(layer "B.SilkS")
		)
		(fp_line
			(start -1.143 -0.5588)
			(end 1.143 -0.5588)
			(stroke
				(width 0.1)
				(type default)
			)
			(layer "B.SilkS")
		)
		(fp_line
			(start 1.143 0.5588)
			(end -1.143 0.5588)
			(stroke
				(width 0.1)
				(type default)
			)
			(layer "B.SilkS")
		)
		(fp_line
			(start -1.143 0.5588)
			(end -1.143 -0.5588)
			(stroke
				(width 0.1)
				(type default)
			)
			(layer "B.SilkS")
		)
		(fp_poly
			(pts
				(xy 1.143 0.5588) (xy -1.143 0.5588) (xy -1.143 -0.5588) (xy 1.143 -0.5588)
			)
			(stroke
				(width 0)
				(type default)
			)
			(fill no)
			(layer "B.CrtYd")
		)
		(fp_line
			(start 0.508 -0.3048)
			(end 0.508 0.3048)
			(stroke
				(width 0.1)
				(type default)
			)
			(layer "B.Fab")
		)
		(fp_line
			(start -0.508 -0.3048)
			(end 0.508 -0.3048)
			(stroke
				(width 0.1)
				(type default)
			)
			(layer "B.Fab")
		)
		(fp_line
			(start 0.508 0.3048)
			(end -0.508 0.3048)
			(stroke
				(width 0.1)
				(type default)
			)
			(layer "B.Fab")
		)
		(fp_line
			(start -0.508 0.3048)
			(end -0.508 -0.3048)
			(stroke
				(width 0.1)
				(type default)
			)
			(layer "B.Fab")
		)
		(pad "1" smd rect
			(at 0.5334 0 270)
			(size 0.7112 0.6096)
			(layers "B.Cu" "B.Mask" "B.Paste")
			(net "UNNAMED_5_24LC16BTISTTSSOP8_I_1")
		)
		(pad "2" smd rect
			(at -0.5334 0 270)
			(size 0.7112 0.6096)
			(layers "B.Cu" "B.Mask" "B.Paste")
			(net "SG")
		)
		(zone
			(layer "B.Cu")
			(hatch none 0.5)
			(connect_pads
				(clearance 0)
			)
			(min_thickness 0.25)
			(keepout
				(tracks allowed)
				(vias not_allowed)
				(pads allowed)
				(copperpour not_allowed)
				(footprints allowed)
			)
			(placement
				(enabled no)
				(sheetname "")
			)
			(fill
				(thermal_gap 0.5)
				(thermal_bridge_width 0.5)
				(island_removal_mode 0)
			)
			(polygon
				(pts
					(xy 21.463 -23.749) (xy 20.8534 -23.749) (xy 20.8534 -23.5966) (xy 21.463 -23.5966)
				)
			)
		)
		(zone
			(layer "B.Cu")
			(hatch none 0.5)
			(connect_pads
				(clearance 0)
			)
			(min_thickness 0.25)
			(keepout
				(tracks not_allowed)
				(vias allowed)
				(pads allowed)
				(copperpour not_allowed)
				(footprints allowed)
			)
			(placement
				(enabled no)
				(sheetname "")
			)
			(fill
				(thermal_gap 0.5)
				(thermal_bridge_width 0.5)
				(island_removal_mode 0)
			)
			(polygon
				(pts
					(xy 21.463 -23.749) (xy 20.8534 -23.749) (xy 20.8534 -23.5966) (xy 21.463 -23.5966)
				)
			)
		)
	)
	(footprint ""
		(layer "B.Cu")
		(at 76.581 -58.801 -90)
		(property "Reference" "Q3"
			(at -2.413 -5.16763 270)
			(unlocked yes)
			(layer "B.SilkS")
			(effects
				(font
					(size 0.7874 0.5842)
					(thickness 0.1524)
				)
				(justify mirror)
			)
		)
		(property "Value" ""
			(at 0 0 90)
			(layer "B.Fab")
			(effects
				(font
					(size 1.27 1.27)
				)
				(justify mirror)
			)
		)
		(property "User Part Number" "PARTNUM*"
			(at -5.207254 -0.501904 270)
			(unlocked yes)
			(layer "Cmts.User")
			(hide yes)
			(effects
				(font
					(size 0.7874 0.5842)
					(thickness 0.000001)
				)
				(justify mirror)
			)
		)
		(property "Device Type" "POWERMOS_3P_PCH-G121-10216-01"
			(at -3.642614 -1.544828 270)
			(unlocked yes)
			(layer "B.Fab")
			(hide yes)
			(effects
				(font
					(size 0.7874 0.5842)
					(thickness 0.000001)
				)
				(justify mirror)
			)
		)
		(duplicate_pad_numbers_are_jumpers no)
		(fp_line
			(start -1.7018 2.0574)
			(end -0.1905 2.0574)
			(stroke
				(width 0.1)
				(type default)
			)
			(layer "B.SilkS")
		)
		(fp_line
			(start -0.1905 2.0574)
			(end -0.1905 0.9144)
			(stroke
				(width 0.1)
				(type default)
			)
			(layer "B.SilkS")
		)
		(fp_line
			(start 0.1905 2.0574)
			(end 1.7018 2.0574)
			(stroke
				(width 0.1)
				(type default)
			)
			(layer "B.SilkS")
		)
		(fp_line
			(start 1.7018 2.0574)
			(end 1.7018 -0.9144)
			(stroke
				(width 0.1)
				(type default)
			)
			(layer "B.SilkS")
		)
		(fp_line
			(start -0.1905 0.9144)
			(end 0.1905 0.9144)
			(stroke
				(width 0.1)
				(type default)
			)
			(layer "B.SilkS")
		)
		(fp_line
			(start 0.1905 0.9144)
			(end 0.1905 2.0574)
			(stroke
				(width 0.1)
				(type default)
			)
			(layer "B.SilkS")
		)
		(fp_line
			(start -1.7018 -0.9144)
			(end -1.7018 2.0574)
			(stroke
				(width 0.1)
				(type default)
			)
			(layer "B.SilkS")
		)
		(fp_line
			(start -0.7493 -0.9144)
			(end -1.7018 -0.9144)
			(stroke
				(width 0.1)
				(type default)
			)
			(layer "B.SilkS")
		)
		(fp_line
			(start 0.7493 -0.9144)
			(end 0.7493 -2.0574)
			(stroke
				(width 0.1)
				(type default)
			)
			(layer "B.SilkS")
		)
		(fp_line
			(start 1.7018 -0.9144)
			(end 0.7493 -0.9144)
			(stroke
				(width 0.1)
				(type default)
			)
			(layer "B.SilkS")
		)
		(fp_line
			(start -0.7493 -2.0574)
			(end -0.7493 -0.9144)
			(stroke
				(width 0.1)
				(type default)
			)
			(layer "B.SilkS")
		)
		(fp_line
			(start 0.7493 -2.0574)
			(end -0.7493 -2.0574)
			(stroke
				(width 0.1)
				(type default)
			)
			(layer "B.SilkS")
		)
		(fp_poly
			(pts
				(arc
					(start 1.524 2.413)
					(mid 1.524 3.175)
					(end 1.524 2.413)
				)
			)
			(stroke
				(width 0)
				(type default)
			)
			(fill yes)
			(layer "B.SilkS")
		)
		(fp_poly
			(pts
				(xy 1.7018 2.0828) (xy 1.7018 -0.9144) (xy 0.762 -0.9144) (xy 0.762 -2.0574) (xy -0.762 -2.0574)
				(xy -0.762 -0.9144) (xy -1.7018 -0.9144) (xy -1.7018 2.0828)
			)
			(stroke
				(width 0)
				(type default)
			)
			(fill no)
			(layer "B.CrtYd")
		)
		(fp_line
			(start -1.1684 1.143)
			(end -0.7112 1.143)
			(stroke
				(width 0.1)
				(type default)
			)
			(layer "B.Fab")
		)
		(fp_line
			(start -0.7112 1.143)
			(end -0.7112 0.6604)
			(stroke
				(width 0.1)
				(type default)
			)
			(layer "B.Fab")
		)
		(fp_line
			(start 0.7112 1.143)
			(end 1.1684 1.143)
			(stroke
				(width 0.1)
				(type default)
			)
			(layer "B.Fab")
		)
		(fp_line
			(start 1.1684 1.143)
			(end 1.1684 0.6604)
			(stroke
				(width 0.1)
				(type default)
			)
			(layer "B.Fab")
		)
		(fp_line
			(start -0.7112 0.9144)
			(end -1.1684 0.9144)
			(stroke
				(width 0.1)
				(type default)
			)
			(layer "B.Fab")
		)
		(fp_line
			(start 1.1684 0.9144)
			(end 0.7112 0.9144)
			(stroke
				(width 0.1)
				(type default)
			)
			(layer "B.Fab")
		)
		(fp_line
			(start -1.4478 0.6604)
			(end 1.4478 0.6604)
			(stroke
				(width 0.1)
				(type default)
			)
			(layer "B.Fab")
		)
		(fp_line
			(start -1.1684 0.6604)
			(end -1.1684 1.143)
			(stroke
				(width 0.1)
				(type default)
			)
			(layer "B.Fab")
		)
		(fp_line
			(start -0.7112 0.6604)
			(end -1.1684 0.6604)
			(stroke
				(width 0.1)
				(type default)
			)
			(layer "B.Fab")
		)
		(fp_line
			(start 0.7112 0.6604)
			(end 0.7112 1.143)
			(stroke
				(width 0.1)
				(type default)
			)
			(layer "B.Fab")
		)
		(fp_line
			(start 1.1684 0.6604)
			(end 0.7112 0.6604)
			(stroke
				(width 0.1)
				(type default)
			)
			(layer "B.Fab")
		)
		(fp_line
			(start 1.4478 0.6604)
			(end 1.3716 0.5842)
			(stroke
				(width 0.1)
				(type default)
			)
			(layer "B.Fab")
		)
		(fp_line
			(start 1.4478 0.6604)
			(end 1.4478 -0.6604)
			(stroke
				(width 0.1)
				(type default)
			)
			(layer "B.Fab")
		)
		(fp_line
			(start -1.3716 0.5842)
			(end -1.4478 0.6604)
			(stroke
				(width 0.1)
				(type default)
			)
			(layer "B.Fab")
		)
		(fp_line
			(start -1.3716 0.5842)
			(end 1.3716 0.5842)
			(stroke
				(width 0.1)
				(type default)
			)
			(layer "B.Fab")
		)
		(fp_line
			(start 1.3716 0.5842)
			(end 1.3716 -0.5842)
			(stroke
				(width 0.1)
				(type default)
			)
			(layer "B.Fab")
		)
		(fp_line
			(start -1.3716 -0.5842)
			(end -1.3716 0.5842)
			(stroke
				(width 0.1)
				(type default)
			)
			(layer "B.Fab")
		)
		(fp_line
			(start -1.3716 -0.5842)
			(end -1.4478 -0.6604)
			(stroke
				(width 0.1)
				(type default)
			)
			(layer "B.Fab")
		)
		(fp_line
			(start 1.3716 -0.5842)
			(end -1.3716 -0.5842)
			(stroke
				(width 0.1)
				(type default)
			)
			(layer "B.Fab")
		)
		(fp_line
			(start -1.4478 -0.6604)
			(end -1.4478 0.6604)
			(stroke
				(width 0.1)
				(type default)
			)
			(layer "B.Fab")
		)
		(fp_line
			(start -0.2286 -0.6604)
			(end 0.2286 -0.6604)
			(stroke
				(width 0.1)
				(type default)
			)
			(layer "B.Fab")
		)
		(fp_line
			(start 0.2286 -0.6604)
			(end 0.2286 -1.143)
			(stroke
				(width 0.1)
				(type default)
			)
			(layer "B.Fab")
		)
		(fp_line
			(start 1.4478 -0.6604)
			(end 1.3716 -0.5842)
			(stroke
				(width 0.1)
				(type default)
			)
			(layer "B.Fab")
		)
		(fp_line
			(start 1.4478 -0.6604)
			(end -1.4478 -0.6604)
			(stroke
				(width 0.1)
				(type default)
			)
			(layer "B.Fab")
		)
		(fp_line
			(start 0.2286 -0.9144)
			(end -0.2286 -0.9144)
			(stroke
				(width 0.1)
				(type default)
			)
			(layer "B.Fab")
		)
		(fp_line
			(start -0.2286 -1.143)
			(end -0.2286 -0.6604)
			(stroke
				(width 0.1)
				(type default)
			)
			(layer "B.Fab")
		)
		(fp_line
			(start 0.2286 -1.143)
			(end -0.2286 -1.143)
			(stroke
				(width 0.1)
				(type default)
			)
			(layer "B.Fab")
		)
		(fp_poly
			(pts
				(arc
					(start 1.651 1.27)
					(mid 1.651 2.032)
					(end 1.651 1.27)
				)
			)
			(stroke
				(width 0)
				(type default)
			)
			(fill yes)
			(layer "B.Fab")
		)
		(fp_text user "2"
			(at -1.8288 1.30175 270)
			(unlocked yes)
			(layer "B.SilkS")
			(effects
				(font
					(size 0.635 0.4064)
					(thickness 0.1524)
				)
				(justify left mirror)
			)
		)
		(fp_text user "2"
			(at -1.23063 1.4859 0)
			(unlocked yes)
			(layer "B.Fab")
			(effects
				(font
					(size 0.7874 0.5842)
					(thickness 0.1524)
				)
				(justify left mirror)
			)
		)
		(pad "1" smd rect
			(at 0.9398 1.1049 90)
			(size 0.9906 1.397)
			(layers "B.Cu" "B.Mask" "B.Paste")
			(net "UNNAMED_527_POWERMOS3PNCHV1_I23")
		)
		(pad "2" smd rect
			(at -0.9398 1.1049 90)
			(size 0.9906 1.397)
			(layers "B.Cu" "B.Mask" "B.Paste")
			(net "XP5R0V_MAC")
		)
		(pad "3" smd rect
			(at 0 -1.1049 90)
			(size 0.9906 1.397)
			(layers "B.Cu" "B.Mask" "B.Paste")
			(net "UNNAMED_527_FUSE_I244_1")
		)
	)
	(footprint ""
		(layer "B.Cu")
		(at 107.696 -100.6348 -90)
		(property "Reference" "C316"
			(at 2.2098 1.05537 270)
			(unlocked yes)
			(layer "B.SilkS")
			(effects
				(font
					(size 0.7874 0.5842)
					(thickness 0.1524)
				)
				(justify mirror)
			)
		)
		(property "Value" "VAL*"
			(at -0.0762 2.067306 270)
			(unlocked yes)
			(layer "B.Fab")
			(hide yes)
			(effects
				(font
					(size 0.7874 0.5842)
					(thickness 0.1524)
				)
				(justify mirror)
			)
		)
		(property "Tolerance" "TOL*"
			(at -0.0762 3.032506 270)
			(unlocked yes)
			(layer "Cmts.User")
			(hide yes)
			(effects
				(font
					(size 0.7874 0.5842)
					(thickness 0.1524)
				)
				(justify mirror)
			)
		)
		(property "User Part Number" "PARTNUM*"
			(at -0.1016 4.023106 270)
			(unlocked yes)
			(layer "Cmts.User")
			(hide yes)
			(effects
				(font
					(size 0.7874 0.5842)
					(thickness 0.1524)
				)
				(justify mirror)
			)
		)
		(property "Device Type" "CAPACITOR-G105-0B104-EK,0.1UF,A"
			(at -0.0508 1.127506 270)
			(unlocked yes)
			(layer "B.Fab")
			(hide yes)
			(effects
				(font
					(size 0.7874 0.5842)
					(thickness 0.1524)
				)
				(justify mirror)
			)
		)
		(duplicate_pad_numbers_are_jumpers no)
		(fp_line
			(start -1.143 0.5588)
			(end -1.143 -0.5588)
			(stroke
				(width 0.1)
				(type default)
			)
			(layer "B.SilkS")
		)
		(fp_line
			(start 1.143 0.5588)
			(end -1.143 0.5588)
			(stroke
				(width 0.1)
				(type default)
			)
			(layer "B.SilkS")
		)
		(fp_line
			(start -1.143 -0.5588)
			(end 1.143 -0.5588)
			(stroke
				(width 0.1)
				(type default)
			)
			(layer "B.SilkS")
		)
		(fp_line
			(start 1.143 -0.5588)
			(end 1.143 0.5588)
			(stroke
				(width 0.1)
				(type default)
			)
			(layer "B.SilkS")
		)
		(fp_poly
			(pts
				(xy 1.143 0.5588) (xy -1.143 0.5588) (xy -1.143 -0.5588) (xy 1.143 -0.5588)
			)
			(stroke
				(width 0)
				(type default)
			)
			(fill no)
			(layer "B.CrtYd")
		)
		(fp_line
			(start -0.508 0.3048)
			(end -0.508 -0.3048)
			(stroke
				(width 0.1)
				(type default)
			)
			(layer "B.Fab")
		)
		(fp_line
			(start 0.508 0.3048)
			(end -0.508 0.3048)
			(stroke
				(width 0.1)
				(type default)
			)
			(layer "B.Fab")
		)
		(fp_line
			(start -0.508 -0.3048)
			(end 0.508 -0.3048)
			(stroke
				(width 0.1)
				(type default)
			)
			(layer "B.Fab")
		)
		(fp_line
			(start 0.508 -0.3048)
			(end 0.508 0.3048)
			(stroke
				(width 0.1)
				(type default)
			)
			(layer "B.Fab")
		)
		(pad "1" smd rect
			(at 0.5334 0 90)
			(size 0.7112 0.6096)
			(layers "B.Cu" "B.Mask" "B.Paste")
			(net "RGB_LED_SHUTDOWN_N")
		)
		(pad "2" smd rect
			(at -0.5334 0 90)
			(size 0.7112 0.6096)
			(layers "B.Cu" "B.Mask" "B.Paste")
			(net "SG")
		)
		(zone
			(layer "B.Cu")
			(hatch none 0.5)
			(connect_pads
				(clearance 0)
			)
			(min_thickness 0.25)
			(keepout
				(tracks not_allowed)
				(vias allowed)
				(pads allowed)
				(copperpour not_allowed)
				(footprints allowed)
			)
			(placement
				(enabled no)
				(sheetname "")
			)
			(fill
				(thermal_gap 0.5)
				(thermal_bridge_width 0.5)
				(island_removal_mode 0)
			)
			(polygon
				(pts
					(xy 107.3912 -100.5586) (xy 108.0008 -100.5586) (xy 108.0008 -100.711) (xy 107.3912 -100.711)
				)
			)
		)
		(zone
			(layer "B.Cu")
			(hatch none 0.5)
			(connect_pads
				(clearance 0)
			)
			(min_thickness 0.25)
			(keepout
				(tracks allowed)
				(vias not_allowed)
				(pads allowed)
				(copperpour not_allowed)
				(footprints allowed)
			)
			(placement
				(enabled no)
				(sheetname "")
			)
			(fill
				(thermal_gap 0.5)
				(thermal_bridge_width 0.5)
				(island_removal_mode 0)
			)
			(polygon
				(pts
					(xy 107.3912 -100.5586) (xy 108.0008 -100.5586) (xy 108.0008 -100.711) (xy 107.3912 -100.711)
				)
			)
		)
	)
	(footprint ""
		(layer "B.Cu")
		(at 106.847132 -36.323016 -90)
		(property "Reference" "C208"
			(at 1.525016 41.600882 270)
			(unlocked yes)
			(layer "B.SilkS")
			(effects
				(font
					(size 0.635 0.4064)
					(thickness 0.1524)
				)
				(justify mirror)
			)
		)
		(property "Value" "VAL*"
			(at 0 3.718306 270)
			(unlocked yes)
			(layer "B.Fab")
			(hide yes)
			(effects
				(font
					(size 0.7874 0.5842)
					(thickness 0.127)
				)
				(justify mirror)
			)
		)
		(property "Device Type" "CAPACITOR-G105-0B104-CK,0.1UF,A"
			(at 0 1.432306 270)
			(unlocked yes)
			(layer "B.Fab")
			(hide yes)
			(effects
				(font
					(size 0.7874 0.5842)
					(thickness 0.127)
				)
				(justify mirror)
			)
		)
		(property "User Part Number" "PARTNUM*"
			(at 0 2.575306 270)
			(unlocked yes)
			(layer "Cmts.User")
			(hide yes)
			(effects
				(font
					(size 0.7874 0.5842)
					(thickness 0.127)
				)
				(justify mirror)
			)
		)
		(property "Tolerance" "TOL*"
			(at 0 4.861306 270)
			(unlocked yes)
			(layer "Cmts.User")
			(hide yes)
			(effects
				(font
					(size 0.7874 0.5842)
					(thickness 0.127)
				)
				(justify mirror)
			)
		)
		(duplicate_pad_numbers_are_jumpers no)
		(fp_line
			(start -0.970026 0.4699)
			(end 0.970026 0.4699)
			(stroke
				(width 0.1)
				(type default)
			)
			(layer "B.SilkS")
		)
		(fp_line
			(start 0.970026 0.4699)
			(end 0.970026 -0.4699)
			(stroke
				(width 0.1)
				(type default)
			)
			(layer "B.SilkS")
		)
		(fp_line
			(start -0.970026 -0.4699)
			(end -0.970026 0.4699)
			(stroke
				(width 0.1)
				(type default)
			)
			(layer "B.SilkS")
		)
		(fp_line
			(start 0.970026 -0.4699)
			(end -0.970026 -0.4699)
			(stroke
				(width 0.1)
				(type default)
			)
			(layer "B.SilkS")
		)
		(fp_poly
			(pts
				(xy 0.970026 0.4699) (xy -0.970026 0.4699) (xy -0.970026 -0.4699) (xy 0.970026 -0.4699)
			)
			(stroke
				(width 0)
				(type default)
			)
			(fill no)
			(layer "B.CrtYd")
		)
		(fp_line
			(start -0.508 0.3048)
			(end 0.508 0.3048)
			(stroke
				(width 0.1)
				(type default)
			)
			(layer "B.Fab")
		)
		(fp_line
			(start 0.508 0.3048)
			(end 0.508 -0.3048)
			(stroke
				(width 0.1)
				(type default)
			)
			(layer "B.Fab")
		)
		(fp_line
			(start -0.508 -0.3048)
			(end -0.508 0.3048)
			(stroke
				(width 0.1)
				(type default)
			)
			(layer "B.Fab")
		)
		(fp_line
			(start 0.508 -0.3048)
			(end -0.508 -0.3048)
			(stroke
				(width 0.1)
				(type default)
			)
			(layer "B.Fab")
		)
		(pad "1" smd circle
			(at 0.500126 0 90)
			(size 0.635 0.635)
			(layers "B.Cu" "B.Mask" "B.Paste")
			(net "XP2R5V_FPGA")
		)
		(pad "2" smd circle
			(at -0.500126 0 90)
			(size 0.635 0.635)
			(layers "B.Cu" "B.Mask" "B.Paste")
			(net "SG")
		)
	)
	(footprint ""
		(layer "B.Cu")
		(at 30.34792 -16.73098 180)
		(property "Reference" "R1991"
			(at 0.75692 -1.27635 0)
			(unlocked yes)
			(layer "B.SilkS")
			(effects
				(font
					(size 0.7874 0.5842)
					(thickness 0.1524)
				)
				(justify mirror)
			)
		)
		(property "Value" "VAL*"
			(at -0.02032 2.13233 180)
			(unlocked yes)
			(layer "B.Fab")
			(hide yes)
			(effects
				(font
					(size 0.7874 0.5842)
					(thickness 0.1524)
				)
				(justify mirror)
			)
		)
		(property "Tolerance" "TOL*"
			(at -0.044704 3.05435 180)
			(unlocked yes)
			(layer "Cmts.User")
			(hide yes)
			(effects
				(font
					(size 0.7874 0.5842)
					(thickness 0.1524)
				)
				(justify mirror)
			)
		)
		(property "User Part Number" "PARTNUM*"
			(at -0.02032 4.024884 180)
			(unlocked yes)
			(layer "Cmts.User")
			(hide yes)
			(effects
				(font
					(size 0.7874 0.5842)
					(thickness 0.1524)
				)
				(justify mirror)
			)
		)
		(property "Device Type" "RESISTOR-G155-11002-01,10KOHM,A"
			(at -0.008382 1.210564 180)
			(unlocked yes)
			(layer "B.Fab")
			(hide yes)
			(effects
				(font
					(size 0.7874 0.5842)
					(thickness 0.1524)
				)
				(justify mirror)
			)
		)
		(duplicate_pad_numbers_are_jumpers no)
		(fp_line
			(start 1.143 0.5588)
			(end -1.143 0.5588)
			(stroke
				(width 0.1)
				(type default)
			)
			(layer "B.SilkS")
		)
		(fp_line
			(start 1.143 -0.5588)
			(end 1.143 0.5588)
			(stroke
				(width 0.1)
				(type default)
			)
			(layer "B.SilkS")
		)
		(fp_line
			(start -1.143 0.5588)
			(end -1.143 -0.5588)
			(stroke
				(width 0.1)
				(type default)
			)
			(layer "B.SilkS")
		)
		(fp_line
			(start -1.143 -0.5588)
			(end 1.143 -0.5588)
			(stroke
				(width 0.1)
				(type default)
			)
			(layer "B.SilkS")
		)
		(fp_rect
			(start 1.143 -0.5588)
			(end -1.143 0.5588)
			(stroke
				(width 0)
				(type default)
			)
			(fill no)
			(layer "B.CrtYd")
		)
		(fp_line
			(start 0.508 0.3048)
			(end -0.508 0.3048)
			(stroke
				(width 0.1)
				(type default)
			)
			(layer "B.Fab")
		)
		(fp_line
			(start 0.508 -0.3048)
			(end 0.508 0.3048)
			(stroke
				(width 0.1)
				(type default)
			)
			(layer "B.Fab")
		)
		(fp_line
			(start -0.508 0.3048)
			(end -0.508 -0.3048)
			(stroke
				(width 0.1)
				(type default)
			)
			(layer "B.Fab")
		)
		(fp_line
			(start -0.508 -0.3048)
			(end 0.508 -0.3048)
			(stroke
				(width 0.1)
				(type default)
			)
			(layer "B.Fab")
		)
		(pad "1" smd rect
			(at 0.5334 0)
			(size 0.7112 0.6096)
			(layers "B.Cu" "B.Mask" "B.Paste")
			(net "XP3R3V_FPGA")
		)
		(pad "2" smd rect
			(at -0.5334 0)
			(size 0.7112 0.6096)
			(layers "B.Cu" "B.Mask" "B.Paste")
			(net "EEPROM_SDA")
		)
		(zone
			(layer "B.Cu")
			(hatch none 0.5)
			(connect_pads
				(clearance 0)
			)
			(min_thickness 0.25)
			(keepout
				(tracks allowed)
				(vias not_allowed)
				(pads allowed)
				(copperpour not_allowed)
				(footprints allowed)
			)
			(placement
				(enabled no)
				(sheetname "")
			)
			(fill
				(thermal_gap 0.5)
				(thermal_bridge_width 0.5)
				(island_removal_mode 0)
			)
			(polygon
				(pts
					(xy 30.27172 -16.42618) (xy 30.42412 -16.42618) (xy 30.42412 -17.03578) (xy 30.27172 -17.03578)
				)
			)
		)
	)
	(footprint ""
		(layer "B.Cu")
		(at 88.519 -83.312 180)
		(property "Reference" "R202"
			(at -0.254 5.54863 0)
			(unlocked yes)
			(layer "B.SilkS")
			(effects
				(font
					(size 0.7874 0.5842)
					(thickness 0.1524)
				)
				(justify mirror)
			)
		)
		(property "Value" "VAL*"
			(at -0.02032 2.13233 180)
			(unlocked yes)
			(layer "B.Fab")
			(hide yes)
			(effects
				(font
					(size 0.7874 0.5842)
					(thickness 0.1524)
				)
				(justify mirror)
			)
		)
		(property "Tolerance" "TOL*"
			(at -0.044704 3.05435 180)
			(unlocked yes)
			(layer "Cmts.User")
			(hide yes)
			(effects
				(font
					(size 0.7874 0.5842)
					(thickness 0.1524)
				)
				(justify mirror)
			)
		)
		(property "User Part Number" "PARTNUM*"
			(at -0.02032 4.024884 180)
			(unlocked yes)
			(layer "Cmts.User")
			(hide yes)
			(effects
				(font
					(size 0.7874 0.5842)
					(thickness 0.1524)
				)
				(justify mirror)
			)
		)
		(property "Device Type" "RESISTOR-G155-14701-01,4.7KOHMA"
			(at -0.008382 1.210564 180)
			(unlocked yes)
			(layer "B.Fab")
			(hide yes)
			(effects
				(font
					(size 0.7874 0.5842)
					(thickness 0.1524)
				)
				(justify mirror)
			)
		)
		(duplicate_pad_numbers_are_jumpers no)
		(fp_line
			(start 1.143 0.5588)
			(end -1.143 0.5588)
			(stroke
				(width 0.1)
				(type default)
			)
			(layer "B.SilkS")
		)
		(fp_line
			(start 1.143 -0.5588)
			(end 1.143 0.5588)
			(stroke
				(width 0.1)
				(type default)
			)
			(layer "B.SilkS")
		)
		(fp_line
			(start -1.143 0.5588)
			(end -1.143 -0.5588)
			(stroke
				(width 0.1)
				(type default)
			)
			(layer "B.SilkS")
		)
		(fp_line
			(start -1.143 -0.5588)
			(end 1.143 -0.5588)
			(stroke
				(width 0.1)
				(type default)
			)
			(layer "B.SilkS")
		)
		(fp_rect
			(start 1.143 -0.5588)
			(end -1.143 0.5588)
			(stroke
				(width 0)
				(type default)
			)
			(fill no)
			(layer "B.CrtYd")
		)
		(fp_line
			(start 0.508 0.3048)
			(end -0.508 0.3048)
			(stroke
				(width 0.1)
				(type default)
			)
			(layer "B.Fab")
		)
		(fp_line
			(start 0.508 -0.3048)
			(end 0.508 0.3048)
			(stroke
				(width 0.1)
				(type default)
			)
			(layer "B.Fab")
		)
		(fp_line
			(start -0.508 0.3048)
			(end -0.508 -0.3048)
			(stroke
				(width 0.1)
				(type default)
			)
			(layer "B.Fab")
		)
		(fp_line
			(start -0.508 -0.3048)
			(end 0.508 -0.3048)
			(stroke
				(width 0.1)
				(type default)
			)
			(layer "B.Fab")
		)
		(pad "1" smd rect
			(at 0.5334 0)
			(size 0.7112 0.6096)
			(layers "B.Cu" "B.Mask" "B.Paste")
			(net "UNNAMED_127_MT25QL128ABA1ESES_2")
		)
		(pad "2" smd rect
			(at -0.5334 0)
			(size 0.7112 0.6096)
			(layers "B.Cu" "B.Mask" "B.Paste")
			(net "XP3R3V_FPGA")
		)
		(zone
			(layer "B.Cu")
			(hatch none 0.5)
			(connect_pads
				(clearance 0)
			)
			(min_thickness 0.25)
			(keepout
				(tracks allowed)
				(vias not_allowed)
				(pads allowed)
				(copperpour not_allowed)
				(footprints allowed)
			)
			(placement
				(enabled no)
				(sheetname "")
			)
			(fill
				(thermal_gap 0.5)
				(thermal_bridge_width 0.5)
				(island_removal_mode 0)
			)
			(polygon
				(pts
					(xy 88.4428 -83.0072) (xy 88.5952 -83.0072) (xy 88.5952 -83.6168) (xy 88.4428 -83.6168)
				)
			)
		)
	)
	(footprint ""
		(layer "B.Cu")
		(at 139.6492 -83.5152)
		(property "Reference" "C299"
			(at 0.4318 -6.61543 0)
			(unlocked yes)
			(layer "B.SilkS")
			(effects
				(font
					(size 0.7874 0.5842)
					(thickness 0.1524)
				)
				(justify mirror)
			)
		)
		(property "Value" "VAL*"
			(at -0.0762 3.134106 0)
			(unlocked yes)
			(layer "B.Fab")
			(hide yes)
			(effects
				(font
					(size 0.7874 0.5842)
					(thickness 0.1524)
				)
				(justify mirror)
			)
		)
		(property "Device Type" "CAPACITOR-G107-0F106-EM,10UF,2A"
			(at -0.0508 2.194306 0)
			(unlocked yes)
			(layer "B.Fab")
			(hide yes)
			(effects
				(font
					(size 0.7874 0.5842)
					(thickness 0.1524)
				)
				(justify mirror)
			)
		)
		(property "User Part Number" "PARTNUM*"
			(at -0.1016 5.013706 0)
			(unlocked yes)
			(layer "Cmts.User")
			(hide yes)
			(effects
				(font
					(size 0.7874 0.5842)
					(thickness 0.1524)
				)
				(justify mirror)
			)
		)
		(property "Tolerance" "TOL*"
			(at -0.0762 4.048506 0)
			(unlocked yes)
			(layer "Cmts.User")
			(hide yes)
			(effects
				(font
					(size 0.7874 0.5842)
					(thickness 0.1524)
				)
				(justify mirror)
			)
		)
		(duplicate_pad_numbers_are_jumpers no)
		(fp_line
			(start -1.5748 -0.9398)
			(end 1.5748 -0.9398)
			(stroke
				(width 0.1)
				(type default)
			)
			(layer "B.SilkS")
		)
		(fp_line
			(start -1.5748 0.9398)
			(end -1.5748 -0.9398)
			(stroke
				(width 0.1)
				(type default)
			)
			(layer "B.SilkS")
		)
		(fp_line
			(start 1.5748 -0.9398)
			(end 1.5748 0.9398)
			(stroke
				(width 0.1)
				(type default)
			)
			(layer "B.SilkS")
		)
		(fp_line
			(start 1.5748 0.9398)
			(end -1.5748 0.9398)
			(stroke
				(width 0.1)
				(type default)
			)
			(layer "B.SilkS")
		)
		(fp_rect
			(start 1.5748 -0.9398)
			(end -1.5748 0.9398)
			(stroke
				(width 0)
				(type default)
			)
			(fill no)
			(layer "B.CrtYd")
		)
		(fp_line
			(start -1.016 -0.635)
			(end 1.016 -0.635)
			(stroke
				(width 0.1)
				(type default)
			)
			(layer "B.Fab")
		)
		(fp_line
			(start -1.016 0.635)
			(end -1.016 -0.635)
			(stroke
				(width 0.1)
				(type default)
			)
			(layer "B.Fab")
		)
		(fp_line
			(start 1.016 -0.635)
			(end 1.016 0.635)
			(stroke
				(width 0.1)
				(type default)
			)
			(layer "B.Fab")
		)
		(fp_line
			(start 1.016 0.635)
			(end -1.016 0.635)
			(stroke
				(width 0.1)
				(type default)
			)
			(layer "B.Fab")
		)
		(pad "1" smd rect
			(at 0.8382 0 180)
			(size 0.9652 1.3716)
			(layers "B.Cu" "B.Mask" "B.Paste")
			(net "XP12R0V_IN")
		)
		(pad "2" smd rect
			(at -0.8382 0 180)
			(size 0.9652 1.3716)
			(layers "B.Cu" "B.Mask" "B.Paste")
			(net "SG")
		)
		(zone
			(layer "B.Cu")
			(hatch none 0.5)
			(connect_pads
				(clearance 0)
			)
			(min_thickness 0.25)
			(keepout
				(tracks not_allowed)
				(vias allowed)
				(pads allowed)
				(copperpour not_allowed)
				(footprints allowed)
			)
			(placement
				(enabled no)
				(sheetname "")
			)
			(fill
				(thermal_gap 0.5)
				(thermal_bridge_width 0.5)
				(island_removal_mode 0)
			)
			(polygon
				(pts
					(xy 139.8778 -84.1502) (xy 139.4206 -84.1502) (xy 139.4206 -82.8802) (xy 139.8778 -82.8802)
				)
			)
		)
		(zone
			(layer "B.Cu")
			(hatch none 0.5)
			(connect_pads
				(clearance 0)
			)
			(min_thickness 0.25)
			(keepout
				(tracks allowed)
				(vias not_allowed)
				(pads allowed)
				(copperpour not_allowed)
				(footprints allowed)
			)
			(placement
				(enabled no)
				(sheetname "")
			)
			(fill
				(thermal_gap 0.5)
				(thermal_bridge_width 0.5)
				(island_removal_mode 0)
			)
			(polygon
				(pts
					(xy 139.8778 -84.1502) (xy 139.4206 -84.1502) (xy 139.4206 -82.8802) (xy 139.8778 -82.8802)
				)
			)
		)
	)
	(footprint ""
		(layer "B.Cu")
		(at 147.066 -107.696 90)
		(property "Reference" "R261"
			(at 0 1.99263 270)
			(unlocked yes)
			(layer "B.SilkS")
			(effects
				(font
					(size 0.7874 0.5842)
					(thickness 0.1524)
				)
				(justify mirror)
			)
		)
		(property "Value" "VAL*"
			(at -0.02032 2.13233 90)
			(unlocked yes)
			(layer "B.Fab")
			(hide yes)
			(effects
				(font
					(size 0.7874 0.5842)
					(thickness 0.1524)
				)
				(justify mirror)
			)
		)
		(property "Device Type" "RESISTOR-G155-13300-01,330OHM,A"
			(at -0.008382 1.210564 90)
			(unlocked yes)
			(layer "B.Fab")
			(hide yes)
			(effects
				(font
					(size 0.7874 0.5842)
					(thickness 0.1524)
				)
				(justify mirror)
			)
		)
		(property "User Part Number" "PARTNUM*"
			(at -0.02032 4.024884 90)
			(unlocked yes)
			(layer "Cmts.User")
			(hide yes)
			(effects
				(font
					(size 0.7874 0.5842)
					(thickness 0.1524)
				)
				(justify mirror)
			)
		)
		(property "Tolerance" "TOL*"
			(at -0.044704 3.05435 90)
			(unlocked yes)
			(layer "Cmts.User")
			(hide yes)
			(effects
				(font
					(size 0.7874 0.5842)
					(thickness 0.1524)
				)
				(justify mirror)
			)
		)
		(duplicate_pad_numbers_are_jumpers no)
		(fp_line
			(start 1.143 -0.5588)
			(end 1.143 0.5588)
			(stroke
				(width 0.1)
				(type default)
			)
			(layer "B.SilkS")
		)
		(fp_line
			(start -1.143 -0.5588)
			(end 1.143 -0.5588)
			(stroke
				(width 0.1)
				(type default)
			)
			(layer "B.SilkS")
		)
		(fp_line
			(start 1.143 0.5588)
			(end -1.143 0.5588)
			(stroke
				(width 0.1)
				(type default)
			)
			(layer "B.SilkS")
		)
		(fp_line
			(start -1.143 0.5588)
			(end -1.143 -0.5588)
			(stroke
				(width 0.1)
				(type default)
			)
			(layer "B.SilkS")
		)
		(fp_rect
			(start -1.143 -0.5588)
			(end 1.143 0.5588)
			(stroke
				(width 0)
				(type default)
			)
			(fill no)
			(layer "B.CrtYd")
		)
		(fp_line
			(start 0.508 -0.3048)
			(end 0.508 0.3048)
			(stroke
				(width 0.1)
				(type default)
			)
			(layer "B.Fab")
		)
		(fp_line
			(start -0.508 -0.3048)
			(end 0.508 -0.3048)
			(stroke
				(width 0.1)
				(type default)
			)
			(layer "B.Fab")
		)
		(fp_line
			(start 0.508 0.3048)
			(end -0.508 0.3048)
			(stroke
				(width 0.1)
				(type default)
			)
			(layer "B.Fab")
		)
		(fp_line
			(start -0.508 0.3048)
			(end -0.508 -0.3048)
			(stroke
				(width 0.1)
				(type default)
			)
			(layer "B.Fab")
		)
		(pad "1" smd rect
			(at 0.5334 0 270)
			(size 0.7112 0.6096)
			(layers "B.Cu" "B.Mask" "B.Paste")
			(net "UNNAMED_14_OPTICAL_I137_A")
		)
		(pad "2" smd rect
			(at -0.5334 0 270)
			(size 0.7112 0.6096)
			(layers "B.Cu" "B.Mask" "B.Paste")
			(net "XP3R3V_FPGA")
		)
		(zone
			(layer "B.Cu")
			(hatch none 0.5)
			(connect_pads
				(clearance 0)
			)
			(min_thickness 0.25)
			(keepout
				(tracks allowed)
				(vias not_allowed)
				(pads allowed)
				(copperpour not_allowed)
				(footprints allowed)
			)
			(placement
				(enabled no)
				(sheetname "")
			)
			(fill
				(thermal_gap 0.5)
				(thermal_bridge_width 0.5)
				(island_removal_mode 0)
			)
			(polygon
				(pts
					(xy 146.7612 -107.6198) (xy 147.3708 -107.6198) (xy 147.3708 -107.7722) (xy 146.7612 -107.7722)
				)
			)
		)
	)
	(footprint ""
		(layer "B.Cu")
		(at 100.347018 -46.823122 180)
		(property "Reference" "C203"
			(at 2.303018 -0.118872 0)
			(unlocked yes)
			(layer "B.SilkS")
			(effects
				(font
					(size 0.635 0.4064)
					(thickness 0.1524)
				)
				(justify mirror)
			)
		)
		(property "Value" "VAL*"
			(at 0 3.718306 180)
			(unlocked yes)
			(layer "B.Fab")
			(hide yes)
			(effects
				(font
					(size 0.7874 0.5842)
					(thickness 0.127)
				)
				(justify mirror)
			)
		)
		(property "Device Type" "CAPACITOR-G105-0B104-CK,0.1UF,A"
			(at 0 1.432306 180)
			(unlocked yes)
			(layer "B.Fab")
			(hide yes)
			(effects
				(font
					(size 0.7874 0.5842)
					(thickness 0.127)
				)
				(justify mirror)
			)
		)
		(property "User Part Number" "PARTNUM*"
			(at 0 2.575306 180)
			(unlocked yes)
			(layer "Cmts.User")
			(hide yes)
			(effects
				(font
					(size 0.7874 0.5842)
					(thickness 0.127)
				)
				(justify mirror)
			)
		)
		(property "Tolerance" "TOL*"
			(at 0 4.861306 180)
			(unlocked yes)
			(layer "Cmts.User")
			(hide yes)
			(effects
				(font
					(size 0.7874 0.5842)
					(thickness 0.127)
				)
				(justify mirror)
			)
		)
		(duplicate_pad_numbers_are_jumpers no)
		(fp_line
			(start 0.970026 0.4699)
			(end 0.970026 -0.4699)
			(stroke
				(width 0.1)
				(type default)
			)
			(layer "B.SilkS")
		)
		(fp_line
			(start 0.970026 -0.4699)
			(end -0.970026 -0.4699)
			(stroke
				(width 0.1)
				(type default)
			)
			(layer "B.SilkS")
		)
		(fp_line
			(start -0.970026 0.4699)
			(end 0.970026 0.4699)
			(stroke
				(width 0.1)
				(type default)
			)
			(layer "B.SilkS")
		)
		(fp_line
			(start -0.970026 -0.4699)
			(end -0.970026 0.4699)
			(stroke
				(width 0.1)
				(type default)
			)
			(layer "B.SilkS")
		)
		(fp_poly
			(pts
				(xy 0.970026 0.4699) (xy -0.970026 0.4699) (xy -0.970026 -0.4699) (xy 0.970026 -0.4699)
			)
			(stroke
				(width 0)
				(type default)
			)
			(fill no)
			(layer "B.CrtYd")
		)
		(fp_line
			(start 0.508 0.3048)
			(end 0.508 -0.3048)
			(stroke
				(width 0.1)
				(type default)
			)
			(layer "B.Fab")
		)
		(fp_line
			(start 0.508 -0.3048)
			(end -0.508 -0.3048)
			(stroke
				(width 0.1)
				(type default)
			)
			(layer "B.Fab")
		)
		(fp_line
			(start -0.508 0.3048)
			(end 0.508 0.3048)
			(stroke
				(width 0.1)
				(type default)
			)
			(layer "B.Fab")
		)
		(fp_line
			(start -0.508 -0.3048)
			(end -0.508 0.3048)
			(stroke
				(width 0.1)
				(type default)
			)
			(layer "B.Fab")
		)
		(pad "1" smd circle
			(at 0.500126 0)
			(size 0.635 0.635)
			(layers "B.Cu" "B.Mask" "B.Paste")
			(net "XP3R3V_FPGA")
		)
		(pad "2" smd circle
			(at -0.500126 0)
			(size 0.635 0.635)
			(layers "B.Cu" "B.Mask" "B.Paste")
			(net "SG")
		)
	)
	(footprint ""
		(layer "B.Cu")
		(at 111.847122 -34.32302 -90)
		(property "Reference" "C108"
			(at 2.06502 -0.008128 270)
			(unlocked yes)
			(layer "B.SilkS")
			(effects
				(font
					(size 0.635 0.4064)
					(thickness 0.1524)
				)
				(justify mirror)
			)
		)
		(property "Value" "VAL*"
			(at 0 3.718306 270)
			(unlocked yes)
			(layer "B.Fab")
			(hide yes)
			(effects
				(font
					(size 0.7874 0.5842)
					(thickness 0.127)
				)
				(justify mirror)
			)
		)
		(property "Tolerance" "TOL*"
			(at 0 4.861306 270)
			(unlocked yes)
			(layer "Cmts.User")
			(hide yes)
			(effects
				(font
					(size 0.7874 0.5842)
					(thickness 0.127)
				)
				(justify mirror)
			)
		)
		(property "User Part Number" "PARTNUM*"
			(at 0 2.575306 270)
			(unlocked yes)
			(layer "Cmts.User")
			(hide yes)
			(effects
				(font
					(size 0.7874 0.5842)
					(thickness 0.127)
				)
				(justify mirror)
			)
		)
		(property "Device Type" "CAPACITOR-G105-0B104-CK,0.1UF,A"
			(at 0 1.432306 270)
			(unlocked yes)
			(layer "B.Fab")
			(hide yes)
			(effects
				(font
					(size 0.7874 0.5842)
					(thickness 0.127)
				)
				(justify mirror)
			)
		)
		(duplicate_pad_numbers_are_jumpers no)
		(fp_line
			(start -0.970026 0.4699)
			(end 0.970026 0.4699)
			(stroke
				(width 0.1)
				(type default)
			)
			(layer "B.SilkS")
		)
		(fp_line
			(start 0.970026 0.4699)
			(end 0.970026 -0.4699)
			(stroke
				(width 0.1)
				(type default)
			)
			(layer "B.SilkS")
		)
		(fp_line
			(start -0.970026 -0.4699)
			(end -0.970026 0.4699)
			(stroke
				(width 0.1)
				(type default)
			)
			(layer "B.SilkS")
		)
		(fp_line
			(start 0.970026 -0.4699)
			(end -0.970026 -0.4699)
			(stroke
				(width 0.1)
				(type default)
			)
			(layer "B.SilkS")
		)
		(fp_poly
			(pts
				(xy 0.970026 0.4699) (xy -0.970026 0.4699) (xy -0.970026 -0.4699) (xy 0.970026 -0.4699)
			)
			(stroke
				(width 0)
				(type default)
			)
			(fill no)
			(layer "B.CrtYd")
		)
		(fp_line
			(start -0.508 0.3048)
			(end 0.508 0.3048)
			(stroke
				(width 0.1)
				(type default)
			)
			(layer "B.Fab")
		)
		(fp_line
			(start 0.508 0.3048)
			(end 0.508 -0.3048)
			(stroke
				(width 0.1)
				(type default)
			)
			(layer "B.Fab")
		)
		(fp_line
			(start -0.508 -0.3048)
			(end -0.508 0.3048)
			(stroke
				(width 0.1)
				(type default)
			)
			(layer "B.Fab")
		)
		(fp_line
			(start 0.508 -0.3048)
			(end -0.508 -0.3048)
			(stroke
				(width 0.1)
				(type default)
			)
			(layer "B.Fab")
		)
		(pad "1" smd circle
			(at 0.500126 0 90)
			(size 0.635 0.635)
			(layers "B.Cu" "B.Mask" "B.Paste")
			(net "XP2R5V_FPGA")
		)
		(pad "2" smd circle
			(at -0.500126 0 90)
			(size 0.635 0.635)
			(layers "B.Cu" "B.Mask" "B.Paste")
			(net "SG")
		)
	)
	(footprint ""
		(layer "B.Cu")
		(at 17.78 -86.487 90)
		(property "Reference" "C94"
			(at 0.127 1.23063 270)
			(unlocked yes)
			(layer "B.SilkS")
			(effects
				(font
					(size 0.7874 0.5842)
					(thickness 0.1524)
				)
				(justify mirror)
			)
		)
		(property "Value" "VAL*"
			(at -0.0762 2.067306 90)
			(unlocked yes)
			(layer "B.Fab")
			(hide yes)
			(effects
				(font
					(size 0.7874 0.5842)
					(thickness 0.1524)
				)
				(justify mirror)
			)
		)
		(property "Tolerance" "TOL*"
			(at -0.0762 3.032506 90)
			(unlocked yes)
			(layer "Cmts.User")
			(hide yes)
			(effects
				(font
					(size 0.7874 0.5842)
					(thickness 0.1524)
				)
				(justify mirror)
			)
		)
		(property "User Part Number" "PARTNUM*"
			(at -0.1016 4.023106 90)
			(unlocked yes)
			(layer "Cmts.User")
			(hide yes)
			(effects
				(font
					(size 0.7874 0.5842)
					(thickness 0.1524)
				)
				(justify mirror)
			)
		)
		(property "Device Type" "CAPACITOR-G105-0B104-EK,0.1UF,A"
			(at -0.0508 1.127506 90)
			(unlocked yes)
			(layer "B.Fab")
			(hide yes)
			(effects
				(font
					(size 0.7874 0.5842)
					(thickness 0.1524)
				)
				(justify mirror)
			)
		)
		(duplicate_pad_numbers_are_jumpers no)
		(fp_line
			(start 1.143 -0.5588)
			(end 1.143 0.5588)
			(stroke
				(width 0.1)
				(type default)
			)
			(layer "B.SilkS")
		)
		(fp_line
			(start -1.143 -0.5588)
			(end 1.143 -0.5588)
			(stroke
				(width 0.1)
				(type default)
			)
			(layer "B.SilkS")
		)
		(fp_line
			(start 1.143 0.5588)
			(end -1.143 0.5588)
			(stroke
				(width 0.1)
				(type default)
			)
			(layer "B.SilkS")
		)
		(fp_line
			(start -1.143 0.5588)
			(end -1.143 -0.5588)
			(stroke
				(width 0.1)
				(type default)
			)
			(layer "B.SilkS")
		)
		(fp_poly
			(pts
				(xy 1.143 0.5588) (xy -1.143 0.5588) (xy -1.143 -0.5588) (xy 1.143 -0.5588)
			)
			(stroke
				(width 0)
				(type default)
			)
			(fill no)
			(layer "B.CrtYd")
		)
		(fp_line
			(start 0.508 -0.3048)
			(end 0.508 0.3048)
			(stroke
				(width 0.1)
				(type default)
			)
			(layer "B.Fab")
		)
		(fp_line
			(start -0.508 -0.3048)
			(end 0.508 -0.3048)
			(stroke
				(width 0.1)
				(type default)
			)
			(layer "B.Fab")
		)
		(fp_line
			(start 0.508 0.3048)
			(end -0.508 0.3048)
			(stroke
				(width 0.1)
				(type default)
			)
			(layer "B.Fab")
		)
		(fp_line
			(start -0.508 0.3048)
			(end -0.508 -0.3048)
			(stroke
				(width 0.1)
				(type default)
			)
			(layer "B.Fab")
		)
		(pad "1" smd rect
			(at 0.5334 0 270)
			(size 0.7112 0.6096)
			(layers "B.Cu" "B.Mask" "B.Paste")
			(net "XP5R0V_FT4232")
		)
		(pad "2" smd rect
			(at -0.5334 0 270)
			(size 0.7112 0.6096)
			(layers "B.Cu" "B.Mask" "B.Paste")
			(net "SG")
		)
		(zone
			(layer "B.Cu")
			(hatch none 0.5)
			(connect_pads
				(clearance 0)
			)
			(min_thickness 0.25)
			(keepout
				(tracks not_allowed)
				(vias allowed)
				(pads allowed)
				(copperpour not_allowed)
				(footprints allowed)
			)
			(placement
				(enabled no)
				(sheetname "")
			)
			(fill
				(thermal_gap 0.5)
				(thermal_bridge_width 0.5)
				(island_removal_mode 0)
			)
			(polygon
				(pts
					(xy 18.0848 -86.5632) (xy 17.4752 -86.5632) (xy 17.4752 -86.4108) (xy 18.0848 -86.4108)
				)
			)
		)
		(zone
			(layer "B.Cu")
			(hatch none 0.5)
			(connect_pads
				(clearance 0)
			)
			(min_thickness 0.25)
			(keepout
				(tracks allowed)
				(vias not_allowed)
				(pads allowed)
				(copperpour not_allowed)
				(footprints allowed)
			)
			(placement
				(enabled no)
				(sheetname "")
			)
			(fill
				(thermal_gap 0.5)
				(thermal_bridge_width 0.5)
				(island_removal_mode 0)
			)
			(polygon
				(pts
					(xy 18.0848 -86.5632) (xy 17.4752 -86.5632) (xy 17.4752 -86.4108) (xy 18.0848 -86.4108)
				)
			)
		)
	)
	(footprint ""
		(layer "B.Cu")
		(at 89.9922 -98.7298)
		(property "Reference" "R54"
			(at 3.683 0.03937 0)
			(unlocked yes)
			(layer "B.SilkS")
			(effects
				(font
					(size 0.7874 0.5842)
					(thickness 0.1524)
				)
				(justify mirror)
			)
		)
		(property "Value" "VAL*"
			(at 0.0254 2.524506 0)
			(unlocked yes)
			(layer "B.Fab")
			(hide yes)
			(effects
				(font
					(size 0.7874 0.5842)
					(thickness 0.1524)
				)
				(justify mirror)
			)
		)
		(property "Tolerance" "TOL*"
			(at 0.0254 3.464306 0)
			(unlocked yes)
			(layer "Cmts.User")
			(hide yes)
			(effects
				(font
					(size 0.7874 0.5842)
					(thickness 0.1524)
				)
				(justify mirror)
			)
		)
		(property "User Part Number" "PARTNUM*"
			(at 0.0254 4.505706 0)
			(unlocked yes)
			(layer "Cmts.User")
			(hide yes)
			(effects
				(font
					(size 0.7874 0.5842)
					(thickness 0.1524)
				)
				(justify mirror)
			)
		)
		(property "Device Type" "RESISTOR-G156-100R0-J0,0OHM,-"
			(at 0 1.610106 0)
			(unlocked yes)
			(layer "B.Fab")
			(hide yes)
			(effects
				(font
					(size 0.7874 0.5842)
					(thickness 0.1524)
				)
				(justify mirror)
			)
		)
		(duplicate_pad_numbers_are_jumpers no)
		(fp_line
			(start -1.3208 -0.7112)
			(end -1.3208 0.7112)
			(stroke
				(width 0.1)
				(type default)
			)
			(layer "B.SilkS")
		)
		(fp_line
			(start -1.3208 0.7112)
			(end 1.3208 0.7112)
			(stroke
				(width 0.1)
				(type default)
			)
			(layer "B.SilkS")
		)
		(fp_line
			(start 1.3208 -0.7112)
			(end -1.3208 -0.7112)
			(stroke
				(width 0.1)
				(type default)
			)
			(layer "B.SilkS")
		)
		(fp_line
			(start 1.3208 0.7112)
			(end 1.3208 -0.7112)
			(stroke
				(width 0.1)
				(type default)
			)
			(layer "B.SilkS")
		)
		(fp_rect
			(start -1.3208 0.7112)
			(end 1.3208 -0.7112)
			(stroke
				(width 0)
				(type default)
			)
			(fill no)
			(layer "B.CrtYd")
		)
		(fp_line
			(start -0.8128 -0.4572)
			(end -0.8128 0.4572)
			(stroke
				(width 0.1)
				(type default)
			)
			(layer "B.Fab")
		)
		(fp_line
			(start -0.8128 0.4572)
			(end 0.8128 0.4572)
			(stroke
				(width 0.1)
				(type default)
			)
			(layer "B.Fab")
		)
		(fp_line
			(start 0.8128 -0.4572)
			(end -0.8128 -0.4572)
			(stroke
				(width 0.1)
				(type default)
			)
			(layer "B.Fab")
		)
		(fp_line
			(start 0.8128 0.4572)
			(end 0.8128 -0.4572)
			(stroke
				(width 0.1)
				(type default)
			)
			(layer "B.Fab")
		)
		(pad "1" smd rect
			(at 0.6858 0 180)
			(size 0.762 0.8636)
			(layers "B.Cu" "B.Mask" "B.Paste")
			(net "XP3R3V_AGND")
		)
		(pad "2" smd rect
			(at -0.6858 0 180)
			(size 0.762 0.8636)
			(layers "B.Cu" "B.Mask" "B.Paste")
			(net "XP3R3V_FB_R_TO_AGND")
		)
		(zone
			(layer "B.Cu")
			(hatch none 0.5)
			(connect_pads
				(clearance 0)
			)
			(min_thickness 0.25)
			(keepout
				(tracks allowed)
				(vias not_allowed)
				(pads allowed)
				(copperpour not_allowed)
				(footprints allowed)
			)
			(placement
				(enabled no)
				(sheetname "")
			)
			(fill
				(thermal_gap 0.5)
				(thermal_bridge_width 0.5)
				(island_removal_mode 0)
			)
			(polygon
				(pts
					(xy 89.8398 -98.2726) (xy 90.1446 -98.2726) (xy 90.1446 -99.187) (xy 89.8398 -99.187)
				)
			)
		)
	)
	(footprint ""
		(layer "B.Cu")
		(at 57.404 -16.51 -90)
		(property "Reference" "L21"
			(at -3.1115 -0.08763 270)
			(unlocked yes)
			(layer "B.SilkS")
			(effects
				(font
					(size 0.7874 0.5842)
					(thickness 0.1524)
				)
				(justify left mirror)
			)
		)
		(property "Value" "VAL*"
			(at 0.9398 3.70967 270)
			(unlocked yes)
			(layer "B.Fab")
			(hide yes)
			(effects
				(font
					(size 0.7874 0.5842)
					(thickness 0.1524)
				)
				(justify left mirror)
			)
		)
		(property "Device Type" "FERRITEBEAD-G191-10101-01,26OHA"
			(at 0.9906 1.22047 270)
			(unlocked yes)
			(layer "B.Fab")
			(hide yes)
			(effects
				(font
					(size 0.7874 0.5842)
					(thickness 0.1524)
				)
				(justify left mirror)
			)
		)
		(property "User Part Number" "PARTNUM*"
			(at 2.54 2.46507 270)
			(unlocked yes)
			(layer "Cmts.User")
			(hide yes)
			(effects
				(font
					(size 0.7874 0.5842)
					(thickness 0.1524)
				)
				(justify left mirror)
			)
		)
		(property "Tolerance" "TOL*"
			(at 0.9906 5.00507 270)
			(unlocked yes)
			(layer "Cmts.User")
			(hide yes)
			(effects
				(font
					(size 0.7874 0.5842)
					(thickness 0.1524)
				)
				(justify left mirror)
			)
		)
		(duplicate_pad_numbers_are_jumpers no)
		(fp_line
			(start -1.3208 0.7112)
			(end 1.3208 0.7112)
			(stroke
				(width 0.1)
				(type default)
			)
			(layer "B.SilkS")
		)
		(fp_line
			(start 1.3208 0.7112)
			(end 1.3208 -0.7112)
			(stroke
				(width 0.1)
				(type default)
			)
			(layer "B.SilkS")
		)
		(fp_line
			(start -1.3208 -0.7112)
			(end -1.3208 0.7112)
			(stroke
				(width 0.1)
				(type default)
			)
			(layer "B.SilkS")
		)
		(fp_line
			(start 1.3208 -0.7112)
			(end -1.3208 -0.7112)
			(stroke
				(width 0.1)
				(type default)
			)
			(layer "B.SilkS")
		)
		(fp_rect
			(start 1.3208 0.7112)
			(end -1.3208 -0.7112)
			(stroke
				(width 0)
				(type default)
			)
			(fill no)
			(layer "B.CrtYd")
		)
		(fp_line
			(start -0.8128 0.4572)
			(end 0.8128 0.4572)
			(stroke
				(width 0.1)
				(type default)
			)
			(layer "B.Fab")
		)
		(fp_line
			(start 0.8128 0.4572)
			(end 0.8128 -0.4572)
			(stroke
				(width 0.1)
				(type default)
			)
			(layer "B.Fab")
		)
		(fp_line
			(start -0.8128 -0.4572)
			(end -0.8128 0.4572)
			(stroke
				(width 0.1)
				(type default)
			)
			(layer "B.Fab")
		)
		(fp_line
			(start 0.8128 -0.4572)
			(end -0.8128 -0.4572)
			(stroke
				(width 0.1)
				(type default)
			)
			(layer "B.Fab")
		)
		(pad "1" smd rect
			(at 0.6858 0 90)
			(size 0.762 0.8636)
			(layers "B.Cu" "B.Mask" "B.Paste")
			(net "XP3R3V_PCIE")
		)
		(pad "2" smd rect
			(at -0.6858 0 90)
			(size 0.762 0.8636)
			(layers "B.Cu" "B.Mask" "B.Paste")
			(net "XP3R3V")
		)
		(zone
			(layer "B.Cu")
			(hatch none 0.5)
			(connect_pads
				(clearance 0)
			)
			(min_thickness 0.25)
			(keepout
				(tracks allowed)
				(vias not_allowed)
				(pads allowed)
				(copperpour not_allowed)
				(footprints allowed)
			)
			(placement
				(enabled no)
				(sheetname "")
			)
			(fill
				(thermal_gap 0.5)
				(thermal_bridge_width 0.5)
				(island_removal_mode 0)
			)
			(polygon
				(pts
					(xy 56.9468 -16.3576) (xy 57.8612 -16.3576) (xy 57.8612 -16.6624) (xy 56.9468 -16.6624)
				)
			)
		)
		(zone
			(layer "B.Cu")
			(hatch none 0.5)
			(connect_pads
				(clearance 0)
			)
			(min_thickness 0.25)
			(keepout
				(tracks not_allowed)
				(vias allowed)
				(pads allowed)
				(copperpour not_allowed)
				(footprints allowed)
			)
			(placement
				(enabled no)
				(sheetname "")
			)
			(fill
				(thermal_gap 0.5)
				(thermal_bridge_width 0.5)
				(island_removal_mode 0)
			)
			(polygon
				(pts
					(xy 56.9468 -16.3576) (xy 57.8612 -16.3576) (xy 57.8612 -16.6624) (xy 56.9468 -16.6624)
				)
			)
		)
	)
	(footprint ""
		(layer "B.Cu")
		(at 76.708 -52.07 180)
		(property "Reference" "C66"
			(at -3.175 0.21463 0)
			(unlocked yes)
			(layer "B.SilkS")
			(effects
				(font
					(size 0.7874 0.5842)
					(thickness 0.1524)
				)
				(justify mirror)
			)
		)
		(property "Value" "VAL*"
			(at -0.0762 2.067306 180)
			(unlocked yes)
			(layer "B.Fab")
			(hide yes)
			(effects
				(font
					(size 0.7874 0.5842)
					(thickness 0.1524)
				)
				(justify mirror)
			)
		)
		(property "Tolerance" "TOL*"
			(at -0.0762 3.032506 180)
			(unlocked yes)
			(layer "Cmts.User")
			(hide yes)
			(effects
				(font
					(size 0.7874 0.5842)
					(thickness 0.1524)
				)
				(justify mirror)
			)
		)
		(property "User Part Number" "PARTNUM*"
			(at -0.1016 4.023106 180)
			(unlocked yes)
			(layer "Cmts.User")
			(hide yes)
			(effects
				(font
					(size 0.7874 0.5842)
					(thickness 0.1524)
				)
				(justify mirror)
			)
		)
		(property "Device Type" "CAPACITOR-G105-0B104-EK,0.1UF,A"
			(at -0.0508 1.127506 180)
			(unlocked yes)
			(layer "B.Fab")
			(hide yes)
			(effects
				(font
					(size 0.7874 0.5842)
					(thickness 0.1524)
				)
				(justify mirror)
			)
		)
		(duplicate_pad_numbers_are_jumpers no)
		(fp_line
			(start 1.143 0.5588)
			(end -1.143 0.5588)
			(stroke
				(width 0.1)
				(type default)
			)
			(layer "B.SilkS")
		)
		(fp_line
			(start 1.143 -0.5588)
			(end 1.143 0.5588)
			(stroke
				(width 0.1)
				(type default)
			)
			(layer "B.SilkS")
		)
		(fp_line
			(start -1.143 0.5588)
			(end -1.143 -0.5588)
			(stroke
				(width 0.1)
				(type default)
			)
			(layer "B.SilkS")
		)
		(fp_line
			(start -1.143 -0.5588)
			(end 1.143 -0.5588)
			(stroke
				(width 0.1)
				(type default)
			)
			(layer "B.SilkS")
		)
		(fp_rect
			(start 1.143 0.5588)
			(end -1.143 -0.5588)
			(stroke
				(width 0)
				(type default)
			)
			(fill no)
			(layer "B.CrtYd")
		)
		(fp_line
			(start 0.508 0.3048)
			(end -0.508 0.3048)
			(stroke
				(width 0.1)
				(type default)
			)
			(layer "B.Fab")
		)
		(fp_line
			(start 0.508 -0.3048)
			(end 0.508 0.3048)
			(stroke
				(width 0.1)
				(type default)
			)
			(layer "B.Fab")
		)
		(fp_line
			(start -0.508 0.3048)
			(end -0.508 -0.3048)
			(stroke
				(width 0.1)
				(type default)
			)
			(layer "B.Fab")
		)
		(fp_line
			(start -0.508 -0.3048)
			(end 0.508 -0.3048)
			(stroke
				(width 0.1)
				(type default)
			)
			(layer "B.Fab")
		)
		(pad "1" smd rect
			(at 0.5334 0)
			(size 0.7112 0.6096)
			(layers "B.Cu" "B.Mask" "B.Paste")
			(net "XP5R0V_MAC_USB")
		)
		(pad "2" smd rect
			(at -0.5334 0)
			(size 0.7112 0.6096)
			(layers "B.Cu" "B.Mask" "B.Paste")
			(net "SG")
		)
		(zone
			(layer "B.Cu")
			(hatch none 0.5)
			(connect_pads
				(clearance 0)
			)
			(min_thickness 0.25)
			(keepout
				(tracks allowed)
				(vias not_allowed)
				(pads allowed)
				(copperpour not_allowed)
				(footprints allowed)
			)
			(placement
				(enabled no)
				(sheetname "")
			)
			(fill
				(thermal_gap 0.5)
				(thermal_bridge_width 0.5)
				(island_removal_mode 0)
			)
			(polygon
				(pts
					(xy 76.6318 -52.3748) (xy 76.6318 -51.7652) (xy 76.7842 -51.7652) (xy 76.7842 -52.3748)
				)
			)
		)
	)
	(footprint ""
		(layer "B.Cu")
		(at 84.709 -64.3128 90)
		(property "Reference" "R80"
			(at -0.3048 1.10363 270)
			(unlocked yes)
			(layer "B.SilkS")
			(effects
				(font
					(size 0.7874 0.5842)
					(thickness 0.1524)
				)
				(justify mirror)
			)
		)
		(property "Value" "VAL*"
			(at -0.02032 2.13233 90)
			(unlocked yes)
			(layer "B.Fab")
			(hide yes)
			(effects
				(font
					(size 0.7874 0.5842)
					(thickness 0.1524)
				)
				(justify mirror)
			)
		)
		(property "Device Type" "RESISTOR-G155-133R0-01,33OHM,1%"
			(at -0.008382 1.210564 90)
			(unlocked yes)
			(layer "B.Fab")
			(hide yes)
			(effects
				(font
					(size 0.7874 0.5842)
					(thickness 0.1524)
				)
				(justify mirror)
			)
		)
		(property "User Part Number" "PARTNUM*"
			(at -0.02032 4.024884 90)
			(unlocked yes)
			(layer "Cmts.User")
			(hide yes)
			(effects
				(font
					(size 0.7874 0.5842)
					(thickness 0.1524)
				)
				(justify mirror)
			)
		)
		(property "Tolerance" "TOL*"
			(at -0.044704 3.05435 90)
			(unlocked yes)
			(layer "Cmts.User")
			(hide yes)
			(effects
				(font
					(size 0.7874 0.5842)
					(thickness 0.1524)
				)
				(justify mirror)
			)
		)
		(duplicate_pad_numbers_are_jumpers no)
		(fp_line
			(start 1.143 -0.5588)
			(end 1.143 0.5588)
			(stroke
				(width 0.1)
				(type default)
			)
			(layer "B.SilkS")
		)
		(fp_line
			(start -1.143 -0.5588)
			(end 1.143 -0.5588)
			(stroke
				(width 0.1)
				(type default)
			)
			(layer "B.SilkS")
		)
		(fp_line
			(start 1.143 0.5588)
			(end -1.143 0.5588)
			(stroke
				(width 0.1)
				(type default)
			)
			(layer "B.SilkS")
		)
		(fp_line
			(start -1.143 0.5588)
			(end -1.143 -0.5588)
			(stroke
				(width 0.1)
				(type default)
			)
			(layer "B.SilkS")
		)
		(fp_rect
			(start -1.143 -0.5588)
			(end 1.143 0.5588)
			(stroke
				(width 0)
				(type default)
			)
			(fill no)
			(layer "B.CrtYd")
		)
		(fp_line
			(start 0.508 -0.3048)
			(end 0.508 0.3048)
			(stroke
				(width 0.1)
				(type default)
			)
			(layer "B.Fab")
		)
		(fp_line
			(start -0.508 -0.3048)
			(end 0.508 -0.3048)
			(stroke
				(width 0.1)
				(type default)
			)
			(layer "B.Fab")
		)
		(fp_line
			(start 0.508 0.3048)
			(end -0.508 0.3048)
			(stroke
				(width 0.1)
				(type default)
			)
			(layer "B.Fab")
		)
		(fp_line
			(start -0.508 0.3048)
			(end -0.508 -0.3048)
			(stroke
				(width 0.1)
				(type default)
			)
			(layer "B.Fab")
		)
		(pad "1" smd rect
			(at 0.5334 0 270)
			(size 0.7112 0.6096)
			(layers "B.Cu" "B.Mask" "B.Paste")
			(net "FPGA_OUT_BNO080_BOOT_N")
		)
		(pad "2" smd rect
			(at -0.5334 0 270)
			(size 0.7112 0.6096)
			(layers "B.Cu" "B.Mask" "B.Paste")
			(net "R_BNO080_BOOT_N")
		)
		(zone
			(layer "B.Cu")
			(hatch none 0.5)
			(connect_pads
				(clearance 0)
			)
			(min_thickness 0.25)
			(keepout
				(tracks allowed)
				(vias not_allowed)
				(pads allowed)
				(copperpour not_allowed)
				(footprints allowed)
			)
			(placement
				(enabled no)
				(sheetname "")
			)
			(fill
				(thermal_gap 0.5)
				(thermal_bridge_width 0.5)
				(island_removal_mode 0)
			)
			(polygon
				(pts
					(xy 84.4042 -64.2366) (xy 85.0138 -64.2366) (xy 85.0138 -64.389) (xy 84.4042 -64.389)
				)
			)
		)
	)
	(footprint ""
		(layer "B.Cu")
		(at 111.34725 -45.823124 180)
		(property "Reference" "C206"
			(at 43.14825 -1.023874 0)
			(unlocked yes)
			(layer "B.SilkS")
			(effects
				(font
					(size 0.635 0.4064)
					(thickness 0.1524)
				)
				(justify mirror)
			)
		)
		(property "Value" "VAL*"
			(at 0 3.718306 180)
			(unlocked yes)
			(layer "B.Fab")
			(hide yes)
			(effects
				(font
					(size 0.7874 0.5842)
					(thickness 0.127)
				)
				(justify mirror)
			)
		)
		(property "Device Type" "CAPACITOR-G105-0B104-CK,0.1UF,A"
			(at 0 1.432306 180)
			(unlocked yes)
			(layer "B.Fab")
			(hide yes)
			(effects
				(font
					(size 0.7874 0.5842)
					(thickness 0.127)
				)
				(justify mirror)
			)
		)
		(property "User Part Number" "PARTNUM*"
			(at 0 2.575306 180)
			(unlocked yes)
			(layer "Cmts.User")
			(hide yes)
			(effects
				(font
					(size 0.7874 0.5842)
					(thickness 0.127)
				)
				(justify mirror)
			)
		)
		(property "Tolerance" "TOL*"
			(at 0 4.861306 180)
			(unlocked yes)
			(layer "Cmts.User")
			(hide yes)
			(effects
				(font
					(size 0.7874 0.5842)
					(thickness 0.127)
				)
				(justify mirror)
			)
		)
		(duplicate_pad_numbers_are_jumpers no)
		(fp_line
			(start 0.970026 0.4699)
			(end 0.970026 -0.4699)
			(stroke
				(width 0.1)
				(type default)
			)
			(layer "B.SilkS")
		)
		(fp_line
			(start 0.970026 -0.4699)
			(end -0.970026 -0.4699)
			(stroke
				(width 0.1)
				(type default)
			)
			(layer "B.SilkS")
		)
		(fp_line
			(start -0.970026 0.4699)
			(end 0.970026 0.4699)
			(stroke
				(width 0.1)
				(type default)
			)
			(layer "B.SilkS")
		)
		(fp_line
			(start -0.970026 -0.4699)
			(end -0.970026 0.4699)
			(stroke
				(width 0.1)
				(type default)
			)
			(layer "B.SilkS")
		)
		(fp_poly
			(pts
				(xy 0.970026 0.4699) (xy -0.970026 0.4699) (xy -0.970026 -0.4699) (xy 0.970026 -0.4699)
			)
			(stroke
				(width 0)
				(type default)
			)
			(fill no)
			(layer "B.CrtYd")
		)
		(fp_line
			(start 0.508 0.3048)
			(end 0.508 -0.3048)
			(stroke
				(width 0.1)
				(type default)
			)
			(layer "B.Fab")
		)
		(fp_line
			(start 0.508 -0.3048)
			(end -0.508 -0.3048)
			(stroke
				(width 0.1)
				(type default)
			)
			(layer "B.Fab")
		)
		(fp_line
			(start -0.508 0.3048)
			(end 0.508 0.3048)
			(stroke
				(width 0.1)
				(type default)
			)
			(layer "B.Fab")
		)
		(fp_line
			(start -0.508 -0.3048)
			(end -0.508 0.3048)
			(stroke
				(width 0.1)
				(type default)
			)
			(layer "B.Fab")
		)
		(pad "1" smd circle
			(at 0.500126 0)
			(size 0.635 0.635)
			(layers "B.Cu" "B.Mask" "B.Paste")
			(net "XP1R8V_FPGA_VCCAUX")
		)
		(pad "2" smd circle
			(at -0.500126 0)
			(size 0.635 0.635)
			(layers "B.Cu" "B.Mask" "B.Paste")
			(net "SG")
		)
	)
	(footprint ""
		(layer "B.Cu")
		(at 136.906 -41.275 90)
		(property "Reference" "C178"
			(at 0.762 1.73863 270)
			(unlocked yes)
			(layer "B.SilkS")
			(effects
				(font
					(size 0.7874 0.5842)
					(thickness 0.1524)
				)
				(justify mirror)
			)
		)
		(property "Value" "VAL*"
			(at -0.0762 2.067306 90)
			(unlocked yes)
			(layer "B.Fab")
			(hide yes)
			(effects
				(font
					(size 0.7874 0.5842)
					(thickness 0.1524)
				)
				(justify mirror)
			)
		)
		(property "Tolerance" "TOL*"
			(at -0.0762 3.032506 90)
			(unlocked yes)
			(layer "Cmts.User")
			(hide yes)
			(effects
				(font
					(size 0.7874 0.5842)
					(thickness 0.1524)
				)
				(justify mirror)
			)
		)
		(property "User Part Number" "PARTNUM*"
			(at -0.1016 4.023106 90)
			(unlocked yes)
			(layer "Cmts.User")
			(hide yes)
			(effects
				(font
					(size 0.7874 0.5842)
					(thickness 0.1524)
				)
				(justify mirror)
			)
		)
		(property "Device Type" "CAPACITOR-G105-0B104-CK,0.1UF,A"
			(at -0.0508 1.127506 90)
			(unlocked yes)
			(layer "B.Fab")
			(hide yes)
			(effects
				(font
					(size 0.7874 0.5842)
					(thickness 0.1524)
				)
				(justify mirror)
			)
		)
		(duplicate_pad_numbers_are_jumpers no)
		(fp_line
			(start 1.143 -0.5588)
			(end 1.143 0.5588)
			(stroke
				(width 0.1)
				(type default)
			)
			(layer "B.SilkS")
		)
		(fp_line
			(start -1.143 -0.5588)
			(end 1.143 -0.5588)
			(stroke
				(width 0.1)
				(type default)
			)
			(layer "B.SilkS")
		)
		(fp_line
			(start 1.143 0.5588)
			(end -1.143 0.5588)
			(stroke
				(width 0.1)
				(type default)
			)
			(layer "B.SilkS")
		)
		(fp_line
			(start -1.143 0.5588)
			(end -1.143 -0.5588)
			(stroke
				(width 0.1)
				(type default)
			)
			(layer "B.SilkS")
		)
		(fp_rect
			(start 1.143 -0.5588)
			(end -1.143 0.5588)
			(stroke
				(width 0)
				(type default)
			)
			(fill no)
			(layer "B.CrtYd")
		)
		(fp_line
			(start 0.508 -0.3048)
			(end 0.508 0.3048)
			(stroke
				(width 0.1)
				(type default)
			)
			(layer "B.Fab")
		)
		(fp_line
			(start -0.508 -0.3048)
			(end 0.508 -0.3048)
			(stroke
				(width 0.1)
				(type default)
			)
			(layer "B.Fab")
		)
		(fp_line
			(start 0.508 0.3048)
			(end -0.508 0.3048)
			(stroke
				(width 0.1)
				(type default)
			)
			(layer "B.Fab")
		)
		(fp_line
			(start -0.508 0.3048)
			(end -0.508 -0.3048)
			(stroke
				(width 0.1)
				(type default)
			)
			(layer "B.Fab")
		)
		(pad "1" smd rect
			(at 0.5334 0 270)
			(size 0.7112 0.6096)
			(layers "B.Cu" "B.Mask" "B.Paste")
			(net "XP1R0V_FPGA")
		)
		(pad "2" smd rect
			(at -0.5334 0 270)
			(size 0.7112 0.6096)
			(layers "B.Cu" "B.Mask" "B.Paste")
			(net "SG")
		)
		(zone
			(layer "B.Cu")
			(hatch none 0.5)
			(connect_pads
				(clearance 0)
			)
			(min_thickness 0.25)
			(keepout
				(tracks allowed)
				(vias not_allowed)
				(pads allowed)
				(copperpour not_allowed)
				(footprints allowed)
			)
			(placement
				(enabled no)
				(sheetname "")
			)
			(fill
				(thermal_gap 0.5)
				(thermal_bridge_width 0.5)
				(island_removal_mode 0)
			)
			(polygon
				(pts
					(xy 136.6012 -41.3512) (xy 136.6012 -41.1988) (xy 137.2108 -41.1988) (xy 137.2108 -41.3512)
				)
			)
		)
	)
	(footprint ""
		(layer "B.Cu")
		(at 100.347018 -38.823138 180)
		(property "Reference" "C117"
			(at 42.562018 -1.008888 0)
			(unlocked yes)
			(layer "B.SilkS")
			(effects
				(font
					(size 0.635 0.4064)
					(thickness 0.1524)
				)
				(justify mirror)
			)
		)
		(property "Value" "VAL*"
			(at 0 3.718306 180)
			(unlocked yes)
			(layer "B.Fab")
			(hide yes)
			(effects
				(font
					(size 0.7874 0.5842)
					(thickness 0.127)
				)
				(justify mirror)
			)
		)
		(property "Tolerance" "TOL*"
			(at 0 4.861306 180)
			(unlocked yes)
			(layer "Cmts.User")
			(hide yes)
			(effects
				(font
					(size 0.7874 0.5842)
					(thickness 0.127)
				)
				(justify mirror)
			)
		)
		(property "User Part Number" "PARTNUM*"
			(at 0 2.575306 180)
			(unlocked yes)
			(layer "Cmts.User")
			(hide yes)
			(effects
				(font
					(size 0.7874 0.5842)
					(thickness 0.127)
				)
				(justify mirror)
			)
		)
		(property "Device Type" "CAPACITOR-G105-0F475-BM,4.7UF,A"
			(at 0 1.432306 180)
			(unlocked yes)
			(layer "B.Fab")
			(hide yes)
			(effects
				(font
					(size 0.7874 0.5842)
					(thickness 0.127)
				)
				(justify mirror)
			)
		)
		(duplicate_pad_numbers_are_jumpers no)
		(fp_line
			(start 0.970026 0.4699)
			(end 0.970026 -0.4699)
			(stroke
				(width 0.1)
				(type default)
			)
			(layer "B.SilkS")
		)
		(fp_line
			(start 0.970026 -0.4699)
			(end -0.970026 -0.4699)
			(stroke
				(width 0.1)
				(type default)
			)
			(layer "B.SilkS")
		)
		(fp_line
			(start -0.970026 0.4699)
			(end 0.970026 0.4699)
			(stroke
				(width 0.1)
				(type default)
			)
			(layer "B.SilkS")
		)
		(fp_line
			(start -0.970026 -0.4699)
			(end -0.970026 0.4699)
			(stroke
				(width 0.1)
				(type default)
			)
			(layer "B.SilkS")
		)
		(fp_poly
			(pts
				(xy 0.970026 0.4699) (xy -0.970026 0.4699) (xy -0.970026 -0.4699) (xy 0.970026 -0.4699)
			)
			(stroke
				(width 0)
				(type default)
			)
			(fill no)
			(layer "B.CrtYd")
		)
		(fp_line
			(start 0.508 0.3048)
			(end 0.508 -0.3048)
			(stroke
				(width 0.1)
				(type default)
			)
			(layer "B.Fab")
		)
		(fp_line
			(start 0.508 -0.3048)
			(end -0.508 -0.3048)
			(stroke
				(width 0.1)
				(type default)
			)
			(layer "B.Fab")
		)
		(fp_line
			(start -0.508 0.3048)
			(end 0.508 0.3048)
			(stroke
				(width 0.1)
				(type default)
			)
			(layer "B.Fab")
		)
		(fp_line
			(start -0.508 -0.3048)
			(end -0.508 0.3048)
			(stroke
				(width 0.1)
				(type default)
			)
			(layer "B.Fab")
		)
		(pad "1" smd circle
			(at 0.500126 0)
			(size 0.635 0.635)
			(layers "B.Cu" "B.Mask" "B.Paste")
			(net "FPGA_MGTAVTT")
		)
		(pad "2" smd circle
			(at -0.500126 0)
			(size 0.635 0.635)
			(layers "B.Cu" "B.Mask" "B.Paste")
			(net "SG")
		)
	)
	(footprint ""
		(layer "B.Cu")
		(at 99.3648 -78.5368 180)
		(property "Reference" "R165"
			(at -0.5842 -2.37617 0)
			(unlocked yes)
			(layer "B.SilkS")
			(effects
				(font
					(size 0.7874 0.5842)
					(thickness 0.1524)
				)
				(justify mirror)
			)
		)
		(property "Value" "VAL*"
			(at -0.02032 2.13233 180)
			(unlocked yes)
			(layer "B.Fab")
			(hide yes)
			(effects
				(font
					(size 0.7874 0.5842)
					(thickness 0.1524)
				)
				(justify mirror)
			)
		)
		(property "Tolerance" "TOL*"
			(at -0.044704 3.05435 180)
			(unlocked yes)
			(layer "Cmts.User")
			(hide yes)
			(effects
				(font
					(size 0.7874 0.5842)
					(thickness 0.1524)
				)
				(justify mirror)
			)
		)
		(property "User Part Number" "PARTNUM*"
			(at -0.02032 4.024884 180)
			(unlocked yes)
			(layer "Cmts.User")
			(hide yes)
			(effects
				(font
					(size 0.7874 0.5842)
					(thickness 0.1524)
				)
				(justify mirror)
			)
		)
		(property "Device Type" "RESISTOR-G155-11002-01,10KOHM,A"
			(at -0.008382 1.210564 180)
			(unlocked yes)
			(layer "B.Fab")
			(hide yes)
			(effects
				(font
					(size 0.7874 0.5842)
					(thickness 0.1524)
				)
				(justify mirror)
			)
		)
		(duplicate_pad_numbers_are_jumpers no)
		(fp_line
			(start 1.143 0.5588)
			(end -1.143 0.5588)
			(stroke
				(width 0.1)
				(type default)
			)
			(layer "B.SilkS")
		)
		(fp_line
			(start 1.143 -0.5588)
			(end 1.143 0.5588)
			(stroke
				(width 0.1)
				(type default)
			)
			(layer "B.SilkS")
		)
		(fp_line
			(start -1.143 0.5588)
			(end -1.143 -0.5588)
			(stroke
				(width 0.1)
				(type default)
			)
			(layer "B.SilkS")
		)
		(fp_line
			(start -1.143 -0.5588)
			(end 1.143 -0.5588)
			(stroke
				(width 0.1)
				(type default)
			)
			(layer "B.SilkS")
		)
		(fp_rect
			(start 1.143 0.5588)
			(end -1.143 -0.5588)
			(stroke
				(width 0)
				(type default)
			)
			(fill no)
			(layer "B.CrtYd")
		)
		(fp_line
			(start 0.508 0.3048)
			(end -0.508 0.3048)
			(stroke
				(width 0.1)
				(type default)
			)
			(layer "B.Fab")
		)
		(fp_line
			(start 0.508 -0.3048)
			(end 0.508 0.3048)
			(stroke
				(width 0.1)
				(type default)
			)
			(layer "B.Fab")
		)
		(fp_line
			(start -0.508 0.3048)
			(end -0.508 -0.3048)
			(stroke
				(width 0.1)
				(type default)
			)
			(layer "B.Fab")
		)
		(fp_line
			(start -0.508 -0.3048)
			(end 0.508 -0.3048)
			(stroke
				(width 0.1)
				(type default)
			)
			(layer "B.Fab")
		)
		(pad "1" smd rect
			(at 0.5334 0)
			(size 0.7112 0.6096)
			(layers "B.Cu" "B.Mask" "B.Paste")
			(net "XP1R2V_EN_R")
		)
		(pad "2" smd rect
			(at -0.5334 0)
			(size 0.7112 0.6096)
			(layers "B.Cu" "B.Mask" "B.Paste")
			(net "SG")
		)
		(zone
			(layer "B.Cu")
			(hatch none 0.5)
			(connect_pads
				(clearance 0)
			)
			(min_thickness 0.25)
			(keepout
				(tracks allowed)
				(vias not_allowed)
				(pads allowed)
				(copperpour not_allowed)
				(footprints allowed)
			)
			(placement
				(enabled no)
				(sheetname "")
			)
			(fill
				(thermal_gap 0.5)
				(thermal_bridge_width 0.5)
				(island_removal_mode 0)
			)
			(polygon
				(pts
					(xy 99.2886 -78.8416) (xy 99.2886 -78.232) (xy 99.441 -78.232) (xy 99.441 -78.8416)
				)
			)
		)
	)
	(footprint ""
		(layer "B.Cu")
		(at 95.758 -20.066 90)
		(property "Reference" "C245"
			(at -0.381 2.11963 270)
			(unlocked yes)
			(layer "B.SilkS")
			(effects
				(font
					(size 0.7874 0.5842)
					(thickness 0.1524)
				)
				(justify mirror)
			)
		)
		(property "Value" "VAL*"
			(at -0.0762 2.067306 90)
			(unlocked yes)
			(layer "B.Fab")
			(hide yes)
			(effects
				(font
					(size 0.7874 0.5842)
					(thickness 0.1524)
				)
				(justify mirror)
			)
		)
		(property "Device Type" "CAPACITOR-G105-0B104-EK,0.1UF,A"
			(at -0.0508 1.127506 90)
			(unlocked yes)
			(layer "B.Fab")
			(hide yes)
			(effects
				(font
					(size 0.7874 0.5842)
					(thickness 0.1524)
				)
				(justify mirror)
			)
		)
		(property "User Part Number" "PARTNUM*"
			(at -0.1016 4.023106 90)
			(unlocked yes)
			(layer "Cmts.User")
			(hide yes)
			(effects
				(font
					(size 0.7874 0.5842)
					(thickness 0.1524)
				)
				(justify mirror)
			)
		)
		(property "Tolerance" "TOL*"
			(at -0.0762 3.032506 90)
			(unlocked yes)
			(layer "Cmts.User")
			(hide yes)
			(effects
				(font
					(size 0.7874 0.5842)
					(thickness 0.1524)
				)
				(justify mirror)
			)
		)
		(duplicate_pad_numbers_are_jumpers no)
		(fp_line
			(start 1.143 -0.5588)
			(end 1.143 0.5588)
			(stroke
				(width 0.1)
				(type default)
			)
			(layer "B.SilkS")
		)
		(fp_line
			(start -1.143 -0.5588)
			(end 1.143 -0.5588)
			(stroke
				(width 0.1)
				(type default)
			)
			(layer "B.SilkS")
		)
		(fp_line
			(start 1.143 0.5588)
			(end -1.143 0.5588)
			(stroke
				(width 0.1)
				(type default)
			)
			(layer "B.SilkS")
		)
		(fp_line
			(start -1.143 0.5588)
			(end -1.143 -0.5588)
			(stroke
				(width 0.1)
				(type default)
			)
			(layer "B.SilkS")
		)
		(fp_rect
			(start -1.143 -0.5588)
			(end 1.143 0.5588)
			(stroke
				(width 0)
				(type default)
			)
			(fill no)
			(layer "B.CrtYd")
		)
		(fp_line
			(start 0.508 -0.3048)
			(end 0.508 0.3048)
			(stroke
				(width 0.1)
				(type default)
			)
			(layer "B.Fab")
		)
		(fp_line
			(start -0.508 -0.3048)
			(end 0.508 -0.3048)
			(stroke
				(width 0.1)
				(type default)
			)
			(layer "B.Fab")
		)
		(fp_line
			(start 0.508 0.3048)
			(end -0.508 0.3048)
			(stroke
				(width 0.1)
				(type default)
			)
			(layer "B.Fab")
		)
		(fp_line
			(start -0.508 0.3048)
			(end -0.508 -0.3048)
			(stroke
				(width 0.1)
				(type default)
			)
			(layer "B.Fab")
		)
		(pad "1" smd rect
			(at 0.5334 0 270)
			(size 0.7112 0.6096)
			(layers "B.Cu" "B.Mask" "B.Paste")
			(net "XP3R3V")
		)
		(pad "2" smd rect
			(at -0.5334 0 270)
			(size 0.7112 0.6096)
			(layers "B.Cu" "B.Mask" "B.Paste")
			(net "SG")
		)
		(zone
			(layer "B.Cu")
			(hatch none 0.5)
			(connect_pads
				(clearance 0)
			)
			(min_thickness 0.25)
			(keepout
				(tracks allowed)
				(vias not_allowed)
				(pads allowed)
				(copperpour not_allowed)
				(footprints allowed)
			)
			(placement
				(enabled no)
				(sheetname "")
			)
			(fill
				(thermal_gap 0.5)
				(thermal_bridge_width 0.5)
				(island_removal_mode 0)
			)
			(polygon
				(pts
					(xy 95.4532 -19.9898) (xy 96.0628 -19.9898) (xy 96.0628 -20.1422) (xy 95.4532 -20.1422)
				)
			)
		)
	)
	(footprint ""
		(layer "B.Cu")
		(at 33.7693 -16.7132)
		(property "Reference" "R175"
			(at 0.7747 1.89357 0)
			(unlocked yes)
			(layer "B.SilkS")
			(effects
				(font
					(size 0.7874 0.5842)
					(thickness 0.1524)
				)
				(justify mirror)
			)
		)
		(property "Value" "VAL*"
			(at -0.02032 2.13233 0)
			(unlocked yes)
			(layer "B.Fab")
			(hide yes)
			(effects
				(font
					(size 0.7874 0.5842)
					(thickness 0.1524)
				)
				(justify mirror)
			)
		)
		(property "Tolerance" "TOL*"
			(at -0.044704 3.05435 0)
			(unlocked yes)
			(layer "Cmts.User")
			(hide yes)
			(effects
				(font
					(size 0.7874 0.5842)
					(thickness 0.1524)
				)
				(justify mirror)
			)
		)
		(property "User Part Number" "PARTNUM*"
			(at -0.02032 4.024884 0)
			(unlocked yes)
			(layer "Cmts.User")
			(hide yes)
			(effects
				(font
					(size 0.7874 0.5842)
					(thickness 0.1524)
				)
				(justify mirror)
			)
		)
		(property "Device Type" "RESISTOR-G155-133R0-01,33OHM,1%"
			(at -0.008382 1.210564 0)
			(unlocked yes)
			(layer "B.Fab")
			(hide yes)
			(effects
				(font
					(size 0.7874 0.5842)
					(thickness 0.1524)
				)
				(justify mirror)
			)
		)
		(duplicate_pad_numbers_are_jumpers no)
		(fp_line
			(start -1.143 -0.5588)
			(end 1.143 -0.5588)
			(stroke
				(width 0.1)
				(type default)
			)
			(layer "B.SilkS")
		)
		(fp_line
			(start -1.143 0.5588)
			(end -1.143 -0.5588)
			(stroke
				(width 0.1)
				(type default)
			)
			(layer "B.SilkS")
		)
		(fp_line
			(start 1.143 -0.5588)
			(end 1.143 0.5588)
			(stroke
				(width 0.1)
				(type default)
			)
			(layer "B.SilkS")
		)
		(fp_line
			(start 1.143 0.5588)
			(end -1.143 0.5588)
			(stroke
				(width 0.1)
				(type default)
			)
			(layer "B.SilkS")
		)
		(fp_rect
			(start -1.143 0.5588)
			(end 1.143 -0.5588)
			(stroke
				(width 0)
				(type default)
			)
			(fill no)
			(layer "B.CrtYd")
		)
		(fp_line
			(start -0.508 -0.3048)
			(end 0.508 -0.3048)
			(stroke
				(width 0.1)
				(type default)
			)
			(layer "B.Fab")
		)
		(fp_line
			(start -0.508 0.3048)
			(end -0.508 -0.3048)
			(stroke
				(width 0.1)
				(type default)
			)
			(layer "B.Fab")
		)
		(fp_line
			(start 0.508 -0.3048)
			(end 0.508 0.3048)
			(stroke
				(width 0.1)
				(type default)
			)
			(layer "B.Fab")
		)
		(fp_line
			(start 0.508 0.3048)
			(end -0.508 0.3048)
			(stroke
				(width 0.1)
				(type default)
			)
			(layer "B.Fab")
		)
		(pad "1" smd rect
			(at 0.5334 0 180)
			(size 0.7112 0.6096)
			(layers "B.Cu" "B.Mask" "B.Paste")
			(net "PCIE_SMDAT")
		)
		(pad "2" smd rect
			(at -0.5334 0 180)
			(size 0.7112 0.6096)
			(layers "B.Cu" "B.Mask" "B.Paste")
			(net "EEPROM_SDA")
		)
		(zone
			(layer "B.Cu")
			(hatch none 0.5)
			(connect_pads
				(clearance 0)
			)
			(min_thickness 0.25)
			(keepout
				(tracks allowed)
				(vias not_allowed)
				(pads allowed)
				(copperpour not_allowed)
				(footprints allowed)
			)
			(placement
				(enabled no)
				(sheetname "")
			)
			(fill
				(thermal_gap 0.5)
				(thermal_bridge_width 0.5)
				(island_removal_mode 0)
			)
			(polygon
				(pts
					(xy 33.6931 -16.4084) (xy 33.8455 -16.4084) (xy 33.8455 -17.018) (xy 33.6931 -17.018)
				)
			)
		)
	)
	(footprint ""
		(layer "B.Cu")
		(at 24.13 -91.059 -90)
		(property "Reference" "R467"
			(at -2.286 5.11937 270)
			(unlocked yes)
			(layer "B.SilkS")
			(effects
				(font
					(size 0.7874 0.5842)
					(thickness 0.1524)
				)
				(justify mirror)
			)
		)
		(property "Value" "VAL*"
			(at -0.02032 2.13233 270)
			(unlocked yes)
			(layer "B.Fab")
			(hide yes)
			(effects
				(font
					(size 0.7874 0.5842)
					(thickness 0.1524)
				)
				(justify mirror)
			)
		)
		(property "Tolerance" "TOL*"
			(at -0.044704 3.05435 270)
			(unlocked yes)
			(layer "Cmts.User")
			(hide yes)
			(effects
				(font
					(size 0.7874 0.5842)
					(thickness 0.1524)
				)
				(justify mirror)
			)
		)
		(property "User Part Number" "PARTNUM*"
			(at -0.02032 4.024884 270)
			(unlocked yes)
			(layer "Cmts.User")
			(hide yes)
			(effects
				(font
					(size 0.7874 0.5842)
					(thickness 0.1524)
				)
				(justify mirror)
			)
		)
		(property "Device Type" "RESISTOR-G155-133R0-01,33OHM,1%"
			(at -0.008382 1.210564 270)
			(unlocked yes)
			(layer "B.Fab")
			(hide yes)
			(effects
				(font
					(size 0.7874 0.5842)
					(thickness 0.1524)
				)
				(justify mirror)
			)
		)
		(duplicate_pad_numbers_are_jumpers no)
		(fp_line
			(start -1.143 0.5588)
			(end -1.143 -0.5588)
			(stroke
				(width 0.1)
				(type default)
			)
			(layer "B.SilkS")
		)
		(fp_line
			(start 1.143 0.5588)
			(end -1.143 0.5588)
			(stroke
				(width 0.1)
				(type default)
			)
			(layer "B.SilkS")
		)
		(fp_line
			(start -1.143 -0.5588)
			(end 1.143 -0.5588)
			(stroke
				(width 0.1)
				(type default)
			)
			(layer "B.SilkS")
		)
		(fp_line
			(start 1.143 -0.5588)
			(end 1.143 0.5588)
			(stroke
				(width 0.1)
				(type default)
			)
			(layer "B.SilkS")
		)
		(fp_poly
			(pts
				(xy 1.143 0.5588) (xy -1.143 0.5588) (xy -1.143 -0.5588) (xy 1.143 -0.5588)
			)
			(stroke
				(width 0)
				(type default)
			)
			(fill no)
			(layer "B.CrtYd")
		)
		(fp_line
			(start -0.508 0.3048)
			(end -0.508 -0.3048)
			(stroke
				(width 0.1)
				(type default)
			)
			(layer "B.Fab")
		)
		(fp_line
			(start 0.508 0.3048)
			(end -0.508 0.3048)
			(stroke
				(width 0.1)
				(type default)
			)
			(layer "B.Fab")
		)
		(fp_line
			(start -0.508 -0.3048)
			(end 0.508 -0.3048)
			(stroke
				(width 0.1)
				(type default)
			)
			(layer "B.Fab")
		)
		(fp_line
			(start 0.508 -0.3048)
			(end 0.508 0.3048)
			(stroke
				(width 0.1)
				(type default)
			)
			(layer "B.Fab")
		)
		(pad "1" smd rect
			(at 0.5334 0 90)
			(size 0.7112 0.6096)
			(layers "B.Cu" "B.Mask" "B.Paste")
			(net "R_FT4232_TCK")
		)
		(pad "2" smd rect
			(at -0.5334 0 90)
			(size 0.7112 0.6096)
			(layers "B.Cu" "B.Mask" "B.Paste")
			(net "FT4232_TCK_SCLK")
		)
		(zone
			(layer "B.Cu")
			(hatch none 0.5)
			(connect_pads
				(clearance 0)
			)
			(min_thickness 0.25)
			(keepout
				(tracks allowed)
				(vias not_allowed)
				(pads allowed)
				(copperpour not_allowed)
				(footprints allowed)
			)
			(placement
				(enabled no)
				(sheetname "")
			)
			(fill
				(thermal_gap 0.5)
				(thermal_bridge_width 0.5)
				(island_removal_mode 0)
			)
			(polygon
				(pts
					(xy 23.8252 -90.9828) (xy 24.4348 -90.9828) (xy 24.4348 -91.1352) (xy 23.8252 -91.1352)
				)
			)
		)
		(zone
			(layer "B.Cu")
			(hatch none 0.5)
			(connect_pads
				(clearance 0)
			)
			(min_thickness 0.25)
			(keepout
				(tracks not_allowed)
				(vias allowed)
				(pads allowed)
				(copperpour not_allowed)
				(footprints allowed)
			)
			(placement
				(enabled no)
				(sheetname "")
			)
			(fill
				(thermal_gap 0.5)
				(thermal_bridge_width 0.5)
				(island_removal_mode 0)
			)
			(polygon
				(pts
					(xy 23.8252 -90.9828) (xy 24.4348 -90.9828) (xy 24.4348 -91.1352) (xy 23.8252 -91.1352)
				)
			)
		)
	)
	(footprint ""
		(layer "B.Cu")
		(at 117.347238 -48.823118 180)
		(property "Reference" "C215"
			(at 0.634238 1.945132 0)
			(unlocked yes)
			(layer "B.SilkS")
			(effects
				(font
					(size 0.635 0.4064)
					(thickness 0.1524)
				)
				(justify mirror)
			)
		)
		(property "Value" "VAL*"
			(at 0 3.718306 180)
			(unlocked yes)
			(layer "B.Fab")
			(hide yes)
			(effects
				(font
					(size 0.7874 0.5842)
					(thickness 0.127)
				)
				(justify mirror)
			)
		)
		(property "Tolerance" "TOL*"
			(at 0 4.861306 180)
			(unlocked yes)
			(layer "Cmts.User")
			(hide yes)
			(effects
				(font
					(size 0.7874 0.5842)
					(thickness 0.127)
				)
				(justify mirror)
			)
		)
		(property "User Part Number" "PARTNUM*"
			(at 0 2.575306 180)
			(unlocked yes)
			(layer "Cmts.User")
			(hide yes)
			(effects
				(font
					(size 0.7874 0.5842)
					(thickness 0.127)
				)
				(justify mirror)
			)
		)
		(property "Device Type" "CAPACITOR-G105-0B104-CK,0.1UF,A"
			(at 0 1.432306 180)
			(unlocked yes)
			(layer "B.Fab")
			(hide yes)
			(effects
				(font
					(size 0.7874 0.5842)
					(thickness 0.127)
				)
				(justify mirror)
			)
		)
		(duplicate_pad_numbers_are_jumpers no)
		(fp_line
			(start 0.970026 0.4699)
			(end 0.970026 -0.4699)
			(stroke
				(width 0.1)
				(type default)
			)
			(layer "B.SilkS")
		)
		(fp_line
			(start 0.970026 -0.4699)
			(end -0.970026 -0.4699)
			(stroke
				(width 0.1)
				(type default)
			)
			(layer "B.SilkS")
		)
		(fp_line
			(start -0.970026 0.4699)
			(end 0.970026 0.4699)
			(stroke
				(width 0.1)
				(type default)
			)
			(layer "B.SilkS")
		)
		(fp_line
			(start -0.970026 -0.4699)
			(end -0.970026 0.4699)
			(stroke
				(width 0.1)
				(type default)
			)
			(layer "B.SilkS")
		)
		(fp_poly
			(pts
				(xy 0.970026 0.4699) (xy -0.970026 0.4699) (xy -0.970026 -0.4699) (xy 0.970026 -0.4699)
			)
			(stroke
				(width 0)
				(type default)
			)
			(fill no)
			(layer "B.CrtYd")
		)
		(fp_line
			(start 0.508 0.3048)
			(end 0.508 -0.3048)
			(stroke
				(width 0.1)
				(type default)
			)
			(layer "B.Fab")
		)
		(fp_line
			(start 0.508 -0.3048)
			(end -0.508 -0.3048)
			(stroke
				(width 0.1)
				(type default)
			)
			(layer "B.Fab")
		)
		(fp_line
			(start -0.508 0.3048)
			(end 0.508 0.3048)
			(stroke
				(width 0.1)
				(type default)
			)
			(layer "B.Fab")
		)
		(fp_line
			(start -0.508 -0.3048)
			(end -0.508 0.3048)
			(stroke
				(width 0.1)
				(type default)
			)
			(layer "B.Fab")
		)
		(pad "1" smd circle
			(at 0.500126 0)
			(size 0.635 0.635)
			(layers "B.Cu" "B.Mask" "B.Paste")
			(net "XP3R3V_FPGA")
		)
		(pad "2" smd circle
			(at -0.500126 0)
			(size 0.635 0.635)
			(layers "B.Cu" "B.Mask" "B.Paste")
			(net "SG")
		)
	)
	(footprint ""
		(layer "B.Cu")
		(at 36.9824 -100.2284)
		(property "Reference" "R48"
			(at -4.0386 0.64897 0)
			(unlocked yes)
			(layer "B.SilkS")
			(effects
				(font
					(size 0.7874 0.5842)
					(thickness 0.1524)
				)
				(justify mirror)
			)
		)
		(property "Value" "VAL*"
			(at -0.02032 2.13233 0)
			(unlocked yes)
			(layer "B.Fab")
			(hide yes)
			(effects
				(font
					(size 0.7874 0.5842)
					(thickness 0.1524)
				)
				(justify mirror)
			)
		)
		(property "Device Type" "RESISTOR-A155-05101-DL,5.1KOHMA"
			(at -0.008382 1.210564 0)
			(unlocked yes)
			(layer "B.Fab")
			(hide yes)
			(effects
				(font
					(size 0.7874 0.5842)
					(thickness 0.1524)
				)
				(justify mirror)
			)
		)
		(property "User Part Number" "PARTNUM*"
			(at -0.02032 4.024884 0)
			(unlocked yes)
			(layer "Cmts.User")
			(hide yes)
			(effects
				(font
					(size 0.7874 0.5842)
					(thickness 0.1524)
				)
				(justify mirror)
			)
		)
		(property "Tolerance" "TOL*"
			(at -0.044704 3.05435 0)
			(unlocked yes)
			(layer "Cmts.User")
			(hide yes)
			(effects
				(font
					(size 0.7874 0.5842)
					(thickness 0.1524)
				)
				(justify mirror)
			)
		)
		(duplicate_pad_numbers_are_jumpers no)
		(fp_line
			(start -1.143 -0.5588)
			(end 1.143 -0.5588)
			(stroke
				(width 0.1)
				(type default)
			)
			(layer "B.SilkS")
		)
		(fp_line
			(start -1.143 0.5588)
			(end -1.143 -0.5588)
			(stroke
				(width 0.1)
				(type default)
			)
			(layer "B.SilkS")
		)
		(fp_line
			(start 1.143 -0.5588)
			(end 1.143 0.5588)
			(stroke
				(width 0.1)
				(type default)
			)
			(layer "B.SilkS")
		)
		(fp_line
			(start 1.143 0.5588)
			(end -1.143 0.5588)
			(stroke
				(width 0.1)
				(type default)
			)
			(layer "B.SilkS")
		)
		(fp_rect
			(start 1.143 -0.5588)
			(end -1.143 0.5588)
			(stroke
				(width 0)
				(type default)
			)
			(fill no)
			(layer "B.CrtYd")
		)
		(fp_line
			(start -0.508 -0.3048)
			(end 0.508 -0.3048)
			(stroke
				(width 0.1)
				(type default)
			)
			(layer "B.Fab")
		)
		(fp_line
			(start -0.508 0.3048)
			(end -0.508 -0.3048)
			(stroke
				(width 0.1)
				(type default)
			)
			(layer "B.Fab")
		)
		(fp_line
			(start 0.508 -0.3048)
			(end 0.508 0.3048)
			(stroke
				(width 0.1)
				(type default)
			)
			(layer "B.Fab")
		)
		(fp_line
			(start 0.508 0.3048)
			(end -0.508 0.3048)
			(stroke
				(width 0.1)
				(type default)
			)
			(layer "B.Fab")
		)
		(pad "1" smd rect
			(at 0.5334 0 180)
			(size 0.7112 0.6096)
			(layers "B.Cu" "B.Mask" "B.Paste")
			(net "R_XP5R0V_EN")
		)
		(pad "2" smd rect
			(at -0.5334 0 180)
			(size 0.7112 0.6096)
			(layers "B.Cu" "B.Mask" "B.Paste")
			(net "SG")
		)
		(zone
			(layer "B.Cu")
			(hatch none 0.5)
			(connect_pads
				(clearance 0)
			)
			(min_thickness 0.25)
			(keepout
				(tracks allowed)
				(vias not_allowed)
				(pads allowed)
				(copperpour not_allowed)
				(footprints allowed)
			)
			(placement
				(enabled no)
				(sheetname "")
			)
			(fill
				(thermal_gap 0.5)
				(thermal_bridge_width 0.5)
				(island_removal_mode 0)
			)
			(polygon
				(pts
					(xy 37.0586 -100.5332) (xy 36.9062 -100.5332) (xy 36.9062 -99.9236) (xy 37.0586 -99.9236)
				)
			)
		)
	)
	(footprint ""
		(layer "B.Cu")
		(at 117.84711 -47.323248 -90)
		(property "Reference" "C202"
			(at -1.698752 -1.88214 270)
			(unlocked yes)
			(layer "B.SilkS")
			(effects
				(font
					(size 0.635 0.4064)
					(thickness 0.1524)
				)
				(justify mirror)
			)
		)
		(property "Value" "VAL*"
			(at 0 3.718306 270)
			(unlocked yes)
			(layer "B.Fab")
			(hide yes)
			(effects
				(font
					(size 0.7874 0.5842)
					(thickness 0.127)
				)
				(justify mirror)
			)
		)
		(property "Tolerance" "TOL*"
			(at 0 4.861306 270)
			(unlocked yes)
			(layer "Cmts.User")
			(hide yes)
			(effects
				(font
					(size 0.7874 0.5842)
					(thickness 0.127)
				)
				(justify mirror)
			)
		)
		(property "User Part Number" "PARTNUM*"
			(at 0 2.575306 270)
			(unlocked yes)
			(layer "Cmts.User")
			(hide yes)
			(effects
				(font
					(size 0.7874 0.5842)
					(thickness 0.127)
				)
				(justify mirror)
			)
		)
		(property "Device Type" "CAPACITOR-G105-0B104-CK,0.1UF,A"
			(at 0 1.432306 270)
			(unlocked yes)
			(layer "B.Fab")
			(hide yes)
			(effects
				(font
					(size 0.7874 0.5842)
					(thickness 0.127)
				)
				(justify mirror)
			)
		)
		(duplicate_pad_numbers_are_jumpers no)
		(fp_line
			(start -0.970026 0.4699)
			(end 0.970026 0.4699)
			(stroke
				(width 0.1)
				(type default)
			)
			(layer "B.SilkS")
		)
		(fp_line
			(start 0.970026 0.4699)
			(end 0.970026 -0.4699)
			(stroke
				(width 0.1)
				(type default)
			)
			(layer "B.SilkS")
		)
		(fp_line
			(start -0.970026 -0.4699)
			(end -0.970026 0.4699)
			(stroke
				(width 0.1)
				(type default)
			)
			(layer "B.SilkS")
		)
		(fp_line
			(start 0.970026 -0.4699)
			(end -0.970026 -0.4699)
			(stroke
				(width 0.1)
				(type default)
			)
			(layer "B.SilkS")
		)
		(fp_poly
			(pts
				(xy 0.970026 0.4699) (xy -0.970026 0.4699) (xy -0.970026 -0.4699) (xy 0.970026 -0.4699)
			)
			(stroke
				(width 0)
				(type default)
			)
			(fill no)
			(layer "B.CrtYd")
		)
		(fp_line
			(start -0.508 0.3048)
			(end 0.508 0.3048)
			(stroke
				(width 0.1)
				(type default)
			)
			(layer "B.Fab")
		)
		(fp_line
			(start 0.508 0.3048)
			(end 0.508 -0.3048)
			(stroke
				(width 0.1)
				(type default)
			)
			(layer "B.Fab")
		)
		(fp_line
			(start -0.508 -0.3048)
			(end -0.508 0.3048)
			(stroke
				(width 0.1)
				(type default)
			)
			(layer "B.Fab")
		)
		(fp_line
			(start 0.508 -0.3048)
			(end -0.508 -0.3048)
			(stroke
				(width 0.1)
				(type default)
			)
			(layer "B.Fab")
		)
		(pad "1" smd circle
			(at 0.500126 0 90)
			(size 0.635 0.635)
			(layers "B.Cu" "B.Mask" "B.Paste")
			(net "XP3R3V_FPGA")
		)
		(pad "2" smd circle
			(at -0.500126 0 90)
			(size 0.635 0.635)
			(layers "B.Cu" "B.Mask" "B.Paste")
			(net "SG")
		)
	)
	(footprint ""
		(layer "B.Cu")
		(at 21.0566 -40.4876)
		(property "Reference" "R26"
			(at -0.381 4.86537 0)
			(unlocked yes)
			(layer "B.SilkS")
			(effects
				(font
					(size 0.7874 0.5842)
					(thickness 0.1524)
				)
				(justify mirror)
			)
		)
		(property "Value" "VAL*"
			(at -0.02032 2.13233 0)
			(unlocked yes)
			(layer "B.Fab")
			(hide yes)
			(effects
				(font
					(size 0.7874 0.5842)
					(thickness 0.1524)
				)
				(justify mirror)
			)
		)
		(property "Tolerance" "TOL*"
			(at -0.044704 3.05435 0)
			(unlocked yes)
			(layer "Cmts.User")
			(hide yes)
			(effects
				(font
					(size 0.7874 0.5842)
					(thickness 0.1524)
				)
				(justify mirror)
			)
		)
		(property "User Part Number" "PARTNUM*"
			(at -0.02032 4.024884 0)
			(unlocked yes)
			(layer "Cmts.User")
			(hide yes)
			(effects
				(font
					(size 0.7874 0.5842)
					(thickness 0.1524)
				)
				(justify mirror)
			)
		)
		(property "Device Type" "RESISTOR-G155-133R0-01,33OHM,1%"
			(at -0.008382 1.210564 0)
			(unlocked yes)
			(layer "B.Fab")
			(hide yes)
			(effects
				(font
					(size 0.7874 0.5842)
					(thickness 0.1524)
				)
				(justify mirror)
			)
		)
		(duplicate_pad_numbers_are_jumpers no)
		(fp_line
			(start -1.143 -0.5588)
			(end 1.143 -0.5588)
			(stroke
				(width 0.1)
				(type default)
			)
			(layer "B.SilkS")
		)
		(fp_line
			(start -1.143 0.5588)
			(end -1.143 -0.5588)
			(stroke
				(width 0.1)
				(type default)
			)
			(layer "B.SilkS")
		)
		(fp_line
			(start 1.143 -0.5588)
			(end 1.143 0.5588)
			(stroke
				(width 0.1)
				(type default)
			)
			(layer "B.SilkS")
		)
		(fp_line
			(start 1.143 0.5588)
			(end -1.143 0.5588)
			(stroke
				(width 0.1)
				(type default)
			)
			(layer "B.SilkS")
		)
		(fp_rect
			(start 1.143 0.5588)
			(end -1.143 -0.5588)
			(stroke
				(width 0)
				(type default)
			)
			(fill no)
			(layer "B.CrtYd")
		)
		(fp_line
			(start -0.508 -0.3048)
			(end 0.508 -0.3048)
			(stroke
				(width 0.1)
				(type default)
			)
			(layer "B.Fab")
		)
		(fp_line
			(start -0.508 0.3048)
			(end -0.508 -0.3048)
			(stroke
				(width 0.1)
				(type default)
			)
			(layer "B.Fab")
		)
		(fp_line
			(start 0.508 -0.3048)
			(end 0.508 0.3048)
			(stroke
				(width 0.1)
				(type default)
			)
			(layer "B.Fab")
		)
		(fp_line
			(start 0.508 0.3048)
			(end -0.508 0.3048)
			(stroke
				(width 0.1)
				(type default)
			)
			(layer "B.Fab")
		)
		(pad "1" smd rect
			(at 0.5334 0 180)
			(size 0.7112 0.6096)
			(layers "B.Cu" "B.Mask" "B.Paste")
			(net "PCIE_SMDAT")
		)
		(pad "2" smd rect
			(at -0.5334 0 180)
			(size 0.7112 0.6096)
			(layers "B.Cu" "B.Mask" "B.Paste")
			(net "R_PCA9546_I2C_SDA")
		)
		(zone
			(layer "B.Cu")
			(hatch none 0.5)
			(connect_pads
				(clearance 0)
			)
			(min_thickness 0.25)
			(keepout
				(tracks allowed)
				(vias not_allowed)
				(pads allowed)
				(copperpour not_allowed)
				(footprints allowed)
			)
			(placement
				(enabled no)
				(sheetname "")
			)
			(fill
				(thermal_gap 0.5)
				(thermal_bridge_width 0.5)
				(island_removal_mode 0)
			)
			(polygon
				(pts
					(xy 21.1328 -40.1828) (xy 21.1328 -40.7924) (xy 20.9804 -40.7924) (xy 20.9804 -40.1828)
				)
			)
		)
	)
	(footprint ""
		(layer "B.Cu")
		(at 105.347008 -37.82314)
		(property "Reference" "C146"
			(at -41.656508 1.37795 0)
			(unlocked yes)
			(layer "B.SilkS")
			(effects
				(font
					(size 0.635 0.4064)
					(thickness 0.1524)
				)
				(justify mirror)
			)
		)
		(property "Value" "VAL*"
			(at 0 3.718306 0)
			(unlocked yes)
			(layer "B.Fab")
			(hide yes)
			(effects
				(font
					(size 0.7874 0.5842)
					(thickness 0.127)
				)
				(justify mirror)
			)
		)
		(property "Tolerance" "TOL*"
			(at 0 4.861306 0)
			(unlocked yes)
			(layer "Cmts.User")
			(hide yes)
			(effects
				(font
					(size 0.7874 0.5842)
					(thickness 0.127)
				)
				(justify mirror)
			)
		)
		(property "User Part Number" "PARTNUM*"
			(at 0 2.575306 0)
			(unlocked yes)
			(layer "Cmts.User")
			(hide yes)
			(effects
				(font
					(size 0.7874 0.5842)
					(thickness 0.127)
				)
				(justify mirror)
			)
		)
		(property "Device Type" "CAPACITOR-G105-0B104-CK,0.1UF,A"
			(at 0 1.432306 0)
			(unlocked yes)
			(layer "B.Fab")
			(hide yes)
			(effects
				(font
					(size 0.7874 0.5842)
					(thickness 0.127)
				)
				(justify mirror)
			)
		)
		(duplicate_pad_numbers_are_jumpers no)
		(fp_line
			(start -0.970026 -0.4699)
			(end -0.970026 0.4699)
			(stroke
				(width 0.1)
				(type default)
			)
			(layer "B.SilkS")
		)
		(fp_line
			(start -0.970026 0.4699)
			(end 0.970026 0.4699)
			(stroke
				(width 0.1)
				(type default)
			)
			(layer "B.SilkS")
		)
		(fp_line
			(start 0.970026 -0.4699)
			(end -0.970026 -0.4699)
			(stroke
				(width 0.1)
				(type default)
			)
			(layer "B.SilkS")
		)
		(fp_line
			(start 0.970026 0.4699)
			(end 0.970026 -0.4699)
			(stroke
				(width 0.1)
				(type default)
			)
			(layer "B.SilkS")
		)
		(fp_poly
			(pts
				(xy 0.970026 0.4699) (xy -0.970026 0.4699) (xy -0.970026 -0.4699) (xy 0.970026 -0.4699)
			)
			(stroke
				(width 0)
				(type default)
			)
			(fill no)
			(layer "B.CrtYd")
		)
		(fp_line
			(start -0.508 -0.3048)
			(end -0.508 0.3048)
			(stroke
				(width 0.1)
				(type default)
			)
			(layer "B.Fab")
		)
		(fp_line
			(start -0.508 0.3048)
			(end 0.508 0.3048)
			(stroke
				(width 0.1)
				(type default)
			)
			(layer "B.Fab")
		)
		(fp_line
			(start 0.508 -0.3048)
			(end -0.508 -0.3048)
			(stroke
				(width 0.1)
				(type default)
			)
			(layer "B.Fab")
		)
		(fp_line
			(start 0.508 0.3048)
			(end 0.508 -0.3048)
			(stroke
				(width 0.1)
				(type default)
			)
			(layer "B.Fab")
		)
		(pad "1" smd circle
			(at 0.500126 0 180)
			(size 0.635 0.635)
			(layers "B.Cu" "B.Mask" "B.Paste")
			(net "XP2R5V_FPGA")
		)
		(pad "2" smd circle
			(at -0.500126 0 180)
			(size 0.635 0.635)
			(layers "B.Cu" "B.Mask" "B.Paste")
			(net "SG")
		)
	)
	(footprint ""
		(layer "B.Cu")
		(at 83.2358 -82.55 180)
		(property "Reference" "R152"
			(at 0.1778 -2.32537 0)
			(unlocked yes)
			(layer "B.SilkS")
			(effects
				(font
					(size 0.7874 0.5842)
					(thickness 0.1524)
				)
				(justify mirror)
			)
		)
		(property "Value" "VAL*"
			(at -0.02032 2.13233 180)
			(unlocked yes)
			(layer "B.Fab")
			(hide yes)
			(effects
				(font
					(size 0.7874 0.5842)
					(thickness 0.1524)
				)
				(justify mirror)
			)
		)
		(property "Tolerance" "TOL*"
			(at -0.044704 3.05435 180)
			(unlocked yes)
			(layer "Cmts.User")
			(hide yes)
			(effects
				(font
					(size 0.7874 0.5842)
					(thickness 0.1524)
				)
				(justify mirror)
			)
		)
		(property "User Part Number" "PARTNUM*"
			(at -0.02032 4.024884 180)
			(unlocked yes)
			(layer "Cmts.User")
			(hide yes)
			(effects
				(font
					(size 0.7874 0.5842)
					(thickness 0.1524)
				)
				(justify mirror)
			)
		)
		(property "Device Type" "RESISTOR-G155-14701-01,4.7KOHMA"
			(at -0.008382 1.210564 180)
			(unlocked yes)
			(layer "B.Fab")
			(hide yes)
			(effects
				(font
					(size 0.7874 0.5842)
					(thickness 0.1524)
				)
				(justify mirror)
			)
		)
		(duplicate_pad_numbers_are_jumpers no)
		(fp_line
			(start 1.143 0.5588)
			(end -1.143 0.5588)
			(stroke
				(width 0.1)
				(type default)
			)
			(layer "B.SilkS")
		)
		(fp_line
			(start 1.143 -0.5588)
			(end 1.143 0.5588)
			(stroke
				(width 0.1)
				(type default)
			)
			(layer "B.SilkS")
		)
		(fp_line
			(start -1.143 0.5588)
			(end -1.143 -0.5588)
			(stroke
				(width 0.1)
				(type default)
			)
			(layer "B.SilkS")
		)
		(fp_line
			(start -1.143 -0.5588)
			(end 1.143 -0.5588)
			(stroke
				(width 0.1)
				(type default)
			)
			(layer "B.SilkS")
		)
		(fp_rect
			(start -1.143 0.5588)
			(end 1.143 -0.5588)
			(stroke
				(width 0)
				(type default)
			)
			(fill no)
			(layer "B.CrtYd")
		)
		(fp_line
			(start 0.508 0.3048)
			(end -0.508 0.3048)
			(stroke
				(width 0.1)
				(type default)
			)
			(layer "B.Fab")
		)
		(fp_line
			(start 0.508 -0.3048)
			(end 0.508 0.3048)
			(stroke
				(width 0.1)
				(type default)
			)
			(layer "B.Fab")
		)
		(fp_line
			(start -0.508 0.3048)
			(end -0.508 -0.3048)
			(stroke
				(width 0.1)
				(type default)
			)
			(layer "B.Fab")
		)
		(fp_line
			(start -0.508 -0.3048)
			(end 0.508 -0.3048)
			(stroke
				(width 0.1)
				(type default)
			)
			(layer "B.Fab")
		)
		(pad "1" smd rect
			(at 0.5334 0)
			(size 0.7112 0.6096)
			(layers "B.Cu" "B.Mask" "B.Paste")
			(net "SG")
		)
		(pad "2" smd rect
			(at -0.5334 0)
			(size 0.7112 0.6096)
			(layers "B.Cu" "B.Mask" "B.Paste")
			(net "UNNAMED_5_PCA9546APWTSSOP16_I33")
		)
		(zone
			(layer "B.Cu")
			(hatch none 0.5)
			(connect_pads
				(clearance 0)
			)
			(min_thickness 0.25)
			(keepout
				(tracks allowed)
				(vias not_allowed)
				(pads allowed)
				(copperpour not_allowed)
				(footprints allowed)
			)
			(placement
				(enabled no)
				(sheetname "")
			)
			(fill
				(thermal_gap 0.5)
				(thermal_bridge_width 0.5)
				(island_removal_mode 0)
			)
			(polygon
				(pts
					(xy 83.312 -82.8548) (xy 83.1596 -82.8548) (xy 83.1596 -82.2452) (xy 83.312 -82.2452)
				)
			)
		)
	)
	(footprint ""
		(layer "B.Cu")
		(at 75.514962 -15.367 -90)
		(property "Reference" "C35"
			(at -1.778 -2.372868 270)
			(unlocked yes)
			(layer "B.SilkS")
			(effects
				(font
					(size 0.7874 0.5842)
					(thickness 0.1524)
				)
				(justify mirror)
			)
		)
		(property "Value" "VAL*"
			(at -0.0762 2.067306 270)
			(unlocked yes)
			(layer "B.Fab")
			(hide yes)
			(effects
				(font
					(size 0.7874 0.5842)
					(thickness 0.1524)
				)
				(justify mirror)
			)
		)
		(property "Tolerance" "TOL*"
			(at -0.0762 3.032506 270)
			(unlocked yes)
			(layer "Cmts.User")
			(hide yes)
			(effects
				(font
					(size 0.7874 0.5842)
					(thickness 0.1524)
				)
				(justify mirror)
			)
		)
		(property "User Part Number" "PARTNUM*"
			(at -0.1016 4.023106 270)
			(unlocked yes)
			(layer "Cmts.User")
			(hide yes)
			(effects
				(font
					(size 0.7874 0.5842)
					(thickness 0.1524)
				)
				(justify mirror)
			)
		)
		(property "Device Type" "CAPACITOR-G105-0B104-CK,0.1UF,A"
			(at -0.0508 1.127506 270)
			(unlocked yes)
			(layer "B.Fab")
			(hide yes)
			(effects
				(font
					(size 0.7874 0.5842)
					(thickness 0.1524)
				)
				(justify mirror)
			)
		)
		(duplicate_pad_numbers_are_jumpers no)
		(fp_line
			(start -1.143 0.5588)
			(end -1.143 -0.5588)
			(stroke
				(width 0.1)
				(type default)
			)
			(layer "B.SilkS")
		)
		(fp_line
			(start 1.143 0.5588)
			(end -1.143 0.5588)
			(stroke
				(width 0.1)
				(type default)
			)
			(layer "B.SilkS")
		)
		(fp_line
			(start -1.143 -0.5588)
			(end 1.143 -0.5588)
			(stroke
				(width 0.1)
				(type default)
			)
			(layer "B.SilkS")
		)
		(fp_line
			(start 1.143 -0.5588)
			(end 1.143 0.5588)
			(stroke
				(width 0.1)
				(type default)
			)
			(layer "B.SilkS")
		)
		(fp_rect
			(start 1.143 0.5588)
			(end -1.143 -0.5588)
			(stroke
				(width 0)
				(type default)
			)
			(fill no)
			(layer "B.CrtYd")
		)
		(fp_line
			(start -0.508 0.3048)
			(end -0.508 -0.3048)
			(stroke
				(width 0.1)
				(type default)
			)
			(layer "B.Fab")
		)
		(fp_line
			(start 0.508 0.3048)
			(end -0.508 0.3048)
			(stroke
				(width 0.1)
				(type default)
			)
			(layer "B.Fab")
		)
		(fp_line
			(start -0.508 -0.3048)
			(end 0.508 -0.3048)
			(stroke
				(width 0.1)
				(type default)
			)
			(layer "B.Fab")
		)
		(fp_line
			(start 0.508 -0.3048)
			(end 0.508 0.3048)
			(stroke
				(width 0.1)
				(type default)
			)
			(layer "B.Fab")
		)
		(pad "1" smd rect
			(at 0.5334 0 90)
			(size 0.7112 0.6096)
			(layers "B.Cu" "B.Mask" "B.Paste")
			(net "C_CPU_RX_PCIE_MGT3_TXP")
		)
		(pad "2" smd rect
			(at -0.5334 0 90)
			(size 0.7112 0.6096)
			(layers "B.Cu" "B.Mask" "B.Paste")
			(net "CPU_RX_PCIE_MGT3_TXP")
		)
		(zone
			(layer "B.Cu")
			(hatch none 0.5)
			(connect_pads
				(clearance 0)
			)
			(min_thickness 0.25)
			(keepout
				(tracks allowed)
				(vias not_allowed)
				(pads allowed)
				(copperpour not_allowed)
				(footprints allowed)
			)
			(placement
				(enabled no)
				(sheetname "")
			)
			(fill
				(thermal_gap 0.5)
				(thermal_bridge_width 0.5)
				(island_removal_mode 0)
			)
			(polygon
				(pts
					(xy 75.210162 -15.2908) (xy 75.819762 -15.2908) (xy 75.819762 -15.4432) (xy 75.210162 -15.4432)
				)
			)
		)
	)
	(footprint ""
		(layer "B.Cu")
		(at 140.2842 -74.2315)
		(property "Reference" "R136"
			(at 0.4318 -1.04013 0)
			(unlocked yes)
			(layer "B.SilkS")
			(effects
				(font
					(size 0.7874 0.5842)
					(thickness 0.1524)
				)
				(justify mirror)
			)
		)
		(property "Value" "VAL*"
			(at -0.02032 2.13233 0)
			(unlocked yes)
			(layer "B.Fab")
			(hide yes)
			(effects
				(font
					(size 0.7874 0.5842)
					(thickness 0.1524)
				)
				(justify mirror)
			)
		)
		(property "Tolerance" "TOL*"
			(at -0.044704 3.05435 0)
			(unlocked yes)
			(layer "Cmts.User")
			(hide yes)
			(effects
				(font
					(size 0.7874 0.5842)
					(thickness 0.1524)
				)
				(justify mirror)
			)
		)
		(property "User Part Number" "PARTNUM*"
			(at -0.02032 4.024884 0)
			(unlocked yes)
			(layer "Cmts.User")
			(hide yes)
			(effects
				(font
					(size 0.7874 0.5842)
					(thickness 0.1524)
				)
				(justify mirror)
			)
		)
		(property "Device Type" "RESISTOR-G155-133R0-01,33OHM,1%"
			(at -0.008382 1.210564 0)
			(unlocked yes)
			(layer "B.Fab")
			(hide yes)
			(effects
				(font
					(size 0.7874 0.5842)
					(thickness 0.1524)
				)
				(justify mirror)
			)
		)
		(duplicate_pad_numbers_are_jumpers no)
		(fp_line
			(start -1.143 -0.5588)
			(end 1.143 -0.5588)
			(stroke
				(width 0.1)
				(type default)
			)
			(layer "B.SilkS")
		)
		(fp_line
			(start -1.143 0.5588)
			(end -1.143 -0.5588)
			(stroke
				(width 0.1)
				(type default)
			)
			(layer "B.SilkS")
		)
		(fp_line
			(start 1.143 -0.5588)
			(end 1.143 0.5588)
			(stroke
				(width 0.1)
				(type default)
			)
			(layer "B.SilkS")
		)
		(fp_line
			(start 1.143 0.5588)
			(end -1.143 0.5588)
			(stroke
				(width 0.1)
				(type default)
			)
			(layer "B.SilkS")
		)
		(fp_rect
			(start -1.143 -0.5588)
			(end 1.143 0.5588)
			(stroke
				(width 0)
				(type default)
			)
			(fill no)
			(layer "B.CrtYd")
		)
		(fp_line
			(start -0.508 -0.3048)
			(end 0.508 -0.3048)
			(stroke
				(width 0.1)
				(type default)
			)
			(layer "B.Fab")
		)
		(fp_line
			(start -0.508 0.3048)
			(end -0.508 -0.3048)
			(stroke
				(width 0.1)
				(type default)
			)
			(layer "B.Fab")
		)
		(fp_line
			(start 0.508 -0.3048)
			(end 0.508 0.3048)
			(stroke
				(width 0.1)
				(type default)
			)
			(layer "B.Fab")
		)
		(fp_line
			(start 0.508 0.3048)
			(end -0.508 0.3048)
			(stroke
				(width 0.1)
				(type default)
			)
			(layer "B.Fab")
		)
		(pad "1" smd rect
			(at 0.5334 0 180)
			(size 0.7112 0.6096)
			(layers "B.Cu" "B.Mask" "B.Paste")
			(net "FT4232_FPGA_TMS")
		)
		(pad "2" smd rect
			(at -0.5334 0 180)
			(size 0.7112 0.6096)
			(layers "B.Cu" "B.Mask" "B.Paste")
			(net "FPGA_TMS")
		)
		(zone
			(layer "B.Cu")
			(hatch none 0.5)
			(connect_pads
				(clearance 0)
			)
			(min_thickness 0.25)
			(keepout
				(tracks allowed)
				(vias not_allowed)
				(pads allowed)
				(copperpour not_allowed)
				(footprints allowed)
			)
			(placement
				(enabled no)
				(sheetname "")
			)
			(fill
				(thermal_gap 0.5)
				(thermal_bridge_width 0.5)
				(island_removal_mode 0)
			)
			(polygon
				(pts
					(xy 140.208 -74.5363) (xy 140.208 -73.9267) (xy 140.3604 -73.9267) (xy 140.3604 -74.5363)
				)
			)
		)
	)
	(footprint ""
		(layer "B.Cu")
		(at 102.84714 -41.32326 -90)
		(property "Reference" "C105"
			(at 1.016 41.50995 270)
			(unlocked yes)
			(layer "B.SilkS")
			(effects
				(font
					(size 0.635 0.4064)
					(thickness 0.1524)
				)
				(justify mirror)
			)
		)
		(property "Value" "VAL*"
			(at 0 3.718306 270)
			(unlocked yes)
			(layer "B.Fab")
			(hide yes)
			(effects
				(font
					(size 0.7874 0.5842)
					(thickness 0.127)
				)
				(justify mirror)
			)
		)
		(property "Tolerance" "TOL*"
			(at 0 4.861306 270)
			(unlocked yes)
			(layer "Cmts.User")
			(hide yes)
			(effects
				(font
					(size 0.7874 0.5842)
					(thickness 0.127)
				)
				(justify mirror)
			)
		)
		(property "User Part Number" "PARTNUM*"
			(at 0 2.575306 270)
			(unlocked yes)
			(layer "Cmts.User")
			(hide yes)
			(effects
				(font
					(size 0.7874 0.5842)
					(thickness 0.127)
				)
				(justify mirror)
			)
		)
		(property "Device Type" "CAPACITOR-G105-0B104-CK,0.1UF,A"
			(at 0 1.432306 270)
			(unlocked yes)
			(layer "B.Fab")
			(hide yes)
			(effects
				(font
					(size 0.7874 0.5842)
					(thickness 0.127)
				)
				(justify mirror)
			)
		)
		(duplicate_pad_numbers_are_jumpers no)
		(fp_line
			(start -0.970026 0.4699)
			(end 0.970026 0.4699)
			(stroke
				(width 0.1)
				(type default)
			)
			(layer "B.SilkS")
		)
		(fp_line
			(start 0.970026 0.4699)
			(end 0.970026 -0.4699)
			(stroke
				(width 0.1)
				(type default)
			)
			(layer "B.SilkS")
		)
		(fp_line
			(start -0.970026 -0.4699)
			(end -0.970026 0.4699)
			(stroke
				(width 0.1)
				(type default)
			)
			(layer "B.SilkS")
		)
		(fp_line
			(start 0.970026 -0.4699)
			(end -0.970026 -0.4699)
			(stroke
				(width 0.1)
				(type default)
			)
			(layer "B.SilkS")
		)
		(fp_poly
			(pts
				(xy 0.970026 0.4699) (xy -0.970026 0.4699) (xy -0.970026 -0.4699) (xy 0.970026 -0.4699)
			)
			(stroke
				(width 0)
				(type default)
			)
			(fill no)
			(layer "B.CrtYd")
		)
		(fp_line
			(start -0.508 0.3048)
			(end 0.508 0.3048)
			(stroke
				(width 0.1)
				(type default)
			)
			(layer "B.Fab")
		)
		(fp_line
			(start 0.508 0.3048)
			(end 0.508 -0.3048)
			(stroke
				(width 0.1)
				(type default)
			)
			(layer "B.Fab")
		)
		(fp_line
			(start -0.508 -0.3048)
			(end -0.508 0.3048)
			(stroke
				(width 0.1)
				(type default)
			)
			(layer "B.Fab")
		)
		(fp_line
			(start 0.508 -0.3048)
			(end -0.508 -0.3048)
			(stroke
				(width 0.1)
				(type default)
			)
			(layer "B.Fab")
		)
		(pad "1" smd circle
			(at 0.500126 0 90)
			(size 0.635 0.635)
			(layers "B.Cu" "B.Mask" "B.Paste")
			(net "XP1R0V_FPGA_MGTAVCC")
		)
		(pad "2" smd circle
			(at -0.500126 0 90)
			(size 0.635 0.635)
			(layers "B.Cu" "B.Mask" "B.Paste")
			(net "SG")
		)
	)
	(footprint ""
		(layer "B.Cu")
		(at 112.880394 -44.577 180)
		(property "Reference" "C128"
			(at 43.307254 -1.88595 0)
			(unlocked yes)
			(layer "B.SilkS")
			(effects
				(font
					(size 0.635 0.4064)
					(thickness 0.1524)
				)
				(justify mirror)
			)
		)
		(property "Value" "VAL*"
			(at -0.02032 2.13233 180)
			(unlocked yes)
			(layer "B.Fab")
			(hide yes)
			(effects
				(font
					(size 0.7874 0.5842)
					(thickness 0.1524)
				)
				(justify mirror)
			)
		)
		(property "Device Type" "CAPACITOR-G105-0F475-BM,4.7UF,A"
			(at -0.008382 1.210564 180)
			(unlocked yes)
			(layer "B.Fab")
			(hide yes)
			(effects
				(font
					(size 0.7874 0.5842)
					(thickness 0.1524)
				)
				(justify mirror)
			)
		)
		(property "User Part Number" "PARTNUM*"
			(at -0.02032 4.024884 180)
			(unlocked yes)
			(layer "Cmts.User")
			(hide yes)
			(effects
				(font
					(size 0.7874 0.5842)
					(thickness 0.1524)
				)
				(justify mirror)
			)
		)
		(property "Tolerance" "TOL*"
			(at -0.044704 3.05435 180)
			(unlocked yes)
			(layer "Cmts.User")
			(hide yes)
			(effects
				(font
					(size 0.7874 0.5842)
					(thickness 0.1524)
				)
				(justify mirror)
			)
		)
		(duplicate_pad_numbers_are_jumpers no)
		(fp_line
			(start 1.143 0.5588)
			(end -1.143 0.5588)
			(stroke
				(width 0.1)
				(type default)
			)
			(layer "B.SilkS")
		)
		(fp_line
			(start 1.143 -0.5588)
			(end 1.143 0.5588)
			(stroke
				(width 0.1)
				(type default)
			)
			(layer "B.SilkS")
		)
		(fp_line
			(start -1.143 0.5588)
			(end -1.143 -0.5588)
			(stroke
				(width 0.1)
				(type default)
			)
			(layer "B.SilkS")
		)
		(fp_line
			(start -1.143 -0.5588)
			(end 1.143 -0.5588)
			(stroke
				(width 0.1)
				(type default)
			)
			(layer "B.SilkS")
		)
		(fp_rect
			(start 1.143 -0.5588)
			(end -1.143 0.5588)
			(stroke
				(width 0)
				(type default)
			)
			(fill no)
			(layer "B.CrtYd")
		)
		(fp_line
			(start 0.508 0.3048)
			(end -0.508 0.3048)
			(stroke
				(width 0.1)
				(type default)
			)
			(layer "B.Fab")
		)
		(fp_line
			(start 0.508 -0.3048)
			(end 0.508 0.3048)
			(stroke
				(width 0.1)
				(type default)
			)
			(layer "B.Fab")
		)
		(fp_line
			(start -0.508 0.3048)
			(end -0.508 -0.3048)
			(stroke
				(width 0.1)
				(type default)
			)
			(layer "B.Fab")
		)
		(fp_line
			(start -0.508 -0.3048)
			(end 0.508 -0.3048)
			(stroke
				(width 0.1)
				(type default)
			)
			(layer "B.Fab")
		)
		(pad "1" smd rect
			(at 0.5334 0)
			(size 0.7112 0.6096)
			(layers "B.Cu" "B.Mask" "B.Paste")
			(net "XP1R8V_FPGA_VCCAUX")
		)
		(pad "2" smd rect
			(at -0.5334 0)
			(size 0.7112 0.6096)
			(layers "B.Cu" "B.Mask" "B.Paste")
			(net "SG")
		)
		(zone
			(layer "B.Cu")
			(hatch none 0.5)
			(connect_pads
				(clearance 0)
			)
			(min_thickness 0.25)
			(keepout
				(tracks allowed)
				(vias not_allowed)
				(pads allowed)
				(copperpour not_allowed)
				(footprints allowed)
			)
			(placement
				(enabled no)
				(sheetname "")
			)
			(fill
				(thermal_gap 0.5)
				(thermal_bridge_width 0.5)
				(island_removal_mode 0)
			)
			(polygon
				(pts
					(xy 112.804194 -44.2722) (xy 112.956594 -44.2722) (xy 112.956594 -44.8818) (xy 112.804194 -44.8818)
				)
			)
		)
	)
	(footprint ""
		(layer "B.Cu")
		(at 90.7542 -106.6038 180)
		(property "Reference" "R263"
			(at 0.5842 2.19583 0)
			(unlocked yes)
			(layer "B.SilkS")
			(effects
				(font
					(size 0.7874 0.5842)
					(thickness 0.1524)
				)
				(justify mirror)
			)
		)
		(property "Value" "VAL*"
			(at -0.02032 2.13233 180)
			(unlocked yes)
			(layer "B.Fab")
			(hide yes)
			(effects
				(font
					(size 0.7874 0.5842)
					(thickness 0.1524)
				)
				(justify mirror)
			)
		)
		(property "Tolerance" "TOL*"
			(at -0.044704 3.05435 180)
			(unlocked yes)
			(layer "Cmts.User")
			(hide yes)
			(effects
				(font
					(size 0.7874 0.5842)
					(thickness 0.1524)
				)
				(justify mirror)
			)
		)
		(property "User Part Number" "PARTNUM*"
			(at -0.02032 4.024884 180)
			(unlocked yes)
			(layer "Cmts.User")
			(hide yes)
			(effects
				(font
					(size 0.7874 0.5842)
					(thickness 0.1524)
				)
				(justify mirror)
			)
		)
		(property "Device Type" "RESISTOR-G155-100R0-J0,0OHM,-"
			(at -0.008382 1.210564 180)
			(unlocked yes)
			(layer "B.Fab")
			(hide yes)
			(effects
				(font
					(size 0.7874 0.5842)
					(thickness 0.1524)
				)
				(justify mirror)
			)
		)
		(duplicate_pad_numbers_are_jumpers no)
		(fp_line
			(start 1.143 0.5588)
			(end -1.143 0.5588)
			(stroke
				(width 0.1)
				(type default)
			)
			(layer "B.SilkS")
		)
		(fp_line
			(start 1.143 -0.5588)
			(end 1.143 0.5588)
			(stroke
				(width 0.1)
				(type default)
			)
			(layer "B.SilkS")
		)
		(fp_line
			(start -1.143 0.5588)
			(end -1.143 -0.5588)
			(stroke
				(width 0.1)
				(type default)
			)
			(layer "B.SilkS")
		)
		(fp_line
			(start -1.143 -0.5588)
			(end 1.143 -0.5588)
			(stroke
				(width 0.1)
				(type default)
			)
			(layer "B.SilkS")
		)
		(fp_rect
			(start -1.143 0.5588)
			(end 1.143 -0.5588)
			(stroke
				(width 0)
				(type default)
			)
			(fill no)
			(layer "B.CrtYd")
		)
		(fp_line
			(start 0.508 0.3048)
			(end -0.508 0.3048)
			(stroke
				(width 0.1)
				(type default)
			)
			(layer "B.Fab")
		)
		(fp_line
			(start 0.508 -0.3048)
			(end 0.508 0.3048)
			(stroke
				(width 0.1)
				(type default)
			)
			(layer "B.Fab")
		)
		(fp_line
			(start -0.508 0.3048)
			(end -0.508 -0.3048)
			(stroke
				(width 0.1)
				(type default)
			)
			(layer "B.Fab")
		)
		(fp_line
			(start -0.508 -0.3048)
			(end 0.508 -0.3048)
			(stroke
				(width 0.1)
				(type default)
			)
			(layer "B.Fab")
		)
		(pad "1" smd rect
			(at 0.5334 0)
			(size 0.7112 0.6096)
			(layers "B.Cu" "B.Mask" "B.Paste")
			(net "R_XP3R3V_PG")
		)
		(pad "2" smd rect
			(at -0.5334 0)
			(size 0.7112 0.6096)
			(layers "B.Cu" "B.Mask" "B.Paste")
			(net "XP3R3V_PG")
		)
		(zone
			(layer "B.Cu")
			(hatch none 0.5)
			(connect_pads
				(clearance 0)
			)
			(min_thickness 0.25)
			(keepout
				(tracks allowed)
				(vias not_allowed)
				(pads allowed)
				(copperpour not_allowed)
				(footprints allowed)
			)
			(placement
				(enabled no)
				(sheetname "")
			)
			(fill
				(thermal_gap 0.5)
				(thermal_bridge_width 0.5)
				(island_removal_mode 0)
			)
			(polygon
				(pts
					(xy 90.8304 -106.9086) (xy 90.678 -106.9086) (xy 90.678 -106.299) (xy 90.8304 -106.299)
				)
			)
		)
	)
	(footprint ""
		(layer "B.Cu")
		(at 68.784978 -15.367 -90)
		(property "Reference" "C27"
			(at 3.048 -0.144272 270)
			(unlocked yes)
			(layer "B.SilkS")
			(effects
				(font
					(size 0.635 0.4064)
					(thickness 0.1524)
				)
				(justify mirror)
			)
		)
		(property "Value" "VAL*"
			(at -0.0762 2.067306 270)
			(unlocked yes)
			(layer "B.Fab")
			(hide yes)
			(effects
				(font
					(size 0.7874 0.5842)
					(thickness 0.1524)
				)
				(justify mirror)
			)
		)
		(property "Tolerance" "TOL*"
			(at -0.0762 3.032506 270)
			(unlocked yes)
			(layer "Cmts.User")
			(hide yes)
			(effects
				(font
					(size 0.7874 0.5842)
					(thickness 0.1524)
				)
				(justify mirror)
			)
		)
		(property "User Part Number" "PARTNUM*"
			(at -0.1016 4.023106 270)
			(unlocked yes)
			(layer "Cmts.User")
			(hide yes)
			(effects
				(font
					(size 0.7874 0.5842)
					(thickness 0.1524)
				)
				(justify mirror)
			)
		)
		(property "Device Type" "CAPACITOR-G105-0B104-CK,0.1UF,A"
			(at -0.0508 1.127506 270)
			(unlocked yes)
			(layer "B.Fab")
			(hide yes)
			(effects
				(font
					(size 0.7874 0.5842)
					(thickness 0.1524)
				)
				(justify mirror)
			)
		)
		(duplicate_pad_numbers_are_jumpers no)
		(fp_line
			(start -1.143 0.5588)
			(end -1.143 -0.5588)
			(stroke
				(width 0.1)
				(type default)
			)
			(layer "B.SilkS")
		)
		(fp_line
			(start 1.143 0.5588)
			(end -1.143 0.5588)
			(stroke
				(width 0.1)
				(type default)
			)
			(layer "B.SilkS")
		)
		(fp_line
			(start -1.143 -0.5588)
			(end 1.143 -0.5588)
			(stroke
				(width 0.1)
				(type default)
			)
			(layer "B.SilkS")
		)
		(fp_line
			(start 1.143 -0.5588)
			(end 1.143 0.5588)
			(stroke
				(width 0.1)
				(type default)
			)
			(layer "B.SilkS")
		)
		(fp_rect
			(start 1.143 0.5588)
			(end -1.143 -0.5588)
			(stroke
				(width 0)
				(type default)
			)
			(fill no)
			(layer "B.CrtYd")
		)
		(fp_line
			(start -0.508 0.3048)
			(end -0.508 -0.3048)
			(stroke
				(width 0.1)
				(type default)
			)
			(layer "B.Fab")
		)
		(fp_line
			(start 0.508 0.3048)
			(end -0.508 0.3048)
			(stroke
				(width 0.1)
				(type default)
			)
			(layer "B.Fab")
		)
		(fp_line
			(start -0.508 -0.3048)
			(end 0.508 -0.3048)
			(stroke
				(width 0.1)
				(type default)
			)
			(layer "B.Fab")
		)
		(fp_line
			(start 0.508 -0.3048)
			(end 0.508 0.3048)
			(stroke
				(width 0.1)
				(type default)
			)
			(layer "B.Fab")
		)
		(pad "1" smd rect
			(at 0.5334 0 90)
			(size 0.7112 0.6096)
			(layers "B.Cu" "B.Mask" "B.Paste")
			(net "C_CPU_RX_PCIE_MGT1_TXN")
		)
		(pad "2" smd rect
			(at -0.5334 0 90)
			(size 0.7112 0.6096)
			(layers "B.Cu" "B.Mask" "B.Paste")
			(net "CPU_RX_PCIE_MGT1_TXN")
		)
		(zone
			(layer "B.Cu")
			(hatch none 0.5)
			(connect_pads
				(clearance 0)
			)
			(min_thickness 0.25)
			(keepout
				(tracks allowed)
				(vias not_allowed)
				(pads allowed)
				(copperpour not_allowed)
				(footprints allowed)
			)
			(placement
				(enabled no)
				(sheetname "")
			)
			(fill
				(thermal_gap 0.5)
				(thermal_bridge_width 0.5)
				(island_removal_mode 0)
			)
			(polygon
				(pts
					(xy 68.480178 -15.2908) (xy 69.089778 -15.2908) (xy 69.089778 -15.4432) (xy 68.480178 -15.4432)
				)
			)
		)
	)
	(footprint ""
		(layer "B.Cu")
		(at 109.4486 -37.211 -90)
		(property "Reference" "C142"
			(at 1.27 41.76395 270)
			(unlocked yes)
			(layer "B.SilkS")
			(effects
				(font
					(size 0.635 0.4064)
					(thickness 0.1524)
				)
				(justify mirror)
			)
		)
		(property "Value" "VAL*"
			(at 0 3.718306 270)
			(unlocked yes)
			(layer "B.Fab")
			(hide yes)
			(effects
				(font
					(size 0.7874 0.5842)
					(thickness 0.127)
				)
				(justify mirror)
			)
		)
		(property "Device Type" "CAPACITOR-G105-0B104-CK,0.1UF,A"
			(at 0 1.432306 270)
			(unlocked yes)
			(layer "B.Fab")
			(hide yes)
			(effects
				(font
					(size 0.7874 0.5842)
					(thickness 0.127)
				)
				(justify mirror)
			)
		)
		(property "User Part Number" "PARTNUM*"
			(at 0 2.575306 270)
			(unlocked yes)
			(layer "Cmts.User")
			(hide yes)
			(effects
				(font
					(size 0.7874 0.5842)
					(thickness 0.127)
				)
				(justify mirror)
			)
		)
		(property "Tolerance" "TOL*"
			(at 0 4.861306 270)
			(unlocked yes)
			(layer "Cmts.User")
			(hide yes)
			(effects
				(font
					(size 0.7874 0.5842)
					(thickness 0.127)
				)
				(justify mirror)
			)
		)
		(duplicate_pad_numbers_are_jumpers no)
		(fp_line
			(start -0.970026 0.4699)
			(end 0.970026 0.4699)
			(stroke
				(width 0.1)
				(type default)
			)
			(layer "B.SilkS")
		)
		(fp_line
			(start 0.970026 0.4699)
			(end 0.970026 -0.4699)
			(stroke
				(width 0.1)
				(type default)
			)
			(layer "B.SilkS")
		)
		(fp_line
			(start -0.970026 -0.4699)
			(end -0.970026 0.4699)
			(stroke
				(width 0.1)
				(type default)
			)
			(layer "B.SilkS")
		)
		(fp_line
			(start 0.970026 -0.4699)
			(end -0.970026 -0.4699)
			(stroke
				(width 0.1)
				(type default)
			)
			(layer "B.SilkS")
		)
		(fp_poly
			(pts
				(xy 0.970026 0.4699) (xy -0.970026 0.4699) (xy -0.970026 -0.4699) (xy 0.970026 -0.4699)
			)
			(stroke
				(width 0)
				(type default)
			)
			(fill no)
			(layer "B.CrtYd")
		)
		(fp_line
			(start -0.508 0.3048)
			(end 0.508 0.3048)
			(stroke
				(width 0.1)
				(type default)
			)
			(layer "B.Fab")
		)
		(fp_line
			(start 0.508 0.3048)
			(end 0.508 -0.3048)
			(stroke
				(width 0.1)
				(type default)
			)
			(layer "B.Fab")
		)
		(fp_line
			(start -0.508 -0.3048)
			(end -0.508 0.3048)
			(stroke
				(width 0.1)
				(type default)
			)
			(layer "B.Fab")
		)
		(fp_line
			(start 0.508 -0.3048)
			(end -0.508 -0.3048)
			(stroke
				(width 0.1)
				(type default)
			)
			(layer "B.Fab")
		)
		(pad "1" smd circle
			(at 0.500126 0 90)
			(size 0.635 0.635)
			(layers "B.Cu" "B.Mask" "B.Paste")
			(net "XP2R5V_FPGA")
		)
		(pad "2" smd circle
			(at -0.500126 0 90)
			(size 0.635 0.635)
			(layers "B.Cu" "B.Mask" "B.Paste")
			(net "SG")
		)
	)
	(footprint ""
		(layer "B.Cu")
		(at 36.9824 -101.3714)
		(property "Reference" "R30"
			(at -4.0386 0.64897 0)
			(unlocked yes)
			(layer "B.SilkS")
			(effects
				(font
					(size 0.7874 0.5842)
					(thickness 0.1524)
				)
				(justify mirror)
			)
		)
		(property "Value" "VAL*"
			(at -0.02032 2.13233 0)
			(unlocked yes)
			(layer "B.Fab")
			(hide yes)
			(effects
				(font
					(size 0.7874 0.5842)
					(thickness 0.1524)
				)
				(justify mirror)
			)
		)
		(property "Device Type" "RESISTOR-G155-12201-01,2.2KOHMA"
			(at -0.008382 1.210564 0)
			(unlocked yes)
			(layer "B.Fab")
			(hide yes)
			(effects
				(font
					(size 0.7874 0.5842)
					(thickness 0.1524)
				)
				(justify mirror)
			)
		)
		(property "User Part Number" "PARTNUM*"
			(at -0.02032 4.024884 0)
			(unlocked yes)
			(layer "Cmts.User")
			(hide yes)
			(effects
				(font
					(size 0.7874 0.5842)
					(thickness 0.1524)
				)
				(justify mirror)
			)
		)
		(property "Tolerance" "TOL*"
			(at -0.044704 3.05435 0)
			(unlocked yes)
			(layer "Cmts.User")
			(hide yes)
			(effects
				(font
					(size 0.7874 0.5842)
					(thickness 0.1524)
				)
				(justify mirror)
			)
		)
		(duplicate_pad_numbers_are_jumpers no)
		(fp_line
			(start -1.143 -0.5588)
			(end 1.143 -0.5588)
			(stroke
				(width 0.1)
				(type default)
			)
			(layer "B.SilkS")
		)
		(fp_line
			(start -1.143 0.5588)
			(end -1.143 -0.5588)
			(stroke
				(width 0.1)
				(type default)
			)
			(layer "B.SilkS")
		)
		(fp_line
			(start 1.143 -0.5588)
			(end 1.143 0.5588)
			(stroke
				(width 0.1)
				(type default)
			)
			(layer "B.SilkS")
		)
		(fp_line
			(start 1.143 0.5588)
			(end -1.143 0.5588)
			(stroke
				(width 0.1)
				(type default)
			)
			(layer "B.SilkS")
		)
		(fp_rect
			(start 1.143 -0.5588)
			(end -1.143 0.5588)
			(stroke
				(width 0)
				(type default)
			)
			(fill no)
			(layer "B.CrtYd")
		)
		(fp_line
			(start -0.508 -0.3048)
			(end 0.508 -0.3048)
			(stroke
				(width 0.1)
				(type default)
			)
			(layer "B.Fab")
		)
		(fp_line
			(start -0.508 0.3048)
			(end -0.508 -0.3048)
			(stroke
				(width 0.1)
				(type default)
			)
			(layer "B.Fab")
		)
		(fp_line
			(start 0.508 -0.3048)
			(end 0.508 0.3048)
			(stroke
				(width 0.1)
				(type default)
			)
			(layer "B.Fab")
		)
		(fp_line
			(start 0.508 0.3048)
			(end -0.508 0.3048)
			(stroke
				(width 0.1)
				(type default)
			)
			(layer "B.Fab")
		)
		(pad "1" smd rect
			(at 0.5334 0 180)
			(size 0.7112 0.6096)
			(layers "B.Cu" "B.Mask" "B.Paste")
			(net "XP5R0V_COMP")
		)
		(pad "2" smd rect
			(at -0.5334 0 180)
			(size 0.7112 0.6096)
			(layers "B.Cu" "B.Mask" "B.Paste")
			(net "UNNAMED_516_CAPACITOR_I13_1")
		)
		(zone
			(layer "B.Cu")
			(hatch none 0.5)
			(connect_pads
				(clearance 0)
			)
			(min_thickness 0.25)
			(keepout
				(tracks allowed)
				(vias not_allowed)
				(pads allowed)
				(copperpour not_allowed)
				(footprints allowed)
			)
			(placement
				(enabled no)
				(sheetname "")
			)
			(fill
				(thermal_gap 0.5)
				(thermal_bridge_width 0.5)
				(island_removal_mode 0)
			)
			(polygon
				(pts
					(xy 37.0586 -101.6762) (xy 36.9062 -101.6762) (xy 36.9062 -101.0666) (xy 37.0586 -101.0666)
				)
			)
		)
	)
	(footprint ""
		(layer "B.Cu")
		(at 110.847124 -41.32326 -90)
		(property "Reference" "C129"
			(at 0.81026 42.044874 270)
			(unlocked yes)
			(layer "B.SilkS")
			(effects
				(font
					(size 0.635 0.4064)
					(thickness 0.1524)
				)
				(justify mirror)
			)
		)
		(property "Value" "VAL*"
			(at 0 3.718306 270)
			(unlocked yes)
			(layer "B.Fab")
			(hide yes)
			(effects
				(font
					(size 0.7874 0.5842)
					(thickness 0.127)
				)
				(justify mirror)
			)
		)
		(property "Tolerance" "TOL*"
			(at 0 4.861306 270)
			(unlocked yes)
			(layer "Cmts.User")
			(hide yes)
			(effects
				(font
					(size 0.7874 0.5842)
					(thickness 0.127)
				)
				(justify mirror)
			)
		)
		(property "User Part Number" "PARTNUM*"
			(at 0 2.575306 270)
			(unlocked yes)
			(layer "Cmts.User")
			(hide yes)
			(effects
				(font
					(size 0.7874 0.5842)
					(thickness 0.127)
				)
				(justify mirror)
			)
		)
		(property "Device Type" "CAPACITOR-G105-0B104-CK,0.1UF,A"
			(at 0 1.432306 270)
			(unlocked yes)
			(layer "B.Fab")
			(hide yes)
			(effects
				(font
					(size 0.7874 0.5842)
					(thickness 0.127)
				)
				(justify mirror)
			)
		)
		(duplicate_pad_numbers_are_jumpers no)
		(fp_line
			(start -0.970026 0.4699)
			(end 0.970026 0.4699)
			(stroke
				(width 0.1)
				(type default)
			)
			(layer "B.SilkS")
		)
		(fp_line
			(start 0.970026 0.4699)
			(end 0.970026 -0.4699)
			(stroke
				(width 0.1)
				(type default)
			)
			(layer "B.SilkS")
		)
		(fp_line
			(start -0.970026 -0.4699)
			(end -0.970026 0.4699)
			(stroke
				(width 0.1)
				(type default)
			)
			(layer "B.SilkS")
		)
		(fp_line
			(start 0.970026 -0.4699)
			(end -0.970026 -0.4699)
			(stroke
				(width 0.1)
				(type default)
			)
			(layer "B.SilkS")
		)
		(fp_poly
			(pts
				(xy 0.970026 0.4699) (xy -0.970026 0.4699) (xy -0.970026 -0.4699) (xy 0.970026 -0.4699)
			)
			(stroke
				(width 0)
				(type default)
			)
			(fill no)
			(layer "B.CrtYd")
		)
		(fp_line
			(start -0.508 0.3048)
			(end 0.508 0.3048)
			(stroke
				(width 0.1)
				(type default)
			)
			(layer "B.Fab")
		)
		(fp_line
			(start 0.508 0.3048)
			(end 0.508 -0.3048)
			(stroke
				(width 0.1)
				(type default)
			)
			(layer "B.Fab")
		)
		(fp_line
			(start -0.508 -0.3048)
			(end -0.508 0.3048)
			(stroke
				(width 0.1)
				(type default)
			)
			(layer "B.Fab")
		)
		(fp_line
			(start 0.508 -0.3048)
			(end -0.508 -0.3048)
			(stroke
				(width 0.1)
				(type default)
			)
			(layer "B.Fab")
		)
		(pad "1" smd circle
			(at 0.500126 0 90)
			(size 0.635 0.635)
			(layers "B.Cu" "B.Mask" "B.Paste")
			(net "XP1R0V_FPGA_VCCINT")
		)
		(pad "2" smd circle
			(at -0.500126 0 90)
			(size 0.635 0.635)
			(layers "B.Cu" "B.Mask" "B.Paste")
			(net "SG")
		)
	)
	(footprint ""
		(layer "B.Cu")
		(at 76.784962 -15.367 -90)
		(property "Reference" "C36"
			(at -1.778 -2.169668 270)
			(unlocked yes)
			(layer "B.SilkS")
			(effects
				(font
					(size 0.7874 0.5842)
					(thickness 0.1524)
				)
				(justify mirror)
			)
		)
		(property "Value" "VAL*"
			(at -0.0762 2.067306 270)
			(unlocked yes)
			(layer "B.Fab")
			(hide yes)
			(effects
				(font
					(size 0.7874 0.5842)
					(thickness 0.1524)
				)
				(justify mirror)
			)
		)
		(property "Tolerance" "TOL*"
			(at -0.0762 3.032506 270)
			(unlocked yes)
			(layer "Cmts.User")
			(hide yes)
			(effects
				(font
					(size 0.7874 0.5842)
					(thickness 0.1524)
				)
				(justify mirror)
			)
		)
		(property "User Part Number" "PARTNUM*"
			(at -0.1016 4.023106 270)
			(unlocked yes)
			(layer "Cmts.User")
			(hide yes)
			(effects
				(font
					(size 0.7874 0.5842)
					(thickness 0.1524)
				)
				(justify mirror)
			)
		)
		(property "Device Type" "CAPACITOR-G105-0B104-CK,0.1UF,A"
			(at -0.0508 1.127506 270)
			(unlocked yes)
			(layer "B.Fab")
			(hide yes)
			(effects
				(font
					(size 0.7874 0.5842)
					(thickness 0.1524)
				)
				(justify mirror)
			)
		)
		(duplicate_pad_numbers_are_jumpers no)
		(fp_line
			(start -1.143 0.5588)
			(end -1.143 -0.5588)
			(stroke
				(width 0.1)
				(type default)
			)
			(layer "B.SilkS")
		)
		(fp_line
			(start 1.143 0.5588)
			(end -1.143 0.5588)
			(stroke
				(width 0.1)
				(type default)
			)
			(layer "B.SilkS")
		)
		(fp_line
			(start -1.143 -0.5588)
			(end 1.143 -0.5588)
			(stroke
				(width 0.1)
				(type default)
			)
			(layer "B.SilkS")
		)
		(fp_line
			(start 1.143 -0.5588)
			(end 1.143 0.5588)
			(stroke
				(width 0.1)
				(type default)
			)
			(layer "B.SilkS")
		)
		(fp_rect
			(start 1.143 0.5588)
			(end -1.143 -0.5588)
			(stroke
				(width 0)
				(type default)
			)
			(fill no)
			(layer "B.CrtYd")
		)
		(fp_line
			(start -0.508 0.3048)
			(end -0.508 -0.3048)
			(stroke
				(width 0.1)
				(type default)
			)
			(layer "B.Fab")
		)
		(fp_line
			(start 0.508 0.3048)
			(end -0.508 0.3048)
			(stroke
				(width 0.1)
				(type default)
			)
			(layer "B.Fab")
		)
		(fp_line
			(start -0.508 -0.3048)
			(end 0.508 -0.3048)
			(stroke
				(width 0.1)
				(type default)
			)
			(layer "B.Fab")
		)
		(fp_line
			(start 0.508 -0.3048)
			(end 0.508 0.3048)
			(stroke
				(width 0.1)
				(type default)
			)
			(layer "B.Fab")
		)
		(pad "1" smd rect
			(at 0.5334 0 90)
			(size 0.7112 0.6096)
			(layers "B.Cu" "B.Mask" "B.Paste")
			(net "C_CPU_RX_PCIE_MGT3_TXN")
		)
		(pad "2" smd rect
			(at -0.5334 0 90)
			(size 0.7112 0.6096)
			(layers "B.Cu" "B.Mask" "B.Paste")
			(net "CPU_RX_PCIE_MGT3_TXN")
		)
		(zone
			(layer "B.Cu")
			(hatch none 0.5)
			(connect_pads
				(clearance 0)
			)
			(min_thickness 0.25)
			(keepout
				(tracks allowed)
				(vias not_allowed)
				(pads allowed)
				(copperpour not_allowed)
				(footprints allowed)
			)
			(placement
				(enabled no)
				(sheetname "")
			)
			(fill
				(thermal_gap 0.5)
				(thermal_bridge_width 0.5)
				(island_removal_mode 0)
			)
			(polygon
				(pts
					(xy 76.480162 -15.2908) (xy 77.089762 -15.2908) (xy 77.089762 -15.4432) (xy 76.480162 -15.4432)
				)
			)
		)
	)
	(footprint ""
		(layer "B.Cu")
		(at 76.708 -50.927 180)
		(property "Reference" "C65"
			(at -3.175 0.08763 0)
			(unlocked yes)
			(layer "B.SilkS")
			(effects
				(font
					(size 0.7874 0.5842)
					(thickness 0.1524)
				)
				(justify mirror)
			)
		)
		(property "Value" "VAL*"
			(at -0.0762 2.067306 180)
			(unlocked yes)
			(layer "B.Fab")
			(hide yes)
			(effects
				(font
					(size 0.7874 0.5842)
					(thickness 0.1524)
				)
				(justify mirror)
			)
		)
		(property "Tolerance" "TOL*"
			(at -0.0762 3.032506 180)
			(unlocked yes)
			(layer "Cmts.User")
			(hide yes)
			(effects
				(font
					(size 0.7874 0.5842)
					(thickness 0.1524)
				)
				(justify mirror)
			)
		)
		(property "User Part Number" "PARTNUM*"
			(at -0.1016 4.023106 180)
			(unlocked yes)
			(layer "Cmts.User")
			(hide yes)
			(effects
				(font
					(size 0.7874 0.5842)
					(thickness 0.1524)
				)
				(justify mirror)
			)
		)
		(property "Device Type" "CAPACITOR-G105-0B104-EK,0.1UF,A"
			(at -0.0508 1.127506 180)
			(unlocked yes)
			(layer "B.Fab")
			(hide yes)
			(effects
				(font
					(size 0.7874 0.5842)
					(thickness 0.1524)
				)
				(justify mirror)
			)
		)
		(duplicate_pad_numbers_are_jumpers no)
		(fp_line
			(start 1.143 0.5588)
			(end -1.143 0.5588)
			(stroke
				(width 0.1)
				(type default)
			)
			(layer "B.SilkS")
		)
		(fp_line
			(start 1.143 -0.5588)
			(end 1.143 0.5588)
			(stroke
				(width 0.1)
				(type default)
			)
			(layer "B.SilkS")
		)
		(fp_line
			(start -1.143 0.5588)
			(end -1.143 -0.5588)
			(stroke
				(width 0.1)
				(type default)
			)
			(layer "B.SilkS")
		)
		(fp_line
			(start -1.143 -0.5588)
			(end 1.143 -0.5588)
			(stroke
				(width 0.1)
				(type default)
			)
			(layer "B.SilkS")
		)
		(fp_rect
			(start 1.143 0.5588)
			(end -1.143 -0.5588)
			(stroke
				(width 0)
				(type default)
			)
			(fill no)
			(layer "B.CrtYd")
		)
		(fp_line
			(start 0.508 0.3048)
			(end -0.508 0.3048)
			(stroke
				(width 0.1)
				(type default)
			)
			(layer "B.Fab")
		)
		(fp_line
			(start 0.508 -0.3048)
			(end 0.508 0.3048)
			(stroke
				(width 0.1)
				(type default)
			)
			(layer "B.Fab")
		)
		(fp_line
			(start -0.508 0.3048)
			(end -0.508 -0.3048)
			(stroke
				(width 0.1)
				(type default)
			)
			(layer "B.Fab")
		)
		(fp_line
			(start -0.508 -0.3048)
			(end 0.508 -0.3048)
			(stroke
				(width 0.1)
				(type default)
			)
			(layer "B.Fab")
		)
		(pad "1" smd rect
			(at 0.5334 0)
			(size 0.7112 0.6096)
			(layers "B.Cu" "B.Mask" "B.Paste")
			(net "XP5R0V_MAC_USB")
		)
		(pad "2" smd rect
			(at -0.5334 0)
			(size 0.7112 0.6096)
			(layers "B.Cu" "B.Mask" "B.Paste")
			(net "SG")
		)
		(zone
			(layer "B.Cu")
			(hatch none 0.5)
			(connect_pads
				(clearance 0)
			)
			(min_thickness 0.25)
			(keepout
				(tracks allowed)
				(vias not_allowed)
				(pads allowed)
				(copperpour not_allowed)
				(footprints allowed)
			)
			(placement
				(enabled no)
				(sheetname "")
			)
			(fill
				(thermal_gap 0.5)
				(thermal_bridge_width 0.5)
				(island_removal_mode 0)
			)
			(polygon
				(pts
					(xy 76.6318 -51.2318) (xy 76.6318 -50.6222) (xy 76.7842 -50.6222) (xy 76.7842 -51.2318)
				)
			)
		)
	)
	(footprint ""
		(layer "B.Cu")
		(at 112.84712 -46.322996 -90)
		(property "Reference" "R436"
			(at 2.032 43.029886 270)
			(unlocked yes)
			(layer "B.SilkS")
			(effects
				(font
					(size 0.635 0.4064)
					(thickness 0.1524)
				)
				(justify mirror)
			)
		)
		(property "Value" "VAL*"
			(at 0 3.718306 270)
			(unlocked yes)
			(layer "B.Fab")
			(hide yes)
			(effects
				(font
					(size 0.7874 0.5842)
					(thickness 0.127)
				)
				(justify mirror)
			)
		)
		(property "Tolerance" "TOL*"
			(at 0 4.861306 270)
			(unlocked yes)
			(layer "Cmts.User")
			(hide yes)
			(effects
				(font
					(size 0.7874 0.5842)
					(thickness 0.127)
				)
				(justify mirror)
			)
		)
		(property "User Part Number" "PARTNUM*"
			(at 0 2.575306 270)
			(unlocked yes)
			(layer "Cmts.User")
			(hide yes)
			(effects
				(font
					(size 0.7874 0.5842)
					(thickness 0.127)
				)
				(justify mirror)
			)
		)
		(property "Device Type" "RESISTOR-G155-11502-01,15KOHM,A"
			(at 0 1.432306 270)
			(unlocked yes)
			(layer "B.Fab")
			(hide yes)
			(effects
				(font
					(size 0.7874 0.5842)
					(thickness 0.127)
				)
				(justify mirror)
			)
		)
		(duplicate_pad_numbers_are_jumpers no)
		(fp_line
			(start -0.970026 0.4699)
			(end 0.970026 0.4699)
			(stroke
				(width 0.1)
				(type default)
			)
			(layer "B.SilkS")
		)
		(fp_line
			(start 0.970026 0.4699)
			(end 0.970026 -0.4699)
			(stroke
				(width 0.1)
				(type default)
			)
			(layer "B.SilkS")
		)
		(fp_line
			(start -0.970026 -0.4699)
			(end -0.970026 0.4699)
			(stroke
				(width 0.1)
				(type default)
			)
			(layer "B.SilkS")
		)
		(fp_line
			(start 0.970026 -0.4699)
			(end -0.970026 -0.4699)
			(stroke
				(width 0.1)
				(type default)
			)
			(layer "B.SilkS")
		)
		(fp_poly
			(pts
				(xy 0.970026 0.4699) (xy -0.970026 0.4699) (xy -0.970026 -0.4699) (xy 0.970026 -0.4699)
			)
			(stroke
				(width 0)
				(type default)
			)
			(fill no)
			(layer "B.CrtYd")
		)
		(fp_line
			(start -0.508 0.3048)
			(end 0.508 0.3048)
			(stroke
				(width 0.1)
				(type default)
			)
			(layer "B.Fab")
		)
		(fp_line
			(start 0.508 0.3048)
			(end 0.508 -0.3048)
			(stroke
				(width 0.1)
				(type default)
			)
			(layer "B.Fab")
		)
		(fp_line
			(start -0.508 -0.3048)
			(end -0.508 0.3048)
			(stroke
				(width 0.1)
				(type default)
			)
			(layer "B.Fab")
		)
		(fp_line
			(start 0.508 -0.3048)
			(end -0.508 -0.3048)
			(stroke
				(width 0.1)
				(type default)
			)
			(layer "B.Fab")
		)
		(pad "1" smd circle
			(at 0.500126 0 90)
			(size 0.635 0.635)
			(layers "B.Cu" "B.Mask" "B.Paste")
			(net "SG")
		)
		(pad "2" smd circle
			(at -0.500126 0 90)
			(size 0.635 0.635)
			(layers "B.Cu" "B.Mask" "B.Paste")
			(net "MAC_USB_DP")
		)
	)
	(footprint ""
		(layer "B.Cu")
		(at 34.544 -83.312 180)
		(property "Reference" "R132"
			(at 0.381 2.37363 0)
			(unlocked yes)
			(layer "B.SilkS")
			(effects
				(font
					(size 0.7874 0.5842)
					(thickness 0.1524)
				)
				(justify mirror)
			)
		)
		(property "Value" "VAL*"
			(at -0.02032 2.13233 180)
			(unlocked yes)
			(layer "B.Fab")
			(hide yes)
			(effects
				(font
					(size 0.7874 0.5842)
					(thickness 0.1524)
				)
				(justify mirror)
			)
		)
		(property "Tolerance" "TOL*"
			(at -0.044704 3.05435 180)
			(unlocked yes)
			(layer "Cmts.User")
			(hide yes)
			(effects
				(font
					(size 0.7874 0.5842)
					(thickness 0.1524)
				)
				(justify mirror)
			)
		)
		(property "User Part Number" "PARTNUM*"
			(at -0.02032 4.024884 180)
			(unlocked yes)
			(layer "Cmts.User")
			(hide yes)
			(effects
				(font
					(size 0.7874 0.5842)
					(thickness 0.1524)
				)
				(justify mirror)
			)
		)
		(property "Device Type" "RESISTOR-G155-11000-01,100OHM,A"
			(at -0.008382 1.210564 180)
			(unlocked yes)
			(layer "B.Fab")
			(hide yes)
			(effects
				(font
					(size 0.7874 0.5842)
					(thickness 0.1524)
				)
				(justify mirror)
			)
		)
		(duplicate_pad_numbers_are_jumpers no)
		(fp_line
			(start 1.143 0.5588)
			(end -1.143 0.5588)
			(stroke
				(width 0.1)
				(type default)
			)
			(layer "B.SilkS")
		)
		(fp_line
			(start 1.143 -0.5588)
			(end 1.143 0.5588)
			(stroke
				(width 0.1)
				(type default)
			)
			(layer "B.SilkS")
		)
		(fp_line
			(start -1.143 0.5588)
			(end -1.143 -0.5588)
			(stroke
				(width 0.1)
				(type default)
			)
			(layer "B.SilkS")
		)
		(fp_line
			(start -1.143 -0.5588)
			(end 1.143 -0.5588)
			(stroke
				(width 0.1)
				(type default)
			)
			(layer "B.SilkS")
		)
		(fp_rect
			(start 1.143 -0.5588)
			(end -1.143 0.5588)
			(stroke
				(width 0)
				(type default)
			)
			(fill no)
			(layer "B.CrtYd")
		)
		(fp_line
			(start 0.508 0.3048)
			(end -0.508 0.3048)
			(stroke
				(width 0.1)
				(type default)
			)
			(layer "B.Fab")
		)
		(fp_line
			(start 0.508 -0.3048)
			(end 0.508 0.3048)
			(stroke
				(width 0.1)
				(type default)
			)
			(layer "B.Fab")
		)
		(fp_line
			(start -0.508 0.3048)
			(end -0.508 -0.3048)
			(stroke
				(width 0.1)
				(type default)
			)
			(layer "B.Fab")
		)
		(fp_line
			(start -0.508 -0.3048)
			(end 0.508 -0.3048)
			(stroke
				(width 0.1)
				(type default)
			)
			(layer "B.Fab")
		)
		(pad "1" smd rect
			(at 0.5334 0)
			(size 0.7112 0.6096)
			(layers "B.Cu" "B.Mask" "B.Paste")
			(net "R_FT4232_CHD_RX")
		)
		(pad "2" smd rect
			(at -0.5334 0)
			(size 0.7112 0.6096)
			(layers "B.Cu" "B.Mask" "B.Paste")
			(net "FT4232_CHD_RX")
		)
		(zone
			(layer "B.Cu")
			(hatch none 0.5)
			(connect_pads
				(clearance 0)
			)
			(min_thickness 0.25)
			(keepout
				(tracks allowed)
				(vias not_allowed)
				(pads allowed)
				(copperpour not_allowed)
				(footprints allowed)
			)
			(placement
				(enabled no)
				(sheetname "")
			)
			(fill
				(thermal_gap 0.5)
				(thermal_bridge_width 0.5)
				(island_removal_mode 0)
			)
			(polygon
				(pts
					(xy 34.4678 -83.0072) (xy 34.6202 -83.0072) (xy 34.6202 -83.6168) (xy 34.4678 -83.6168)
				)
			)
		)
	)
	(footprint ""
		(layer "B.Cu")
		(at 117.346984 -42.82313)
		(property "Reference" "C210"
			(at 4.033266 0.78613 270)
			(unlocked yes)
			(layer "B.SilkS")
			(effects
				(font
					(size 0.635 0.4064)
					(thickness 0.1524)
				)
				(justify mirror)
			)
		)
		(property "Value" "VAL*"
			(at 0 3.718306 0)
			(unlocked yes)
			(layer "B.Fab")
			(hide yes)
			(effects
				(font
					(size 0.7874 0.5842)
					(thickness 0.127)
				)
				(justify mirror)
			)
		)
		(property "Tolerance" "TOL*"
			(at 0 4.861306 0)
			(unlocked yes)
			(layer "Cmts.User")
			(hide yes)
			(effects
				(font
					(size 0.7874 0.5842)
					(thickness 0.127)
				)
				(justify mirror)
			)
		)
		(property "User Part Number" "PARTNUM*"
			(at 0 2.575306 0)
			(unlocked yes)
			(layer "Cmts.User")
			(hide yes)
			(effects
				(font
					(size 0.7874 0.5842)
					(thickness 0.127)
				)
				(justify mirror)
			)
		)
		(property "Device Type" "CAPACITOR-G105-0B104-CK,0.1UF,A"
			(at 0 1.432306 0)
			(unlocked yes)
			(layer "B.Fab")
			(hide yes)
			(effects
				(font
					(size 0.7874 0.5842)
					(thickness 0.127)
				)
				(justify mirror)
			)
		)
		(duplicate_pad_numbers_are_jumpers no)
		(fp_line
			(start -0.970026 -0.4699)
			(end -0.970026 0.4699)
			(stroke
				(width 0.1)
				(type default)
			)
			(layer "B.SilkS")
		)
		(fp_line
			(start -0.970026 0.4699)
			(end 0.970026 0.4699)
			(stroke
				(width 0.1)
				(type default)
			)
			(layer "B.SilkS")
		)
		(fp_line
			(start 0.970026 -0.4699)
			(end -0.970026 -0.4699)
			(stroke
				(width 0.1)
				(type default)
			)
			(layer "B.SilkS")
		)
		(fp_line
			(start 0.970026 0.4699)
			(end 0.970026 -0.4699)
			(stroke
				(width 0.1)
				(type default)
			)
			(layer "B.SilkS")
		)
		(fp_poly
			(pts
				(xy 0.970026 0.4699) (xy -0.970026 0.4699) (xy -0.970026 -0.4699) (xy 0.970026 -0.4699)
			)
			(stroke
				(width 0)
				(type default)
			)
			(fill no)
			(layer "B.CrtYd")
		)
		(fp_line
			(start -0.508 -0.3048)
			(end -0.508 0.3048)
			(stroke
				(width 0.1)
				(type default)
			)
			(layer "B.Fab")
		)
		(fp_line
			(start -0.508 0.3048)
			(end 0.508 0.3048)
			(stroke
				(width 0.1)
				(type default)
			)
			(layer "B.Fab")
		)
		(fp_line
			(start 0.508 -0.3048)
			(end -0.508 -0.3048)
			(stroke
				(width 0.1)
				(type default)
			)
			(layer "B.Fab")
		)
		(fp_line
			(start 0.508 0.3048)
			(end 0.508 -0.3048)
			(stroke
				(width 0.1)
				(type default)
			)
			(layer "B.Fab")
		)
		(pad "1" smd circle
			(at 0.500126 0 180)
			(size 0.635 0.635)
			(layers "B.Cu" "B.Mask" "B.Paste")
			(net "XP3R3V_FPGA")
		)
		(pad "2" smd circle
			(at -0.500126 0 180)
			(size 0.635 0.635)
			(layers "B.Cu" "B.Mask" "B.Paste")
			(net "SG")
		)
	)
	(footprint ""
		(layer "B.Cu")
		(at 124.587 -45.974)
		(property "Reference" "R195"
			(at 3.683 0.16637 0)
			(unlocked yes)
			(layer "B.SilkS")
			(effects
				(font
					(size 0.7874 0.5842)
					(thickness 0.1524)
				)
				(justify mirror)
			)
		)
		(property "Value" "VAL*"
			(at -0.02032 2.13233 0)
			(unlocked yes)
			(layer "B.Fab")
			(hide yes)
			(effects
				(font
					(size 0.7874 0.5842)
					(thickness 0.1524)
				)
				(justify mirror)
			)
		)
		(property "Tolerance" "TOL*"
			(at -0.044704 3.05435 0)
			(unlocked yes)
			(layer "Cmts.User")
			(hide yes)
			(effects
				(font
					(size 0.7874 0.5842)
					(thickness 0.1524)
				)
				(justify mirror)
			)
		)
		(property "User Part Number" "PARTNUM*"
			(at -0.02032 4.024884 0)
			(unlocked yes)
			(layer "Cmts.User")
			(hide yes)
			(effects
				(font
					(size 0.7874 0.5842)
					(thickness 0.1524)
				)
				(justify mirror)
			)
		)
		(property "Device Type" "RESISTOR-G155-133R0-01,33OHM,1%"
			(at -0.008382 1.210564 0)
			(unlocked yes)
			(layer "B.Fab")
			(hide yes)
			(effects
				(font
					(size 0.7874 0.5842)
					(thickness 0.1524)
				)
				(justify mirror)
			)
		)
		(duplicate_pad_numbers_are_jumpers no)
		(fp_line
			(start -1.143 -0.5588)
			(end 1.143 -0.5588)
			(stroke
				(width 0.1)
				(type default)
			)
			(layer "B.SilkS")
		)
		(fp_line
			(start -1.143 0.5588)
			(end -1.143 -0.5588)
			(stroke
				(width 0.1)
				(type default)
			)
			(layer "B.SilkS")
		)
		(fp_line
			(start 1.143 -0.5588)
			(end 1.143 0.5588)
			(stroke
				(width 0.1)
				(type default)
			)
			(layer "B.SilkS")
		)
		(fp_line
			(start 1.143 0.5588)
			(end -1.143 0.5588)
			(stroke
				(width 0.1)
				(type default)
			)
			(layer "B.SilkS")
		)
		(fp_rect
			(start -1.143 -0.5588)
			(end 1.143 0.5588)
			(stroke
				(width 0)
				(type default)
			)
			(fill no)
			(layer "B.CrtYd")
		)
		(fp_line
			(start -0.508 -0.3048)
			(end 0.508 -0.3048)
			(stroke
				(width 0.1)
				(type default)
			)
			(layer "B.Fab")
		)
		(fp_line
			(start -0.508 0.3048)
			(end -0.508 -0.3048)
			(stroke
				(width 0.1)
				(type default)
			)
			(layer "B.Fab")
		)
		(fp_line
			(start 0.508 -0.3048)
			(end 0.508 0.3048)
			(stroke
				(width 0.1)
				(type default)
			)
			(layer "B.Fab")
		)
		(fp_line
			(start 0.508 0.3048)
			(end -0.508 0.3048)
			(stroke
				(width 0.1)
				(type default)
			)
			(layer "B.Fab")
		)
		(pad "1" smd rect
			(at 0.5334 0 180)
			(size 0.7112 0.6096)
			(layers "B.Cu" "B.Mask" "B.Paste")
			(net "FPGA_TDO")
		)
		(pad "2" smd rect
			(at -0.5334 0 180)
			(size 0.7112 0.6096)
			(layers "B.Cu" "B.Mask" "B.Paste")
			(net "R_FPGA_TDO")
		)
		(zone
			(layer "B.Cu")
			(hatch none 0.5)
			(connect_pads
				(clearance 0)
			)
			(min_thickness 0.25)
			(keepout
				(tracks allowed)
				(vias not_allowed)
				(pads allowed)
				(copperpour not_allowed)
				(footprints allowed)
			)
			(placement
				(enabled no)
				(sheetname "")
			)
			(fill
				(thermal_gap 0.5)
				(thermal_bridge_width 0.5)
				(island_removal_mode 0)
			)
			(polygon
				(pts
					(xy 124.5108 -46.2788) (xy 124.5108 -45.6692) (xy 124.6632 -45.6692) (xy 124.6632 -46.2788)
				)
			)
		)
	)
	(footprint ""
		(layer "B.Cu")
		(at 47.879 -75.184 -90)
		(property "Reference" "R488"
			(at 0.381 -1.23063 270)
			(unlocked yes)
			(layer "B.SilkS")
			(effects
				(font
					(size 0.7874 0.5842)
					(thickness 0.1524)
				)
				(justify mirror)
			)
		)
		(property "Value" "VAL*"
			(at -0.02032 2.13233 270)
			(unlocked yes)
			(layer "B.Fab")
			(hide yes)
			(effects
				(font
					(size 0.7874 0.5842)
					(thickness 0.1524)
				)
				(justify mirror)
			)
		)
		(property "Tolerance" "TOL*"
			(at -0.044704 3.05435 270)
			(unlocked yes)
			(layer "Cmts.User")
			(hide yes)
			(effects
				(font
					(size 0.7874 0.5842)
					(thickness 0.1524)
				)
				(justify mirror)
			)
		)
		(property "User Part Number" "PARTNUM*"
			(at -0.02032 4.024884 270)
			(unlocked yes)
			(layer "Cmts.User")
			(hide yes)
			(effects
				(font
					(size 0.7874 0.5842)
					(thickness 0.1524)
				)
				(justify mirror)
			)
		)
		(property "Device Type" "RESISTOR-G155-11002-01,10KOHM,A"
			(at -0.008382 1.210564 270)
			(unlocked yes)
			(layer "B.Fab")
			(hide yes)
			(effects
				(font
					(size 0.7874 0.5842)
					(thickness 0.1524)
				)
				(justify mirror)
			)
		)
		(duplicate_pad_numbers_are_jumpers no)
		(fp_line
			(start -1.143 0.5588)
			(end -1.143 -0.5588)
			(stroke
				(width 0.1)
				(type default)
			)
			(layer "B.SilkS")
		)
		(fp_line
			(start 1.143 0.5588)
			(end -1.143 0.5588)
			(stroke
				(width 0.1)
				(type default)
			)
			(layer "B.SilkS")
		)
		(fp_line
			(start -1.143 -0.5588)
			(end 1.143 -0.5588)
			(stroke
				(width 0.1)
				(type default)
			)
			(layer "B.SilkS")
		)
		(fp_line
			(start 1.143 -0.5588)
			(end 1.143 0.5588)
			(stroke
				(width 0.1)
				(type default)
			)
			(layer "B.SilkS")
		)
		(fp_poly
			(pts
				(xy 1.143 0.5588) (xy -1.143 0.5588) (xy -1.143 -0.5588) (xy 1.143 -0.5588)
			)
			(stroke
				(width 0)
				(type default)
			)
			(fill no)
			(layer "B.CrtYd")
		)
		(fp_line
			(start -0.508 0.3048)
			(end -0.508 -0.3048)
			(stroke
				(width 0.1)
				(type default)
			)
			(layer "B.Fab")
		)
		(fp_line
			(start 0.508 0.3048)
			(end -0.508 0.3048)
			(stroke
				(width 0.1)
				(type default)
			)
			(layer "B.Fab")
		)
		(fp_line
			(start -0.508 -0.3048)
			(end 0.508 -0.3048)
			(stroke
				(width 0.1)
				(type default)
			)
			(layer "B.Fab")
		)
		(fp_line
			(start 0.508 -0.3048)
			(end 0.508 0.3048)
			(stroke
				(width 0.1)
				(type default)
			)
			(layer "B.Fab")
		)
		(pad "1" smd rect
			(at 0.5334 0 90)
			(size 0.7112 0.6096)
			(layers "B.Cu" "B.Mask" "B.Paste")
			(net "UNNAMED_525_CAPACITOR_I14_1")
		)
		(pad "2" smd rect
			(at -0.5334 0 90)
			(size 0.7112 0.6096)
			(layers "B.Cu" "B.Mask" "B.Paste")
			(net "SG")
		)
		(zone
			(layer "B.Cu")
			(hatch none 0.5)
			(connect_pads
				(clearance 0)
			)
			(min_thickness 0.25)
			(keepout
				(tracks allowed)
				(vias not_allowed)
				(pads allowed)
				(copperpour not_allowed)
				(footprints allowed)
			)
			(placement
				(enabled no)
				(sheetname "")
			)
			(fill
				(thermal_gap 0.5)
				(thermal_bridge_width 0.5)
				(island_removal_mode 0)
			)
			(polygon
				(pts
					(xy 47.5742 -75.1078) (xy 48.1838 -75.1078) (xy 48.1838 -75.2602) (xy 47.5742 -75.2602)
				)
			)
		)
		(zone
			(layer "B.Cu")
			(hatch none 0.5)
			(connect_pads
				(clearance 0)
			)
			(min_thickness 0.25)
			(keepout
				(tracks not_allowed)
				(vias allowed)
				(pads allowed)
				(copperpour not_allowed)
				(footprints allowed)
			)
			(placement
				(enabled no)
				(sheetname "")
			)
			(fill
				(thermal_gap 0.5)
				(thermal_bridge_width 0.5)
				(island_removal_mode 0)
			)
			(polygon
				(pts
					(xy 47.5742 -75.1078) (xy 48.1838 -75.1078) (xy 48.1838 -75.2602) (xy 47.5742 -75.2602)
				)
			)
		)
	)
	(footprint ""
		(layer "B.Cu")
		(at 41.783 -98.679 180)
		(property "Reference" "R31"
			(at 0.762 1.23063 0)
			(unlocked yes)
			(layer "B.SilkS")
			(effects
				(font
					(size 0.7874 0.5842)
					(thickness 0.1524)
				)
				(justify mirror)
			)
		)
		(property "Value" "VAL*"
			(at -0.02032 2.13233 180)
			(unlocked yes)
			(layer "B.Fab")
			(hide yes)
			(effects
				(font
					(size 0.7874 0.5842)
					(thickness 0.1524)
				)
				(justify mirror)
			)
		)
		(property "Tolerance" "TOL*"
			(at -0.044704 3.05435 180)
			(unlocked yes)
			(layer "Cmts.User")
			(hide yes)
			(effects
				(font
					(size 0.7874 0.5842)
					(thickness 0.1524)
				)
				(justify mirror)
			)
		)
		(property "User Part Number" "PARTNUM*"
			(at -0.02032 4.024884 180)
			(unlocked yes)
			(layer "Cmts.User")
			(hide yes)
			(effects
				(font
					(size 0.7874 0.5842)
					(thickness 0.1524)
				)
				(justify mirror)
			)
		)
		(property "Device Type" "RESISTOR-G155-100R0-J0,0OHM,-"
			(at -0.008382 1.210564 180)
			(unlocked yes)
			(layer "B.Fab")
			(hide yes)
			(effects
				(font
					(size 0.7874 0.5842)
					(thickness 0.1524)
				)
				(justify mirror)
			)
		)
		(duplicate_pad_numbers_are_jumpers no)
		(fp_line
			(start 1.143 0.5588)
			(end -1.143 0.5588)
			(stroke
				(width 0.1)
				(type default)
			)
			(layer "B.SilkS")
		)
		(fp_line
			(start 1.143 -0.5588)
			(end 1.143 0.5588)
			(stroke
				(width 0.1)
				(type default)
			)
			(layer "B.SilkS")
		)
		(fp_line
			(start -1.143 0.5588)
			(end -1.143 -0.5588)
			(stroke
				(width 0.1)
				(type default)
			)
			(layer "B.SilkS")
		)
		(fp_line
			(start -1.143 -0.5588)
			(end 1.143 -0.5588)
			(stroke
				(width 0.1)
				(type default)
			)
			(layer "B.SilkS")
		)
		(fp_poly
			(pts
				(xy 1.143 0.5588) (xy -1.143 0.5588) (xy -1.143 -0.5588) (xy 1.143 -0.5588)
			)
			(stroke
				(width 0)
				(type default)
			)
			(fill no)
			(layer "B.CrtYd")
		)
		(fp_line
			(start 0.508 0.3048)
			(end -0.508 0.3048)
			(stroke
				(width 0.1)
				(type default)
			)
			(layer "B.Fab")
		)
		(fp_line
			(start 0.508 -0.3048)
			(end 0.508 0.3048)
			(stroke
				(width 0.1)
				(type default)
			)
			(layer "B.Fab")
		)
		(fp_line
			(start -0.508 0.3048)
			(end -0.508 -0.3048)
			(stroke
				(width 0.1)
				(type default)
			)
			(layer "B.Fab")
		)
		(fp_line
			(start -0.508 -0.3048)
			(end 0.508 -0.3048)
			(stroke
				(width 0.1)
				(type default)
			)
			(layer "B.Fab")
		)
		(pad "1" smd rect
			(at 0.5334 0)
			(size 0.7112 0.6096)
			(layers "B.Cu" "B.Mask" "B.Paste")
			(net "XP5R0V_BT")
		)
		(pad "2" smd rect
			(at -0.5334 0)
			(size 0.7112 0.6096)
			(layers "B.Cu" "B.Mask" "B.Paste")
			(net "UNNAMED_516_CAPACITOR_I27_1")
		)
		(zone
			(layer "B.Cu")
			(hatch none 0.5)
			(connect_pads
				(clearance 0)
			)
			(min_thickness 0.25)
			(keepout
				(tracks not_allowed)
				(vias allowed)
				(pads allowed)
				(copperpour not_allowed)
				(footprints allowed)
			)
			(placement
				(enabled no)
				(sheetname "")
			)
			(fill
				(thermal_gap 0.5)
				(thermal_bridge_width 0.5)
				(island_removal_mode 0)
			)
			(polygon
				(pts
					(xy 41.7068 -98.9838) (xy 41.7068 -98.3742) (xy 41.8592 -98.3742) (xy 41.8592 -98.9838)
				)
			)
		)
		(zone
			(layer "B.Cu")
			(hatch none 0.5)
			(connect_pads
				(clearance 0)
			)
			(min_thickness 0.25)
			(keepout
				(tracks allowed)
				(vias not_allowed)
				(pads allowed)
				(copperpour not_allowed)
				(footprints allowed)
			)
			(placement
				(enabled no)
				(sheetname "")
			)
			(fill
				(thermal_gap 0.5)
				(thermal_bridge_width 0.5)
				(island_removal_mode 0)
			)
			(polygon
				(pts
					(xy 41.7068 -98.9838) (xy 41.7068 -98.3742) (xy 41.8592 -98.3742) (xy 41.8592 -98.9838)
				)
			)
		)
	)
	(footprint ""
		(layer "B.Cu")
		(at 111.847122 -55.323232 -90)
		(property "Reference" "C223"
			(at -2.207768 -0.008128 270)
			(unlocked yes)
			(layer "B.SilkS")
			(effects
				(font
					(size 0.635 0.4064)
					(thickness 0.1524)
				)
				(justify mirror)
			)
		)
		(property "Value" "VAL*"
			(at 0 3.718306 270)
			(unlocked yes)
			(layer "B.Fab")
			(hide yes)
			(effects
				(font
					(size 0.7874 0.5842)
					(thickness 0.127)
				)
				(justify mirror)
			)
		)
		(property "Tolerance" "TOL*"
			(at 0 4.861306 270)
			(unlocked yes)
			(layer "Cmts.User")
			(hide yes)
			(effects
				(font
					(size 0.7874 0.5842)
					(thickness 0.127)
				)
				(justify mirror)
			)
		)
		(property "User Part Number" "PARTNUM*"
			(at 0 2.575306 270)
			(unlocked yes)
			(layer "Cmts.User")
			(hide yes)
			(effects
				(font
					(size 0.7874 0.5842)
					(thickness 0.127)
				)
				(justify mirror)
			)
		)
		(property "Device Type" "CAPACITOR-G105-0B104-CK,0.1UF,A"
			(at 0 1.432306 270)
			(unlocked yes)
			(layer "B.Fab")
			(hide yes)
			(effects
				(font
					(size 0.7874 0.5842)
					(thickness 0.127)
				)
				(justify mirror)
			)
		)
		(duplicate_pad_numbers_are_jumpers no)
		(fp_line
			(start -0.970026 0.4699)
			(end 0.970026 0.4699)
			(stroke
				(width 0.1)
				(type default)
			)
			(layer "B.SilkS")
		)
		(fp_line
			(start 0.970026 0.4699)
			(end 0.970026 -0.4699)
			(stroke
				(width 0.1)
				(type default)
			)
			(layer "B.SilkS")
		)
		(fp_line
			(start -0.970026 -0.4699)
			(end -0.970026 0.4699)
			(stroke
				(width 0.1)
				(type default)
			)
			(layer "B.SilkS")
		)
		(fp_line
			(start 0.970026 -0.4699)
			(end -0.970026 -0.4699)
			(stroke
				(width 0.1)
				(type default)
			)
			(layer "B.SilkS")
		)
		(fp_poly
			(pts
				(xy 0.970026 0.4699) (xy -0.970026 0.4699) (xy -0.970026 -0.4699) (xy 0.970026 -0.4699)
			)
			(stroke
				(width 0)
				(type default)
			)
			(fill no)
			(layer "B.CrtYd")
		)
		(fp_line
			(start -0.508 0.3048)
			(end 0.508 0.3048)
			(stroke
				(width 0.1)
				(type default)
			)
			(layer "B.Fab")
		)
		(fp_line
			(start 0.508 0.3048)
			(end 0.508 -0.3048)
			(stroke
				(width 0.1)
				(type default)
			)
			(layer "B.Fab")
		)
		(fp_line
			(start -0.508 -0.3048)
			(end -0.508 0.3048)
			(stroke
				(width 0.1)
				(type default)
			)
			(layer "B.Fab")
		)
		(fp_line
			(start 0.508 -0.3048)
			(end -0.508 -0.3048)
			(stroke
				(width 0.1)
				(type default)
			)
			(layer "B.Fab")
		)
		(pad "1" smd circle
			(at 0.500126 0 90)
			(size 0.635 0.635)
			(layers "B.Cu" "B.Mask" "B.Paste")
			(net "XP3R3V_FPGA")
		)
		(pad "2" smd circle
			(at -0.500126 0 90)
			(size 0.635 0.635)
			(layers "B.Cu" "B.Mask" "B.Paste")
			(net "SG")
		)
	)
	(footprint ""
		(layer "B.Cu")
		(at 99.5426 -64.2874 90)
		(property "Reference" "R173"
			(at 3.4036 0.11303 270)
			(unlocked yes)
			(layer "B.SilkS")
			(effects
				(font
					(size 0.7874 0.5842)
					(thickness 0.1524)
				)
				(justify mirror)
			)
		)
		(property "Value" "VAL*"
			(at -0.02032 2.13233 90)
			(unlocked yes)
			(layer "B.Fab")
			(hide yes)
			(effects
				(font
					(size 0.7874 0.5842)
					(thickness 0.1524)
				)
				(justify mirror)
			)
		)
		(property "Tolerance" "TOL*"
			(at -0.044704 3.05435 90)
			(unlocked yes)
			(layer "Cmts.User")
			(hide yes)
			(effects
				(font
					(size 0.7874 0.5842)
					(thickness 0.1524)
				)
				(justify mirror)
			)
		)
		(property "User Part Number" "PARTNUM*"
			(at -0.02032 4.024884 90)
			(unlocked yes)
			(layer "Cmts.User")
			(hide yes)
			(effects
				(font
					(size 0.7874 0.5842)
					(thickness 0.1524)
				)
				(justify mirror)
			)
		)
		(property "Device Type" "RESISTOR-G155-14701-01,4.7KOHMA"
			(at -0.008382 1.210564 90)
			(unlocked yes)
			(layer "B.Fab")
			(hide yes)
			(effects
				(font
					(size 0.7874 0.5842)
					(thickness 0.1524)
				)
				(justify mirror)
			)
		)
		(duplicate_pad_numbers_are_jumpers no)
		(fp_line
			(start 1.143 -0.5588)
			(end 1.143 0.5588)
			(stroke
				(width 0.1)
				(type default)
			)
			(layer "B.SilkS")
		)
		(fp_line
			(start -1.143 -0.5588)
			(end 1.143 -0.5588)
			(stroke
				(width 0.1)
				(type default)
			)
			(layer "B.SilkS")
		)
		(fp_line
			(start 1.143 0.5588)
			(end -1.143 0.5588)
			(stroke
				(width 0.1)
				(type default)
			)
			(layer "B.SilkS")
		)
		(fp_line
			(start -1.143 0.5588)
			(end -1.143 -0.5588)
			(stroke
				(width 0.1)
				(type default)
			)
			(layer "B.SilkS")
		)
		(fp_poly
			(pts
				(xy 1.143 0.5588) (xy -1.143 0.5588) (xy -1.143 -0.5588) (xy 1.143 -0.5588)
			)
			(stroke
				(width 0)
				(type default)
			)
			(fill no)
			(layer "B.CrtYd")
		)
		(fp_line
			(start 0.508 -0.3048)
			(end 0.508 0.3048)
			(stroke
				(width 0.1)
				(type default)
			)
			(layer "B.Fab")
		)
		(fp_line
			(start -0.508 -0.3048)
			(end 0.508 -0.3048)
			(stroke
				(width 0.1)
				(type default)
			)
			(layer "B.Fab")
		)
		(fp_line
			(start 0.508 0.3048)
			(end -0.508 0.3048)
			(stroke
				(width 0.1)
				(type default)
			)
			(layer "B.Fab")
		)
		(fp_line
			(start -0.508 0.3048)
			(end -0.508 -0.3048)
			(stroke
				(width 0.1)
				(type default)
			)
			(layer "B.Fab")
		)
		(pad "1" smd rect
			(at 0.5334 0 270)
			(size 0.7112 0.6096)
			(layers "B.Cu" "B.Mask" "B.Paste")
			(net "SG")
		)
		(pad "2" smd rect
			(at -0.5334 0 270)
			(size 0.7112 0.6096)
			(layers "B.Cu" "B.Mask" "B.Paste")
			(net "FPGA_IO_1")
		)
		(zone
			(layer "B.Cu")
			(hatch none 0.5)
			(connect_pads
				(clearance 0)
			)
			(min_thickness 0.25)
			(keepout
				(tracks not_allowed)
				(vias allowed)
				(pads allowed)
				(copperpour not_allowed)
				(footprints allowed)
			)
			(placement
				(enabled no)
				(sheetname "")
			)
			(fill
				(thermal_gap 0.5)
				(thermal_bridge_width 0.5)
				(island_removal_mode 0)
			)
			(polygon
				(pts
					(xy 99.8474 -64.3636) (xy 99.2378 -64.3636) (xy 99.2378 -64.2112) (xy 99.8474 -64.2112)
				)
			)
		)
		(zone
			(layer "B.Cu")
			(hatch none 0.5)
			(connect_pads
				(clearance 0)
			)
			(min_thickness 0.25)
			(keepout
				(tracks allowed)
				(vias not_allowed)
				(pads allowed)
				(copperpour not_allowed)
				(footprints allowed)
			)
			(placement
				(enabled no)
				(sheetname "")
			)
			(fill
				(thermal_gap 0.5)
				(thermal_bridge_width 0.5)
				(island_removal_mode 0)
			)
			(polygon
				(pts
					(xy 99.8474 -64.3636) (xy 99.2378 -64.3636) (xy 99.2378 -64.2112) (xy 99.8474 -64.2112)
				)
			)
		)
	)
	(footprint ""
		(layer "B.Cu")
		(at 116.346986 -46.823122)
		(property "Reference" "R502"
			(at -42.940986 2.658872 0)
			(unlocked yes)
			(layer "B.SilkS")
			(effects
				(font
					(size 0.635 0.4064)
					(thickness 0.1524)
				)
				(justify mirror)
			)
		)
		(property "Value" "VAL*"
			(at 0 3.718306 0)
			(unlocked yes)
			(layer "B.Fab")
			(hide yes)
			(effects
				(font
					(size 0.7874 0.5842)
					(thickness 0.127)
				)
				(justify mirror)
			)
		)
		(property "Tolerance" "TOL*"
			(at 0 4.861306 0)
			(unlocked yes)
			(layer "Cmts.User")
			(hide yes)
			(effects
				(font
					(size 0.7874 0.5842)
					(thickness 0.127)
				)
				(justify mirror)
			)
		)
		(property "User Part Number" "PARTNUM*"
			(at 0 2.575306 0)
			(unlocked yes)
			(layer "Cmts.User")
			(hide yes)
			(effects
				(font
					(size 0.7874 0.5842)
					(thickness 0.127)
				)
				(justify mirror)
			)
		)
		(property "Device Type" "RESISTOR-G155-12201-01,2.2KOHMA"
			(at 0 1.432306 0)
			(unlocked yes)
			(layer "B.Fab")
			(hide yes)
			(effects
				(font
					(size 0.7874 0.5842)
					(thickness 0.127)
				)
				(justify mirror)
			)
		)
		(duplicate_pad_numbers_are_jumpers no)
		(fp_line
			(start -0.970026 -0.4699)
			(end -0.970026 0.4699)
			(stroke
				(width 0.1)
				(type default)
			)
			(layer "B.SilkS")
		)
		(fp_line
			(start -0.970026 0.4699)
			(end 0.970026 0.4699)
			(stroke
				(width 0.1)
				(type default)
			)
			(layer "B.SilkS")
		)
		(fp_line
			(start 0.970026 -0.4699)
			(end -0.970026 -0.4699)
			(stroke
				(width 0.1)
				(type default)
			)
			(layer "B.SilkS")
		)
		(fp_line
			(start 0.970026 0.4699)
			(end 0.970026 -0.4699)
			(stroke
				(width 0.1)
				(type default)
			)
			(layer "B.SilkS")
		)
		(fp_poly
			(pts
				(xy 0.970026 0.4699) (xy -0.970026 0.4699) (xy -0.970026 -0.4699) (xy 0.970026 -0.4699)
			)
			(stroke
				(width 0)
				(type default)
			)
			(fill no)
			(layer "B.CrtYd")
		)
		(fp_line
			(start -0.508 -0.3048)
			(end -0.508 0.3048)
			(stroke
				(width 0.1)
				(type default)
			)
			(layer "B.Fab")
		)
		(fp_line
			(start -0.508 0.3048)
			(end 0.508 0.3048)
			(stroke
				(width 0.1)
				(type default)
			)
			(layer "B.Fab")
		)
		(fp_line
			(start 0.508 -0.3048)
			(end -0.508 -0.3048)
			(stroke
				(width 0.1)
				(type default)
			)
			(layer "B.Fab")
		)
		(fp_line
			(start 0.508 0.3048)
			(end 0.508 -0.3048)
			(stroke
				(width 0.1)
				(type default)
			)
			(layer "B.Fab")
		)
		(pad "1" smd circle
			(at 0.500126 0 180)
			(size 0.635 0.635)
			(layers "B.Cu" "B.Mask" "B.Paste")
			(net "XP3R3V_FPGA")
		)
		(pad "2" smd circle
			(at -0.500126 0 180)
			(size 0.635 0.635)
			(layers "B.Cu" "B.Mask" "B.Paste")
			(net "FPGA_IN_MAC_10MHZ_OUT")
		)
	)
	(footprint ""
		(layer "B.Cu")
		(at 138.4808 -70.9168 90)
		(property "Reference" "R403"
			(at 0.9652 -4.78917 270)
			(unlocked yes)
			(layer "B.SilkS")
			(effects
				(font
					(size 0.7874 0.5842)
					(thickness 0.1524)
				)
				(justify mirror)
			)
		)
		(property "Value" "VAL*"
			(at -0.02032 2.13233 90)
			(unlocked yes)
			(layer "B.Fab")
			(hide yes)
			(effects
				(font
					(size 0.7874 0.5842)
					(thickness 0.1524)
				)
				(justify mirror)
			)
		)
		(property "Tolerance" "TOL*"
			(at -0.044704 3.05435 90)
			(unlocked yes)
			(layer "Cmts.User")
			(hide yes)
			(effects
				(font
					(size 0.7874 0.5842)
					(thickness 0.1524)
				)
				(justify mirror)
			)
		)
		(property "User Part Number" "PARTNUM*"
			(at -0.02032 4.024884 90)
			(unlocked yes)
			(layer "Cmts.User")
			(hide yes)
			(effects
				(font
					(size 0.7874 0.5842)
					(thickness 0.1524)
				)
				(justify mirror)
			)
		)
		(property "Device Type" "RESISTOR-G155-11002-01,10KOHM,A"
			(at -0.008382 1.210564 90)
			(unlocked yes)
			(layer "B.Fab")
			(hide yes)
			(effects
				(font
					(size 0.7874 0.5842)
					(thickness 0.1524)
				)
				(justify mirror)
			)
		)
		(duplicate_pad_numbers_are_jumpers no)
		(fp_line
			(start 1.143 -0.5588)
			(end 1.143 0.5588)
			(stroke
				(width 0.1)
				(type default)
			)
			(layer "B.SilkS")
		)
		(fp_line
			(start -1.143 -0.5588)
			(end 1.143 -0.5588)
			(stroke
				(width 0.1)
				(type default)
			)
			(layer "B.SilkS")
		)
		(fp_line
			(start 1.143 0.5588)
			(end -1.143 0.5588)
			(stroke
				(width 0.1)
				(type default)
			)
			(layer "B.SilkS")
		)
		(fp_line
			(start -1.143 0.5588)
			(end -1.143 -0.5588)
			(stroke
				(width 0.1)
				(type default)
			)
			(layer "B.SilkS")
		)
		(fp_rect
			(start 1.143 0.5588)
			(end -1.143 -0.5588)
			(stroke
				(width 0)
				(type default)
			)
			(fill no)
			(layer "B.CrtYd")
		)
		(fp_line
			(start 0.508 -0.3048)
			(end 0.508 0.3048)
			(stroke
				(width 0.1)
				(type default)
			)
			(layer "B.Fab")
		)
		(fp_line
			(start -0.508 -0.3048)
			(end 0.508 -0.3048)
			(stroke
				(width 0.1)
				(type default)
			)
			(layer "B.Fab")
		)
		(fp_line
			(start 0.508 0.3048)
			(end -0.508 0.3048)
			(stroke
				(width 0.1)
				(type default)
			)
			(layer "B.Fab")
		)
		(fp_line
			(start -0.508 0.3048)
			(end -0.508 -0.3048)
			(stroke
				(width 0.1)
				(type default)
			)
			(layer "B.Fab")
		)
		(pad "1" smd rect
			(at 0.5334 0 270)
			(size 0.7112 0.6096)
			(layers "B.Cu" "B.Mask" "B.Paste")
			(net "XP3R3V_FPGA")
		)
		(pad "2" smd rect
			(at -0.5334 0 270)
			(size 0.7112 0.6096)
			(layers "B.Cu" "B.Mask" "B.Paste")
			(net "FPGA_TDO")
		)
		(zone
			(layer "B.Cu")
			(hatch none 0.5)
			(connect_pads
				(clearance 0)
			)
			(min_thickness 0.25)
			(keepout
				(tracks not_allowed)
				(vias allowed)
				(pads allowed)
				(copperpour not_allowed)
				(footprints allowed)
			)
			(placement
				(enabled no)
				(sheetname "")
			)
			(fill
				(thermal_gap 0.5)
				(thermal_bridge_width 0.5)
				(island_removal_mode 0)
			)
			(polygon
				(pts
					(xy 138.7856 -70.993) (xy 138.176 -70.993) (xy 138.176 -70.8406) (xy 138.7856 -70.8406)
				)
			)
		)
		(zone
			(layer "B.Cu")
			(hatch none 0.5)
			(connect_pads
				(clearance 0)
			)
			(min_thickness 0.25)
			(keepout
				(tracks allowed)
				(vias not_allowed)
				(pads allowed)
				(copperpour not_allowed)
				(footprints allowed)
			)
			(placement
				(enabled no)
				(sheetname "")
			)
			(fill
				(thermal_gap 0.5)
				(thermal_bridge_width 0.5)
				(island_removal_mode 0)
			)
			(polygon
				(pts
					(xy 138.7856 -70.993) (xy 138.176 -70.993) (xy 138.176 -70.8406) (xy 138.7856 -70.8406)
				)
			)
		)
	)
	(footprint ""
		(layer "B.Cu")
		(at 36.9824 -99.0854 180)
		(property "Reference" "R142"
			(at 4.4196 -0.62357 0)
			(unlocked yes)
			(layer "B.SilkS")
			(effects
				(font
					(size 0.7874 0.5842)
					(thickness 0.1524)
				)
				(justify mirror)
			)
		)
		(property "Value" "VAL*"
			(at -0.02032 2.13233 180)
			(unlocked yes)
			(layer "B.Fab")
			(hide yes)
			(effects
				(font
					(size 0.7874 0.5842)
					(thickness 0.1524)
				)
				(justify mirror)
			)
		)
		(property "Device Type" "RESISTOR-G155-11000-01,100OHM,A"
			(at -0.008382 1.210564 180)
			(unlocked yes)
			(layer "B.Fab")
			(hide yes)
			(effects
				(font
					(size 0.7874 0.5842)
					(thickness 0.1524)
				)
				(justify mirror)
			)
		)
		(property "User Part Number" "PARTNUM*"
			(at -0.02032 4.024884 180)
			(unlocked yes)
			(layer "Cmts.User")
			(hide yes)
			(effects
				(font
					(size 0.7874 0.5842)
					(thickness 0.1524)
				)
				(justify mirror)
			)
		)
		(property "Tolerance" "TOL*"
			(at -0.044704 3.05435 180)
			(unlocked yes)
			(layer "Cmts.User")
			(hide yes)
			(effects
				(font
					(size 0.7874 0.5842)
					(thickness 0.1524)
				)
				(justify mirror)
			)
		)
		(duplicate_pad_numbers_are_jumpers no)
		(fp_line
			(start 1.143 0.5588)
			(end -1.143 0.5588)
			(stroke
				(width 0.1)
				(type default)
			)
			(layer "B.SilkS")
		)
		(fp_line
			(start 1.143 -0.5588)
			(end 1.143 0.5588)
			(stroke
				(width 0.1)
				(type default)
			)
			(layer "B.SilkS")
		)
		(fp_line
			(start -1.143 0.5588)
			(end -1.143 -0.5588)
			(stroke
				(width 0.1)
				(type default)
			)
			(layer "B.SilkS")
		)
		(fp_line
			(start -1.143 -0.5588)
			(end 1.143 -0.5588)
			(stroke
				(width 0.1)
				(type default)
			)
			(layer "B.SilkS")
		)
		(fp_rect
			(start -1.143 0.5588)
			(end 1.143 -0.5588)
			(stroke
				(width 0)
				(type default)
			)
			(fill no)
			(layer "B.CrtYd")
		)
		(fp_line
			(start 0.508 0.3048)
			(end -0.508 0.3048)
			(stroke
				(width 0.1)
				(type default)
			)
			(layer "B.Fab")
		)
		(fp_line
			(start 0.508 -0.3048)
			(end 0.508 0.3048)
			(stroke
				(width 0.1)
				(type default)
			)
			(layer "B.Fab")
		)
		(fp_line
			(start -0.508 0.3048)
			(end -0.508 -0.3048)
			(stroke
				(width 0.1)
				(type default)
			)
			(layer "B.Fab")
		)
		(fp_line
			(start -0.508 -0.3048)
			(end 0.508 -0.3048)
			(stroke
				(width 0.1)
				(type default)
			)
			(layer "B.Fab")
		)
		(pad "1" smd rect
			(at 0.5334 0)
			(size 0.7112 0.6096)
			(layers "B.Cu" "B.Mask" "B.Paste")
			(net "XP1R8V_FPGA_PG")
		)
		(pad "2" smd rect
			(at -0.5334 0)
			(size 0.7112 0.6096)
			(layers "B.Cu" "B.Mask" "B.Paste")
			(net "R_XP5R0V_EN")
		)
		(zone
			(layer "B.Cu")
			(hatch none 0.5)
			(connect_pads
				(clearance 0)
			)
			(min_thickness 0.25)
			(keepout
				(tracks allowed)
				(vias not_allowed)
				(pads allowed)
				(copperpour not_allowed)
				(footprints allowed)
			)
			(placement
				(enabled no)
				(sheetname "")
			)
			(fill
				(thermal_gap 0.5)
				(thermal_bridge_width 0.5)
				(island_removal_mode 0)
			)
			(polygon
				(pts
					(xy 37.0586 -99.3902) (xy 36.9062 -99.3902) (xy 36.9062 -98.7806) (xy 37.0586 -98.7806)
				)
			)
		)
	)
	(footprint ""
		(layer "B.Cu")
		(at 117.729 -100.076)
		(property "Reference" "C273"
			(at -1.397 -1.48463 0)
			(unlocked yes)
			(layer "B.SilkS")
			(effects
				(font
					(size 0.7874 0.5842)
					(thickness 0.1524)
				)
				(justify mirror)
			)
		)
		(property "Value" "VAL*"
			(at -0.0762 2.067306 0)
			(unlocked yes)
			(layer "B.Fab")
			(hide yes)
			(effects
				(font
					(size 0.7874 0.5842)
					(thickness 0.1524)
				)
				(justify mirror)
			)
		)
		(property "Tolerance" "TOL*"
			(at -0.0762 3.032506 0)
			(unlocked yes)
			(layer "Cmts.User")
			(hide yes)
			(effects
				(font
					(size 0.7874 0.5842)
					(thickness 0.1524)
				)
				(justify mirror)
			)
		)
		(property "User Part Number" "PARTNUM*"
			(at -0.1016 4.023106 0)
			(unlocked yes)
			(layer "Cmts.User")
			(hide yes)
			(effects
				(font
					(size 0.7874 0.5842)
					(thickness 0.1524)
				)
				(justify mirror)
			)
		)
		(property "Device Type" "CAPACITOR-G105-0B104-CK,0.1UF,A"
			(at -0.0508 1.127506 0)
			(unlocked yes)
			(layer "B.Fab")
			(hide yes)
			(effects
				(font
					(size 0.7874 0.5842)
					(thickness 0.1524)
				)
				(justify mirror)
			)
		)
		(duplicate_pad_numbers_are_jumpers no)
		(fp_line
			(start -1.143 -0.5588)
			(end 1.143 -0.5588)
			(stroke
				(width 0.1)
				(type default)
			)
			(layer "B.SilkS")
		)
		(fp_line
			(start -1.143 0.5588)
			(end -1.143 -0.5588)
			(stroke
				(width 0.1)
				(type default)
			)
			(layer "B.SilkS")
		)
		(fp_line
			(start 1.143 -0.5588)
			(end 1.143 0.5588)
			(stroke
				(width 0.1)
				(type default)
			)
			(layer "B.SilkS")
		)
		(fp_line
			(start 1.143 0.5588)
			(end -1.143 0.5588)
			(stroke
				(width 0.1)
				(type default)
			)
			(layer "B.SilkS")
		)
		(fp_rect
			(start -1.143 -0.5588)
			(end 1.143 0.5588)
			(stroke
				(width 0)
				(type default)
			)
			(fill no)
			(layer "B.CrtYd")
		)
		(fp_line
			(start -0.508 -0.3048)
			(end 0.508 -0.3048)
			(stroke
				(width 0.1)
				(type default)
			)
			(layer "B.Fab")
		)
		(fp_line
			(start -0.508 0.3048)
			(end -0.508 -0.3048)
			(stroke
				(width 0.1)
				(type default)
			)
			(layer "B.Fab")
		)
		(fp_line
			(start 0.508 -0.3048)
			(end 0.508 0.3048)
			(stroke
				(width 0.1)
				(type default)
			)
			(layer "B.Fab")
		)
		(fp_line
			(start 0.508 0.3048)
			(end -0.508 0.3048)
			(stroke
				(width 0.1)
				(type default)
			)
			(layer "B.Fab")
		)
		(pad "1" smd rect
			(at 0.5334 0 180)
			(size 0.7112 0.6096)
			(layers "B.Cu" "B.Mask" "B.Paste")
			(net "XP3R3V_GPS")
		)
		(pad "2" smd rect
			(at -0.5334 0 180)
			(size 0.7112 0.6096)
			(layers "B.Cu" "B.Mask" "B.Paste")
			(net "SG")
		)
		(zone
			(layer "B.Cu")
			(hatch none 0.5)
			(connect_pads
				(clearance 0)
			)
			(min_thickness 0.25)
			(keepout
				(tracks allowed)
				(vias not_allowed)
				(pads allowed)
				(copperpour not_allowed)
				(footprints allowed)
			)
			(placement
				(enabled no)
				(sheetname "")
			)
			(fill
				(thermal_gap 0.5)
				(thermal_bridge_width 0.5)
				(island_removal_mode 0)
			)
			(polygon
				(pts
					(xy 117.6528 -100.3808) (xy 117.6528 -99.7712) (xy 117.8052 -99.7712) (xy 117.8052 -100.3808)
				)
			)
		)
	)
	(footprint ""
		(layer "B.Cu")
		(at 21.0566 -41.6306)
		(property "Reference" "R147"
			(at -0.3556 4.83997 0)
			(unlocked yes)
			(layer "B.SilkS")
			(effects
				(font
					(size 0.7874 0.5842)
					(thickness 0.1524)
				)
				(justify mirror)
			)
		)
		(property "Value" "VAL*"
			(at -0.02032 2.13233 0)
			(unlocked yes)
			(layer "B.Fab")
			(hide yes)
			(effects
				(font
					(size 0.7874 0.5842)
					(thickness 0.1524)
				)
				(justify mirror)
			)
		)
		(property "Device Type" "RESISTOR-G155-11002-01,10KOHM,A"
			(at -0.008382 1.210564 0)
			(unlocked yes)
			(layer "B.Fab")
			(hide yes)
			(effects
				(font
					(size 0.7874 0.5842)
					(thickness 0.1524)
				)
				(justify mirror)
			)
		)
		(property "User Part Number" "PARTNUM*"
			(at -0.02032 4.024884 0)
			(unlocked yes)
			(layer "Cmts.User")
			(hide yes)
			(effects
				(font
					(size 0.7874 0.5842)
					(thickness 0.1524)
				)
				(justify mirror)
			)
		)
		(property "Tolerance" "TOL*"
			(at -0.044704 3.05435 0)
			(unlocked yes)
			(layer "Cmts.User")
			(hide yes)
			(effects
				(font
					(size 0.7874 0.5842)
					(thickness 0.1524)
				)
				(justify mirror)
			)
		)
		(duplicate_pad_numbers_are_jumpers no)
		(fp_line
			(start -1.143 -0.5588)
			(end 1.143 -0.5588)
			(stroke
				(width 0.1)
				(type default)
			)
			(layer "B.SilkS")
		)
		(fp_line
			(start -1.143 0.5588)
			(end -1.143 -0.5588)
			(stroke
				(width 0.1)
				(type default)
			)
			(layer "B.SilkS")
		)
		(fp_line
			(start 1.143 -0.5588)
			(end 1.143 0.5588)
			(stroke
				(width 0.1)
				(type default)
			)
			(layer "B.SilkS")
		)
		(fp_line
			(start 1.143 0.5588)
			(end -1.143 0.5588)
			(stroke
				(width 0.1)
				(type default)
			)
			(layer "B.SilkS")
		)
		(fp_rect
			(start 1.143 0.5588)
			(end -1.143 -0.5588)
			(stroke
				(width 0)
				(type default)
			)
			(fill no)
			(layer "B.CrtYd")
		)
		(fp_line
			(start -0.508 -0.3048)
			(end 0.508 -0.3048)
			(stroke
				(width 0.1)
				(type default)
			)
			(layer "B.Fab")
		)
		(fp_line
			(start -0.508 0.3048)
			(end -0.508 -0.3048)
			(stroke
				(width 0.1)
				(type default)
			)
			(layer "B.Fab")
		)
		(fp_line
			(start 0.508 -0.3048)
			(end 0.508 0.3048)
			(stroke
				(width 0.1)
				(type default)
			)
			(layer "B.Fab")
		)
		(fp_line
			(start 0.508 0.3048)
			(end -0.508 0.3048)
			(stroke
				(width 0.1)
				(type default)
			)
			(layer "B.Fab")
		)
		(pad "1" smd rect
			(at 0.5334 0 180)
			(size 0.7112 0.6096)
			(layers "B.Cu" "B.Mask" "B.Paste")
			(net "XP3R3V_FPGA")
		)
		(pad "2" smd rect
			(at -0.5334 0 180)
			(size 0.7112 0.6096)
			(layers "B.Cu" "B.Mask" "B.Paste")
			(net "R_PCA9546_I2C_SDA")
		)
		(zone
			(layer "B.Cu")
			(hatch none 0.5)
			(connect_pads
				(clearance 0)
			)
			(min_thickness 0.25)
			(keepout
				(tracks allowed)
				(vias not_allowed)
				(pads allowed)
				(copperpour not_allowed)
				(footprints allowed)
			)
			(placement
				(enabled no)
				(sheetname "")
			)
			(fill
				(thermal_gap 0.5)
				(thermal_bridge_width 0.5)
				(island_removal_mode 0)
			)
			(polygon
				(pts
					(xy 21.1328 -41.3258) (xy 21.1328 -41.9354) (xy 20.9804 -41.9354) (xy 20.9804 -41.3258)
				)
			)
		)
	)
	(footprint ""
		(layer "B.Cu")
		(at 96.139 -33.909 90)
		(property "Reference" "C125"
			(at -2.19837 -0.889 0)
			(unlocked yes)
			(layer "B.SilkS")
			(effects
				(font
					(size 0.7874 0.5842)
					(thickness 0.1524)
				)
				(justify mirror)
			)
		)
		(property "Value" "VAL*"
			(at -0.0762 3.134106 90)
			(unlocked yes)
			(layer "B.Fab")
			(hide yes)
			(effects
				(font
					(size 0.7874 0.5842)
					(thickness 0.1524)
				)
				(justify mirror)
			)
		)
		(property "Tolerance" "TOL*"
			(at -0.0762 4.048506 90)
			(unlocked yes)
			(layer "Cmts.User")
			(hide yes)
			(effects
				(font
					(size 0.7874 0.5842)
					(thickness 0.1524)
				)
				(justify mirror)
			)
		)
		(property "User Part Number" "PARTNUM*"
			(at -0.1016 5.013706 90)
			(unlocked yes)
			(layer "Cmts.User")
			(hide yes)
			(effects
				(font
					(size 0.7874 0.5842)
					(thickness 0.1524)
				)
				(justify mirror)
			)
		)
		(property "Device Type" "CAPACITOR-G107-0F476-AM,47UF,2A"
			(at -0.0508 2.194306 90)
			(unlocked yes)
			(layer "B.Fab")
			(hide yes)
			(effects
				(font
					(size 0.7874 0.5842)
					(thickness 0.1524)
				)
				(justify mirror)
			)
		)
		(duplicate_pad_numbers_are_jumpers no)
		(fp_line
			(start 1.5748 -0.9398)
			(end 1.5748 0.9398)
			(stroke
				(width 0.1)
				(type default)
			)
			(layer "B.SilkS")
		)
		(fp_line
			(start -1.5748 -0.9398)
			(end 1.5748 -0.9398)
			(stroke
				(width 0.1)
				(type default)
			)
			(layer "B.SilkS")
		)
		(fp_line
			(start 1.5748 0.9398)
			(end -1.5748 0.9398)
			(stroke
				(width 0.1)
				(type default)
			)
			(layer "B.SilkS")
		)
		(fp_line
			(start -1.5748 0.9398)
			(end -1.5748 -0.9398)
			(stroke
				(width 0.1)
				(type default)
			)
			(layer "B.SilkS")
		)
		(fp_rect
			(start -1.5748 -0.9398)
			(end 1.5748 0.9398)
			(stroke
				(width 0)
				(type default)
			)
			(fill no)
			(layer "B.CrtYd")
		)
		(fp_line
			(start 1.016 -0.635)
			(end 1.016 0.635)
			(stroke
				(width 0.1)
				(type default)
			)
			(layer "B.Fab")
		)
		(fp_line
			(start -1.016 -0.635)
			(end 1.016 -0.635)
			(stroke
				(width 0.1)
				(type default)
			)
			(layer "B.Fab")
		)
		(fp_line
			(start 1.016 0.635)
			(end -1.016 0.635)
			(stroke
				(width 0.1)
				(type default)
			)
			(layer "B.Fab")
		)
		(fp_line
			(start -1.016 0.635)
			(end -1.016 -0.635)
			(stroke
				(width 0.1)
				(type default)
			)
			(layer "B.Fab")
		)
		(pad "1" smd rect
			(at 0.8382 0 270)
			(size 0.9652 1.3716)
			(layers "B.Cu" "B.Mask" "B.Paste")
			(net "FPGA_MGTAVTT")
		)
		(pad "2" smd rect
			(at -0.8382 0 270)
			(size 0.9652 1.3716)
			(layers "B.Cu" "B.Mask" "B.Paste")
			(net "SG")
		)
		(zone
			(layer "B.Cu")
			(hatch none 0.5)
			(connect_pads
				(clearance 0)
			)
			(min_thickness 0.25)
			(keepout
				(tracks allowed)
				(vias not_allowed)
				(pads allowed)
				(copperpour not_allowed)
				(footprints allowed)
			)
			(placement
				(enabled no)
				(sheetname "")
			)
			(fill
				(thermal_gap 0.5)
				(thermal_bridge_width 0.5)
				(island_removal_mode 0)
			)
			(polygon
				(pts
					(xy 95.504 -33.6804) (xy 96.774 -33.6804) (xy 96.774 -34.1376) (xy 95.504 -34.1376)
				)
			)
		)
	)
	(footprint ""
		(layer "B.Cu")
		(at 41.402 -89.535 90)
		(property "Reference" "C88"
			(at -2.413 -0.03937 270)
			(unlocked yes)
			(layer "B.SilkS")
			(effects
				(font
					(size 0.7874 0.5842)
					(thickness 0.1524)
				)
				(justify mirror)
			)
		)
		(property "Value" "VAL*"
			(at -0.0762 2.067306 90)
			(unlocked yes)
			(layer "B.Fab")
			(hide yes)
			(effects
				(font
					(size 0.7874 0.5842)
					(thickness 0.1524)
				)
				(justify mirror)
			)
		)
		(property "Device Type" "CAPACITOR-G105-0B104-EK,0.1UF,A"
			(at -0.0508 1.127506 90)
			(unlocked yes)
			(layer "B.Fab")
			(hide yes)
			(effects
				(font
					(size 0.7874 0.5842)
					(thickness 0.1524)
				)
				(justify mirror)
			)
		)
		(property "User Part Number" "PARTNUM*"
			(at -0.1016 4.023106 90)
			(unlocked yes)
			(layer "Cmts.User")
			(hide yes)
			(effects
				(font
					(size 0.7874 0.5842)
					(thickness 0.1524)
				)
				(justify mirror)
			)
		)
		(property "Tolerance" "TOL*"
			(at -0.0762 3.032506 90)
			(unlocked yes)
			(layer "Cmts.User")
			(hide yes)
			(effects
				(font
					(size 0.7874 0.5842)
					(thickness 0.1524)
				)
				(justify mirror)
			)
		)
		(duplicate_pad_numbers_are_jumpers no)
		(fp_line
			(start 1.143 -0.5588)
			(end 1.143 0.5588)
			(stroke
				(width 0.1)
				(type default)
			)
			(layer "B.SilkS")
		)
		(fp_line
			(start -1.143 -0.5588)
			(end 1.143 -0.5588)
			(stroke
				(width 0.1)
				(type default)
			)
			(layer "B.SilkS")
		)
		(fp_line
			(start 1.143 0.5588)
			(end -1.143 0.5588)
			(stroke
				(width 0.1)
				(type default)
			)
			(layer "B.SilkS")
		)
		(fp_line
			(start -1.143 0.5588)
			(end -1.143 -0.5588)
			(stroke
				(width 0.1)
				(type default)
			)
			(layer "B.SilkS")
		)
		(fp_rect
			(start 1.143 -0.5588)
			(end -1.143 0.5588)
			(stroke
				(width 0)
				(type default)
			)
			(fill no)
			(layer "B.CrtYd")
		)
		(fp_line
			(start 0.508 -0.3048)
			(end 0.508 0.3048)
			(stroke
				(width 0.1)
				(type default)
			)
			(layer "B.Fab")
		)
		(fp_line
			(start -0.508 -0.3048)
			(end 0.508 -0.3048)
			(stroke
				(width 0.1)
				(type default)
			)
			(layer "B.Fab")
		)
		(fp_line
			(start 0.508 0.3048)
			(end -0.508 0.3048)
			(stroke
				(width 0.1)
				(type default)
			)
			(layer "B.Fab")
		)
		(fp_line
			(start -0.508 0.3048)
			(end -0.508 -0.3048)
			(stroke
				(width 0.1)
				(type default)
			)
			(layer "B.Fab")
		)
		(pad "1" smd rect
			(at 0.5334 0 270)
			(size 0.7112 0.6096)
			(layers "B.Cu" "B.Mask" "B.Paste")
			(net "XP3R3V_FT4232")
		)
		(pad "2" smd rect
			(at -0.5334 0 270)
			(size 0.7112 0.6096)
			(layers "B.Cu" "B.Mask" "B.Paste")
			(net "SG")
		)
		(zone
			(layer "B.Cu")
			(hatch none 0.5)
			(connect_pads
				(clearance 0)
			)
			(min_thickness 0.25)
			(keepout
				(tracks allowed)
				(vias not_allowed)
				(pads allowed)
				(copperpour not_allowed)
				(footprints allowed)
			)
			(placement
				(enabled no)
				(sheetname "")
			)
			(fill
				(thermal_gap 0.5)
				(thermal_bridge_width 0.5)
				(island_removal_mode 0)
			)
			(polygon
				(pts
					(xy 41.0972 -89.6112) (xy 41.0972 -89.4588) (xy 41.7068 -89.4588) (xy 41.7068 -89.6112)
				)
			)
		)
	)
	(footprint ""
		(layer "B.Cu")
		(at 83.2358 -84.836 180)
		(property "Reference" "R150"
			(at 0.6858 5.67563 0)
			(unlocked yes)
			(layer "B.SilkS")
			(effects
				(font
					(size 0.7874 0.5842)
					(thickness 0.1524)
				)
				(justify mirror)
			)
		)
		(property "Value" "VAL*"
			(at -0.02032 2.13233 180)
			(unlocked yes)
			(layer "B.Fab")
			(hide yes)
			(effects
				(font
					(size 0.7874 0.5842)
					(thickness 0.1524)
				)
				(justify mirror)
			)
		)
		(property "Tolerance" "TOL*"
			(at -0.044704 3.05435 180)
			(unlocked yes)
			(layer "Cmts.User")
			(hide yes)
			(effects
				(font
					(size 0.7874 0.5842)
					(thickness 0.1524)
				)
				(justify mirror)
			)
		)
		(property "User Part Number" "PARTNUM*"
			(at -0.02032 4.024884 180)
			(unlocked yes)
			(layer "Cmts.User")
			(hide yes)
			(effects
				(font
					(size 0.7874 0.5842)
					(thickness 0.1524)
				)
				(justify mirror)
			)
		)
		(property "Device Type" "RESISTOR-G155-14701-01,4.7KOHMA"
			(at -0.008382 1.210564 180)
			(unlocked yes)
			(layer "B.Fab")
			(hide yes)
			(effects
				(font
					(size 0.7874 0.5842)
					(thickness 0.1524)
				)
				(justify mirror)
			)
		)
		(duplicate_pad_numbers_are_jumpers no)
		(fp_line
			(start 1.143 0.5588)
			(end -1.143 0.5588)
			(stroke
				(width 0.1)
				(type default)
			)
			(layer "B.SilkS")
		)
		(fp_line
			(start 1.143 -0.5588)
			(end 1.143 0.5588)
			(stroke
				(width 0.1)
				(type default)
			)
			(layer "B.SilkS")
		)
		(fp_line
			(start -1.143 0.5588)
			(end -1.143 -0.5588)
			(stroke
				(width 0.1)
				(type default)
			)
			(layer "B.SilkS")
		)
		(fp_line
			(start -1.143 -0.5588)
			(end 1.143 -0.5588)
			(stroke
				(width 0.1)
				(type default)
			)
			(layer "B.SilkS")
		)
		(fp_rect
			(start -1.143 0.5588)
			(end 1.143 -0.5588)
			(stroke
				(width 0)
				(type default)
			)
			(fill no)
			(layer "B.CrtYd")
		)
		(fp_line
			(start 0.508 0.3048)
			(end -0.508 0.3048)
			(stroke
				(width 0.1)
				(type default)
			)
			(layer "B.Fab")
		)
		(fp_line
			(start 0.508 -0.3048)
			(end 0.508 0.3048)
			(stroke
				(width 0.1)
				(type default)
			)
			(layer "B.Fab")
		)
		(fp_line
			(start -0.508 0.3048)
			(end -0.508 -0.3048)
			(stroke
				(width 0.1)
				(type default)
			)
			(layer "B.Fab")
		)
		(fp_line
			(start -0.508 -0.3048)
			(end 0.508 -0.3048)
			(stroke
				(width 0.1)
				(type default)
			)
			(layer "B.Fab")
		)
		(pad "1" smd rect
			(at 0.5334 0)
			(size 0.7112 0.6096)
			(layers "B.Cu" "B.Mask" "B.Paste")
			(net "XP3R3V_FPGA")
		)
		(pad "2" smd rect
			(at -0.5334 0)
			(size 0.7112 0.6096)
			(layers "B.Cu" "B.Mask" "B.Paste")
			(net "UNNAMED_5_PCA9546APWTSSOP16_I_1")
		)
		(zone
			(layer "B.Cu")
			(hatch none 0.5)
			(connect_pads
				(clearance 0)
			)
			(min_thickness 0.25)
			(keepout
				(tracks allowed)
				(vias not_allowed)
				(pads allowed)
				(copperpour not_allowed)
				(footprints allowed)
			)
			(placement
				(enabled no)
				(sheetname "")
			)
			(fill
				(thermal_gap 0.5)
				(thermal_bridge_width 0.5)
				(island_removal_mode 0)
			)
			(polygon
				(pts
					(xy 83.312 -85.1408) (xy 83.1596 -85.1408) (xy 83.1596 -84.5312) (xy 83.312 -84.5312)
				)
			)
		)
	)
	(footprint ""
		(layer "B.Cu")
		(at 108.966 -18.542 180)
		(property "Reference" "C244"
			(at 0 -1.30937 0)
			(unlocked yes)
			(layer "B.SilkS")
			(effects
				(font
					(size 0.7874 0.5842)
					(thickness 0.1524)
				)
				(justify mirror)
			)
		)
		(property "Value" "VAL*"
			(at -0.0762 2.067306 180)
			(unlocked yes)
			(layer "B.Fab")
			(hide yes)
			(effects
				(font
					(size 0.7874 0.5842)
					(thickness 0.1524)
				)
				(justify mirror)
			)
		)
		(property "Device Type" "CAPACITOR-G105-0B104-EK,0.1UF,A"
			(at -0.0508 1.127506 180)
			(unlocked yes)
			(layer "B.Fab")
			(hide yes)
			(effects
				(font
					(size 0.7874 0.5842)
					(thickness 0.1524)
				)
				(justify mirror)
			)
		)
		(property "User Part Number" "PARTNUM*"
			(at -0.1016 4.023106 180)
			(unlocked yes)
			(layer "Cmts.User")
			(hide yes)
			(effects
				(font
					(size 0.7874 0.5842)
					(thickness 0.1524)
				)
				(justify mirror)
			)
		)
		(property "Tolerance" "TOL*"
			(at -0.0762 3.032506 180)
			(unlocked yes)
			(layer "Cmts.User")
			(hide yes)
			(effects
				(font
					(size 0.7874 0.5842)
					(thickness 0.1524)
				)
				(justify mirror)
			)
		)
		(duplicate_pad_numbers_are_jumpers no)
		(fp_line
			(start 1.143 0.5588)
			(end -1.143 0.5588)
			(stroke
				(width 0.1)
				(type default)
			)
			(layer "B.SilkS")
		)
		(fp_line
			(start 1.143 -0.5588)
			(end 1.143 0.5588)
			(stroke
				(width 0.1)
				(type default)
			)
			(layer "B.SilkS")
		)
		(fp_line
			(start -1.143 0.5588)
			(end -1.143 -0.5588)
			(stroke
				(width 0.1)
				(type default)
			)
			(layer "B.SilkS")
		)
		(fp_line
			(start -1.143 -0.5588)
			(end 1.143 -0.5588)
			(stroke
				(width 0.1)
				(type default)
			)
			(layer "B.SilkS")
		)
		(fp_rect
			(start 1.143 -0.5588)
			(end -1.143 0.5588)
			(stroke
				(width 0)
				(type default)
			)
			(fill no)
			(layer "B.CrtYd")
		)
		(fp_line
			(start 0.508 0.3048)
			(end -0.508 0.3048)
			(stroke
				(width 0.1)
				(type default)
			)
			(layer "B.Fab")
		)
		(fp_line
			(start 0.508 -0.3048)
			(end 0.508 0.3048)
			(stroke
				(width 0.1)
				(type default)
			)
			(layer "B.Fab")
		)
		(fp_line
			(start -0.508 0.3048)
			(end -0.508 -0.3048)
			(stroke
				(width 0.1)
				(type default)
			)
			(layer "B.Fab")
		)
		(fp_line
			(start -0.508 -0.3048)
			(end 0.508 -0.3048)
			(stroke
				(width 0.1)
				(type default)
			)
			(layer "B.Fab")
		)
		(pad "1" smd rect
			(at 0.5334 0)
			(size 0.7112 0.6096)
			(layers "B.Cu" "B.Mask" "B.Paste")
			(net "XP3R3V")
		)
		(pad "2" smd rect
			(at -0.5334 0)
			(size 0.7112 0.6096)
			(layers "B.Cu" "B.Mask" "B.Paste")
			(net "SG")
		)
		(zone
			(layer "B.Cu")
			(hatch none 0.5)
			(connect_pads
				(clearance 0)
			)
			(min_thickness 0.25)
			(keepout
				(tracks allowed)
				(vias not_allowed)
				(pads allowed)
				(copperpour not_allowed)
				(footprints allowed)
			)
			(placement
				(enabled no)
				(sheetname "")
			)
			(fill
				(thermal_gap 0.5)
				(thermal_bridge_width 0.5)
				(island_removal_mode 0)
			)
			(polygon
				(pts
					(xy 108.8898 -18.2372) (xy 109.0422 -18.2372) (xy 109.0422 -18.8468) (xy 108.8898 -18.8468)
				)
			)
		)
	)
	(footprint ""
		(layer "B.Cu")
		(at 67.514978 -15.367 -90)
		(property "Reference" "C26"
			(at 3.048 0.236728 270)
			(unlocked yes)
			(layer "B.SilkS")
			(effects
				(font
					(size 0.635 0.4064)
					(thickness 0.1524)
				)
				(justify mirror)
			)
		)
		(property "Value" "VAL*"
			(at -0.0762 2.067306 270)
			(unlocked yes)
			(layer "B.Fab")
			(hide yes)
			(effects
				(font
					(size 0.7874 0.5842)
					(thickness 0.1524)
				)
				(justify mirror)
			)
		)
		(property "Tolerance" "TOL*"
			(at -0.0762 3.032506 270)
			(unlocked yes)
			(layer "Cmts.User")
			(hide yes)
			(effects
				(font
					(size 0.7874 0.5842)
					(thickness 0.1524)
				)
				(justify mirror)
			)
		)
		(property "User Part Number" "PARTNUM*"
			(at -0.1016 4.023106 270)
			(unlocked yes)
			(layer "Cmts.User")
			(hide yes)
			(effects
				(font
					(size 0.7874 0.5842)
					(thickness 0.1524)
				)
				(justify mirror)
			)
		)
		(property "Device Type" "CAPACITOR-G105-0B104-CK,0.1UF,A"
			(at -0.0508 1.127506 270)
			(unlocked yes)
			(layer "B.Fab")
			(hide yes)
			(effects
				(font
					(size 0.7874 0.5842)
					(thickness 0.1524)
				)
				(justify mirror)
			)
		)
		(duplicate_pad_numbers_are_jumpers no)
		(fp_line
			(start -1.143 0.5588)
			(end -1.143 -0.5588)
			(stroke
				(width 0.1)
				(type default)
			)
			(layer "B.SilkS")
		)
		(fp_line
			(start 1.143 0.5588)
			(end -1.143 0.5588)
			(stroke
				(width 0.1)
				(type default)
			)
			(layer "B.SilkS")
		)
		(fp_line
			(start -1.143 -0.5588)
			(end 1.143 -0.5588)
			(stroke
				(width 0.1)
				(type default)
			)
			(layer "B.SilkS")
		)
		(fp_line
			(start 1.143 -0.5588)
			(end 1.143 0.5588)
			(stroke
				(width 0.1)
				(type default)
			)
			(layer "B.SilkS")
		)
		(fp_rect
			(start 1.143 0.5588)
			(end -1.143 -0.5588)
			(stroke
				(width 0)
				(type default)
			)
			(fill no)
			(layer "B.CrtYd")
		)
		(fp_line
			(start -0.508 0.3048)
			(end -0.508 -0.3048)
			(stroke
				(width 0.1)
				(type default)
			)
			(layer "B.Fab")
		)
		(fp_line
			(start 0.508 0.3048)
			(end -0.508 0.3048)
			(stroke
				(width 0.1)
				(type default)
			)
			(layer "B.Fab")
		)
		(fp_line
			(start -0.508 -0.3048)
			(end 0.508 -0.3048)
			(stroke
				(width 0.1)
				(type default)
			)
			(layer "B.Fab")
		)
		(fp_line
			(start 0.508 -0.3048)
			(end 0.508 0.3048)
			(stroke
				(width 0.1)
				(type default)
			)
			(layer "B.Fab")
		)
		(pad "1" smd rect
			(at 0.5334 0 90)
			(size 0.7112 0.6096)
			(layers "B.Cu" "B.Mask" "B.Paste")
			(net "C_CPU_RX_PCIE_MGT1_TXP")
		)
		(pad "2" smd rect
			(at -0.5334 0 90)
			(size 0.7112 0.6096)
			(layers "B.Cu" "B.Mask" "B.Paste")
			(net "CPU_RX_PCIE_MGT1_TXP")
		)
		(zone
			(layer "B.Cu")
			(hatch none 0.5)
			(connect_pads
				(clearance 0)
			)
			(min_thickness 0.25)
			(keepout
				(tracks allowed)
				(vias not_allowed)
				(pads allowed)
				(copperpour not_allowed)
				(footprints allowed)
			)
			(placement
				(enabled no)
				(sheetname "")
			)
			(fill
				(thermal_gap 0.5)
				(thermal_bridge_width 0.5)
				(island_removal_mode 0)
			)
			(polygon
				(pts
					(xy 67.210178 -15.2908) (xy 67.819778 -15.2908) (xy 67.819778 -15.4432) (xy 67.210178 -15.4432)
				)
			)
		)
	)
	(footprint ""
		(layer "B.Cu")
		(at 119.347234 -52.82311 180)
		(property "Reference" "R503"
			(at 2.253234 -0.02286 0)
			(unlocked yes)
			(layer "B.SilkS")
			(effects
				(font
					(size 0.635 0.4064)
					(thickness 0.1524)
				)
				(justify mirror)
			)
		)
		(property "Value" "VAL*"
			(at 0 3.718306 180)
			(unlocked yes)
			(layer "B.Fab")
			(hide yes)
			(effects
				(font
					(size 0.7874 0.5842)
					(thickness 0.127)
				)
				(justify mirror)
			)
		)
		(property "Tolerance" "TOL*"
			(at 0 4.861306 180)
			(unlocked yes)
			(layer "Cmts.User")
			(hide yes)
			(effects
				(font
					(size 0.7874 0.5842)
					(thickness 0.127)
				)
				(justify mirror)
			)
		)
		(property "User Part Number" "PARTNUM*"
			(at 0 2.575306 180)
			(unlocked yes)
			(layer "Cmts.User")
			(hide yes)
			(effects
				(font
					(size 0.7874 0.5842)
					(thickness 0.127)
				)
				(justify mirror)
			)
		)
		(property "Device Type" "RESISTOR-G155-14701-01,4.7KOHMA"
			(at 0 1.432306 180)
			(unlocked yes)
			(layer "B.Fab")
			(hide yes)
			(effects
				(font
					(size 0.7874 0.5842)
					(thickness 0.127)
				)
				(justify mirror)
			)
		)
		(duplicate_pad_numbers_are_jumpers no)
		(fp_line
			(start 0.970026 0.4699)
			(end 0.970026 -0.4699)
			(stroke
				(width 0.1)
				(type default)
			)
			(layer "B.SilkS")
		)
		(fp_line
			(start 0.970026 -0.4699)
			(end -0.970026 -0.4699)
			(stroke
				(width 0.1)
				(type default)
			)
			(layer "B.SilkS")
		)
		(fp_line
			(start -0.970026 0.4699)
			(end 0.970026 0.4699)
			(stroke
				(width 0.1)
				(type default)
			)
			(layer "B.SilkS")
		)
		(fp_line
			(start -0.970026 -0.4699)
			(end -0.970026 0.4699)
			(stroke
				(width 0.1)
				(type default)
			)
			(layer "B.SilkS")
		)
		(fp_poly
			(pts
				(xy 0.970026 0.4699) (xy -0.970026 0.4699) (xy -0.970026 -0.4699) (xy 0.970026 -0.4699)
			)
			(stroke
				(width 0)
				(type default)
			)
			(fill no)
			(layer "B.CrtYd")
		)
		(fp_line
			(start 0.508 0.3048)
			(end 0.508 -0.3048)
			(stroke
				(width 0.1)
				(type default)
			)
			(layer "B.Fab")
		)
		(fp_line
			(start 0.508 -0.3048)
			(end -0.508 -0.3048)
			(stroke
				(width 0.1)
				(type default)
			)
			(layer "B.Fab")
		)
		(fp_line
			(start -0.508 0.3048)
			(end 0.508 0.3048)
			(stroke
				(width 0.1)
				(type default)
			)
			(layer "B.Fab")
		)
		(fp_line
			(start -0.508 -0.3048)
			(end -0.508 0.3048)
			(stroke
				(width 0.1)
				(type default)
			)
			(layer "B.Fab")
		)
		(pad "1" smd circle
			(at 0.500126 0)
			(size 0.635 0.635)
			(layers "B.Cu" "B.Mask" "B.Paste")
			(net "ANT2_IN")
		)
		(pad "2" smd circle
			(at -0.500126 0)
			(size 0.635 0.635)
			(layers "B.Cu" "B.Mask" "B.Paste")
			(net "SG")
		)
	)
	(footprint ""
		(layer "B.Cu")
		(at 88.519 -73.279 90)
		(property "Reference" "R341"
			(at -3.556 -0.16637 270)
			(unlocked yes)
			(layer "B.SilkS")
			(effects
				(font
					(size 0.7874 0.5842)
					(thickness 0.1524)
				)
				(justify mirror)
			)
		)
		(property "Value" "VAL*"
			(at -0.02032 2.13233 90)
			(unlocked yes)
			(layer "B.Fab")
			(hide yes)
			(effects
				(font
					(size 0.7874 0.5842)
					(thickness 0.1524)
				)
				(justify mirror)
			)
		)
		(property "Device Type" "RESISTOR-G155-14701-01,4.7KOHMA"
			(at -0.008382 1.210564 90)
			(unlocked yes)
			(layer "B.Fab")
			(hide yes)
			(effects
				(font
					(size 0.7874 0.5842)
					(thickness 0.1524)
				)
				(justify mirror)
			)
		)
		(property "User Part Number" "PARTNUM*"
			(at -0.02032 4.024884 90)
			(unlocked yes)
			(layer "Cmts.User")
			(hide yes)
			(effects
				(font
					(size 0.7874 0.5842)
					(thickness 0.1524)
				)
				(justify mirror)
			)
		)
		(property "Tolerance" "TOL*"
			(at -0.044704 3.05435 90)
			(unlocked yes)
			(layer "Cmts.User")
			(hide yes)
			(effects
				(font
					(size 0.7874 0.5842)
					(thickness 0.1524)
				)
				(justify mirror)
			)
		)
		(duplicate_pad_numbers_are_jumpers no)
		(fp_line
			(start 1.143 -0.5588)
			(end 1.143 0.5588)
			(stroke
				(width 0.1)
				(type default)
			)
			(layer "B.SilkS")
		)
		(fp_line
			(start -1.143 -0.5588)
			(end 1.143 -0.5588)
			(stroke
				(width 0.1)
				(type default)
			)
			(layer "B.SilkS")
		)
		(fp_line
			(start 1.143 0.5588)
			(end -1.143 0.5588)
			(stroke
				(width 0.1)
				(type default)
			)
			(layer "B.SilkS")
		)
		(fp_line
			(start -1.143 0.5588)
			(end -1.143 -0.5588)
			(stroke
				(width 0.1)
				(type default)
			)
			(layer "B.SilkS")
		)
		(fp_rect
			(start 1.143 -0.5588)
			(end -1.143 0.5588)
			(stroke
				(width 0)
				(type default)
			)
			(fill no)
			(layer "B.CrtYd")
		)
		(fp_line
			(start 0.508 -0.3048)
			(end 0.508 0.3048)
			(stroke
				(width 0.1)
				(type default)
			)
			(layer "B.Fab")
		)
		(fp_line
			(start -0.508 -0.3048)
			(end 0.508 -0.3048)
			(stroke
				(width 0.1)
				(type default)
			)
			(layer "B.Fab")
		)
		(fp_line
			(start 0.508 0.3048)
			(end -0.508 0.3048)
			(stroke
				(width 0.1)
				(type default)
			)
			(layer "B.Fab")
		)
		(fp_line
			(start -0.508 0.3048)
			(end -0.508 -0.3048)
			(stroke
				(width 0.1)
				(type default)
			)
			(layer "B.Fab")
		)
		(pad "1" smd rect
			(at 0.5334 0 270)
			(size 0.7112 0.6096)
			(layers "B.Cu" "B.Mask" "B.Paste")
			(net "XP3R3V_FPGA")
		)
		(pad "2" smd rect
			(at -0.5334 0 270)
			(size 0.7112 0.6096)
			(layers "B.Cu" "B.Mask" "B.Paste")
			(net "BNO080_EVN_SDA")
		)
		(zone
			(layer "B.Cu")
			(hatch none 0.5)
			(connect_pads
				(clearance 0)
			)
			(min_thickness 0.25)
			(keepout
				(tracks allowed)
				(vias not_allowed)
				(pads allowed)
				(copperpour not_allowed)
				(footprints allowed)
			)
			(placement
				(enabled no)
				(sheetname "")
			)
			(fill
				(thermal_gap 0.5)
				(thermal_bridge_width 0.5)
				(island_removal_mode 0)
			)
			(polygon
				(pts
					(xy 88.2142 -73.3552) (xy 88.2142 -73.2028) (xy 88.8238 -73.2028) (xy 88.8238 -73.3552)
				)
			)
		)
	)
	(footprint ""
		(layer "B.Cu")
		(at 90.424 -104.902)
		(property "Reference" "R51"
			(at 0.127 -2.88163 0)
			(unlocked yes)
			(layer "B.SilkS")
			(effects
				(font
					(size 0.7874 0.5842)
					(thickness 0.1524)
				)
				(justify mirror)
			)
		)
		(property "Value" "VAL*"
			(at -0.02032 2.13233 0)
			(unlocked yes)
			(layer "B.Fab")
			(hide yes)
			(effects
				(font
					(size 0.7874 0.5842)
					(thickness 0.1524)
				)
				(justify mirror)
			)
		)
		(property "Tolerance" "TOL*"
			(at -0.044704 3.05435 0)
			(unlocked yes)
			(layer "Cmts.User")
			(hide yes)
			(effects
				(font
					(size 0.7874 0.5842)
					(thickness 0.1524)
				)
				(justify mirror)
			)
		)
		(property "User Part Number" "PARTNUM*"
			(at -0.02032 4.024884 0)
			(unlocked yes)
			(layer "Cmts.User")
			(hide yes)
			(effects
				(font
					(size 0.7874 0.5842)
					(thickness 0.1524)
				)
				(justify mirror)
			)
		)
		(property "Device Type" "RESISTOR-G155-11002-01,10KOHM,A"
			(at -0.008382 1.210564 0)
			(unlocked yes)
			(layer "B.Fab")
			(hide yes)
			(effects
				(font
					(size 0.7874 0.5842)
					(thickness 0.1524)
				)
				(justify mirror)
			)
		)
		(duplicate_pad_numbers_are_jumpers no)
		(fp_line
			(start -1.143 -0.5588)
			(end 1.143 -0.5588)
			(stroke
				(width 0.1)
				(type default)
			)
			(layer "B.SilkS")
		)
		(fp_line
			(start -1.143 0.5588)
			(end -1.143 -0.5588)
			(stroke
				(width 0.1)
				(type default)
			)
			(layer "B.SilkS")
		)
		(fp_line
			(start 1.143 -0.5588)
			(end 1.143 0.5588)
			(stroke
				(width 0.1)
				(type default)
			)
			(layer "B.SilkS")
		)
		(fp_line
			(start 1.143 0.5588)
			(end -1.143 0.5588)
			(stroke
				(width 0.1)
				(type default)
			)
			(layer "B.SilkS")
		)
		(fp_poly
			(pts
				(xy 1.143 0.5588) (xy -1.143 0.5588) (xy -1.143 -0.5588) (xy 1.143 -0.5588)
			)
			(stroke
				(width 0)
				(type default)
			)
			(fill no)
			(layer "B.CrtYd")
		)
		(fp_line
			(start -0.508 -0.3048)
			(end 0.508 -0.3048)
			(stroke
				(width 0.1)
				(type default)
			)
			(layer "B.Fab")
		)
		(fp_line
			(start -0.508 0.3048)
			(end -0.508 -0.3048)
			(stroke
				(width 0.1)
				(type default)
			)
			(layer "B.Fab")
		)
		(fp_line
			(start 0.508 -0.3048)
			(end 0.508 0.3048)
			(stroke
				(width 0.1)
				(type default)
			)
			(layer "B.Fab")
		)
		(fp_line
			(start 0.508 0.3048)
			(end -0.508 0.3048)
			(stroke
				(width 0.1)
				(type default)
			)
			(layer "B.Fab")
		)
		(pad "1" smd rect
			(at 0.5334 0 180)
			(size 0.7112 0.6096)
			(layers "B.Cu" "B.Mask" "B.Paste")
			(net "XP3R3V")
		)
		(pad "2" smd rect
			(at -0.5334 0 180)
			(size 0.7112 0.6096)
			(layers "B.Cu" "B.Mask" "B.Paste")
			(net "R_XP3R3V_PG")
		)
		(zone
			(layer "B.Cu")
			(hatch none 0.5)
			(connect_pads
				(clearance 0)
			)
			(min_thickness 0.25)
			(keepout
				(tracks allowed)
				(vias not_allowed)
				(pads allowed)
				(copperpour not_allowed)
				(footprints allowed)
			)
			(placement
				(enabled no)
				(sheetname "")
			)
			(fill
				(thermal_gap 0.5)
				(thermal_bridge_width 0.5)
				(island_removal_mode 0)
			)
			(polygon
				(pts
					(xy 90.5002 -104.5972) (xy 90.5002 -105.2068) (xy 90.3478 -105.2068) (xy 90.3478 -104.5972)
				)
			)
		)
		(zone
			(layer "B.Cu")
			(hatch none 0.5)
			(connect_pads
				(clearance 0)
			)
			(min_thickness 0.25)
			(keepout
				(tracks not_allowed)
				(vias allowed)
				(pads allowed)
				(copperpour not_allowed)
				(footprints allowed)
			)
			(placement
				(enabled no)
				(sheetname "")
			)
			(fill
				(thermal_gap 0.5)
				(thermal_bridge_width 0.5)
				(island_removal_mode 0)
			)
			(polygon
				(pts
					(xy 90.5002 -104.5972) (xy 90.5002 -105.2068) (xy 90.3478 -105.2068) (xy 90.3478 -104.5972)
				)
			)
		)
	)
	(footprint ""
		(layer "B.Cu")
		(at 110.847124 -37.323268 -90)
		(property "Reference" "C220"
			(at 1.382268 42.044874 270)
			(unlocked yes)
			(layer "B.SilkS")
			(effects
				(font
					(size 0.635 0.4064)
					(thickness 0.1524)
				)
				(justify mirror)
			)
		)
		(property "Value" "VAL*"
			(at 0 3.718306 270)
			(unlocked yes)
			(layer "B.Fab")
			(hide yes)
			(effects
				(font
					(size 0.7874 0.5842)
					(thickness 0.127)
				)
				(justify mirror)
			)
		)
		(property "Tolerance" "TOL*"
			(at 0 4.861306 270)
			(unlocked yes)
			(layer "Cmts.User")
			(hide yes)
			(effects
				(font
					(size 0.7874 0.5842)
					(thickness 0.127)
				)
				(justify mirror)
			)
		)
		(property "User Part Number" "PARTNUM*"
			(at 0 2.575306 270)
			(unlocked yes)
			(layer "Cmts.User")
			(hide yes)
			(effects
				(font
					(size 0.7874 0.5842)
					(thickness 0.127)
				)
				(justify mirror)
			)
		)
		(property "Device Type" "CAPACITOR-G105-0B104-CK,0.1UF,A"
			(at 0 1.432306 270)
			(unlocked yes)
			(layer "B.Fab")
			(hide yes)
			(effects
				(font
					(size 0.7874 0.5842)
					(thickness 0.127)
				)
				(justify mirror)
			)
		)
		(duplicate_pad_numbers_are_jumpers no)
		(fp_line
			(start -0.970026 0.4699)
			(end 0.970026 0.4699)
			(stroke
				(width 0.1)
				(type default)
			)
			(layer "B.SilkS")
		)
		(fp_line
			(start 0.970026 0.4699)
			(end 0.970026 -0.4699)
			(stroke
				(width 0.1)
				(type default)
			)
			(layer "B.SilkS")
		)
		(fp_line
			(start -0.970026 -0.4699)
			(end -0.970026 0.4699)
			(stroke
				(width 0.1)
				(type default)
			)
			(layer "B.SilkS")
		)
		(fp_line
			(start 0.970026 -0.4699)
			(end -0.970026 -0.4699)
			(stroke
				(width 0.1)
				(type default)
			)
			(layer "B.SilkS")
		)
		(fp_poly
			(pts
				(xy 0.970026 0.4699) (xy -0.970026 0.4699) (xy -0.970026 -0.4699) (xy 0.970026 -0.4699)
			)
			(stroke
				(width 0)
				(type default)
			)
			(fill no)
			(layer "B.CrtYd")
		)
		(fp_line
			(start -0.508 0.3048)
			(end 0.508 0.3048)
			(stroke
				(width 0.1)
				(type default)
			)
			(layer "B.Fab")
		)
		(fp_line
			(start 0.508 0.3048)
			(end 0.508 -0.3048)
			(stroke
				(width 0.1)
				(type default)
			)
			(layer "B.Fab")
		)
		(fp_line
			(start -0.508 -0.3048)
			(end -0.508 0.3048)
			(stroke
				(width 0.1)
				(type default)
			)
			(layer "B.Fab")
		)
		(fp_line
			(start 0.508 -0.3048)
			(end -0.508 -0.3048)
			(stroke
				(width 0.1)
				(type default)
			)
			(layer "B.Fab")
		)
		(pad "1" smd circle
			(at 0.500126 0 90)
			(size 0.635 0.635)
			(layers "B.Cu" "B.Mask" "B.Paste")
			(net "XP2R5V_FPGA")
		)
		(pad "2" smd circle
			(at -0.500126 0 90)
			(size 0.635 0.635)
			(layers "B.Cu" "B.Mask" "B.Paste")
			(net "SG")
		)
	)
	(footprint ""
		(layer "B.Cu")
		(at 95.631 -83.312)
		(property "Reference" "R200"
			(at -0.254 -5.54863 0)
			(unlocked yes)
			(layer "B.SilkS")
			(effects
				(font
					(size 0.7874 0.5842)
					(thickness 0.1524)
				)
				(justify mirror)
			)
		)
		(property "Value" "VAL*"
			(at -0.02032 2.13233 0)
			(unlocked yes)
			(layer "B.Fab")
			(hide yes)
			(effects
				(font
					(size 0.7874 0.5842)
					(thickness 0.1524)
				)
				(justify mirror)
			)
		)
		(property "Tolerance" "TOL*"
			(at -0.044704 3.05435 0)
			(unlocked yes)
			(layer "Cmts.User")
			(hide yes)
			(effects
				(font
					(size 0.7874 0.5842)
					(thickness 0.1524)
				)
				(justify mirror)
			)
		)
		(property "User Part Number" "PARTNUM*"
			(at -0.02032 4.024884 0)
			(unlocked yes)
			(layer "Cmts.User")
			(hide yes)
			(effects
				(font
					(size 0.7874 0.5842)
					(thickness 0.1524)
				)
				(justify mirror)
			)
		)
		(property "Device Type" "RESISTOR-G155-14701-01,4.7KOHMA"
			(at -0.008382 1.210564 0)
			(unlocked yes)
			(layer "B.Fab")
			(hide yes)
			(effects
				(font
					(size 0.7874 0.5842)
					(thickness 0.1524)
				)
				(justify mirror)
			)
		)
		(duplicate_pad_numbers_are_jumpers no)
		(fp_line
			(start -1.143 -0.5588)
			(end 1.143 -0.5588)
			(stroke
				(width 0.1)
				(type default)
			)
			(layer "B.SilkS")
		)
		(fp_line
			(start -1.143 0.5588)
			(end -1.143 -0.5588)
			(stroke
				(width 0.1)
				(type default)
			)
			(layer "B.SilkS")
		)
		(fp_line
			(start 1.143 -0.5588)
			(end 1.143 0.5588)
			(stroke
				(width 0.1)
				(type default)
			)
			(layer "B.SilkS")
		)
		(fp_line
			(start 1.143 0.5588)
			(end -1.143 0.5588)
			(stroke
				(width 0.1)
				(type default)
			)
			(layer "B.SilkS")
		)
		(fp_rect
			(start -1.143 0.5588)
			(end 1.143 -0.5588)
			(stroke
				(width 0)
				(type default)
			)
			(fill no)
			(layer "B.CrtYd")
		)
		(fp_line
			(start -0.508 -0.3048)
			(end 0.508 -0.3048)
			(stroke
				(width 0.1)
				(type default)
			)
			(layer "B.Fab")
		)
		(fp_line
			(start -0.508 0.3048)
			(end -0.508 -0.3048)
			(stroke
				(width 0.1)
				(type default)
			)
			(layer "B.Fab")
		)
		(fp_line
			(start 0.508 -0.3048)
			(end 0.508 0.3048)
			(stroke
				(width 0.1)
				(type default)
			)
			(layer "B.Fab")
		)
		(fp_line
			(start 0.508 0.3048)
			(end -0.508 0.3048)
			(stroke
				(width 0.1)
				(type default)
			)
			(layer "B.Fab")
		)
		(pad "1" smd rect
			(at 0.5334 0 180)
			(size 0.7112 0.6096)
			(layers "B.Cu" "B.Mask" "B.Paste")
			(net "UNNAMED_127_MT25QL128ABA1ESES_1")
		)
		(pad "2" smd rect
			(at -0.5334 0 180)
			(size 0.7112 0.6096)
			(layers "B.Cu" "B.Mask" "B.Paste")
			(net "XP3R3V_FPGA")
		)
		(zone
			(layer "B.Cu")
			(hatch none 0.5)
			(connect_pads
				(clearance 0)
			)
			(min_thickness 0.25)
			(keepout
				(tracks allowed)
				(vias not_allowed)
				(pads allowed)
				(copperpour not_allowed)
				(footprints allowed)
			)
			(placement
				(enabled no)
				(sheetname "")
			)
			(fill
				(thermal_gap 0.5)
				(thermal_bridge_width 0.5)
				(island_removal_mode 0)
			)
			(polygon
				(pts
					(xy 95.5548 -83.0072) (xy 95.7072 -83.0072) (xy 95.7072 -83.6168) (xy 95.5548 -83.6168)
				)
			)
		)
	)
	(footprint ""
		(layer "B.Cu")
		(at 33.782 -19.1262 180)
		(property "Reference" "R158"
			(at -3.175 -0.62357 0)
			(unlocked yes)
			(layer "B.SilkS")
			(effects
				(font
					(size 0.7874 0.5842)
					(thickness 0.1524)
				)
				(justify mirror)
			)
		)
		(property "Value" "VAL*"
			(at -0.02032 2.13233 180)
			(unlocked yes)
			(layer "B.Fab")
			(hide yes)
			(effects
				(font
					(size 0.7874 0.5842)
					(thickness 0.1524)
				)
				(justify mirror)
			)
		)
		(property "Device Type" "RESISTOR-G155-14701-01,4.7KOHMA"
			(at -0.008382 1.210564 180)
			(unlocked yes)
			(layer "B.Fab")
			(hide yes)
			(effects
				(font
					(size 0.7874 0.5842)
					(thickness 0.1524)
				)
				(justify mirror)
			)
		)
		(property "User Part Number" "PARTNUM*"
			(at -0.02032 4.024884 180)
			(unlocked yes)
			(layer "Cmts.User")
			(hide yes)
			(effects
				(font
					(size 0.7874 0.5842)
					(thickness 0.1524)
				)
				(justify mirror)
			)
		)
		(property "Tolerance" "TOL*"
			(at -0.044704 3.05435 180)
			(unlocked yes)
			(layer "Cmts.User")
			(hide yes)
			(effects
				(font
					(size 0.7874 0.5842)
					(thickness 0.1524)
				)
				(justify mirror)
			)
		)
		(duplicate_pad_numbers_are_jumpers no)
		(fp_line
			(start 1.143 0.5588)
			(end -1.143 0.5588)
			(stroke
				(width 0.1)
				(type default)
			)
			(layer "B.SilkS")
		)
		(fp_line
			(start 1.143 -0.5588)
			(end 1.143 0.5588)
			(stroke
				(width 0.1)
				(type default)
			)
			(layer "B.SilkS")
		)
		(fp_line
			(start -1.143 0.5588)
			(end -1.143 -0.5588)
			(stroke
				(width 0.1)
				(type default)
			)
			(layer "B.SilkS")
		)
		(fp_line
			(start -1.143 -0.5588)
			(end 1.143 -0.5588)
			(stroke
				(width 0.1)
				(type default)
			)
			(layer "B.SilkS")
		)
		(fp_rect
			(start 1.143 -0.5588)
			(end -1.143 0.5588)
			(stroke
				(width 0)
				(type default)
			)
			(fill no)
			(layer "B.CrtYd")
		)
		(fp_line
			(start 0.508 0.3048)
			(end -0.508 0.3048)
			(stroke
				(width 0.1)
				(type default)
			)
			(layer "B.Fab")
		)
		(fp_line
			(start 0.508 -0.3048)
			(end 0.508 0.3048)
			(stroke
				(width 0.1)
				(type default)
			)
			(layer "B.Fab")
		)
		(fp_line
			(start -0.508 0.3048)
			(end -0.508 -0.3048)
			(stroke
				(width 0.1)
				(type default)
			)
			(layer "B.Fab")
		)
		(fp_line
			(start -0.508 -0.3048)
			(end 0.508 -0.3048)
			(stroke
				(width 0.1)
				(type default)
			)
			(layer "B.Fab")
		)
		(pad "1" smd rect
			(at 0.5334 0)
			(size 0.7112 0.6096)
			(layers "B.Cu" "B.Mask" "B.Paste")
			(net "XP3R3V_FPGA")
		)
		(pad "2" smd rect
			(at -0.5334 0)
			(size 0.7112 0.6096)
			(layers "B.Cu" "B.Mask" "B.Paste")
			(net "UNNAMED_5_24LC16BTISTTSSOP8_I15")
		)
		(zone
			(layer "B.Cu")
			(hatch none 0.5)
			(connect_pads
				(clearance 0)
			)
			(min_thickness 0.25)
			(keepout
				(tracks allowed)
				(vias not_allowed)
				(pads allowed)
				(copperpour not_allowed)
				(footprints allowed)
			)
			(placement
				(enabled no)
				(sheetname "")
			)
			(fill
				(thermal_gap 0.5)
				(thermal_bridge_width 0.5)
				(island_removal_mode 0)
			)
			(polygon
				(pts
					(xy 33.7058 -18.8214) (xy 33.8582 -18.8214) (xy 33.8582 -19.431) (xy 33.7058 -19.431)
				)
			)
		)
	)
	(footprint ""
		(layer "B.Cu")
		(at 64.262 -60.325 180)
		(property "Reference" "R107"
			(at 2.159 1.10363 0)
			(unlocked yes)
			(layer "B.SilkS")
			(effects
				(font
					(size 0.7874 0.5842)
					(thickness 0.1524)
				)
				(justify mirror)
			)
		)
		(property "Value" "VAL*"
			(at -0.02032 2.13233 180)
			(unlocked yes)
			(layer "B.Fab")
			(hide yes)
			(effects
				(font
					(size 0.7874 0.5842)
					(thickness 0.1524)
				)
				(justify mirror)
			)
		)
		(property "Tolerance" "TOL*"
			(at -0.044704 3.05435 180)
			(unlocked yes)
			(layer "Cmts.User")
			(hide yes)
			(effects
				(font
					(size 0.7874 0.5842)
					(thickness 0.1524)
				)
				(justify mirror)
			)
		)
		(property "User Part Number" "PARTNUM*"
			(at -0.02032 4.024884 180)
			(unlocked yes)
			(layer "Cmts.User")
			(hide yes)
			(effects
				(font
					(size 0.7874 0.5842)
					(thickness 0.1524)
				)
				(justify mirror)
			)
		)
		(property "Device Type" "RESISTOR-G155-14701-01,4.7KOHMA"
			(at -0.008382 1.210564 180)
			(unlocked yes)
			(layer "B.Fab")
			(hide yes)
			(effects
				(font
					(size 0.7874 0.5842)
					(thickness 0.1524)
				)
				(justify mirror)
			)
		)
		(duplicate_pad_numbers_are_jumpers no)
		(fp_line
			(start 1.143 0.5588)
			(end -1.143 0.5588)
			(stroke
				(width 0.1)
				(type default)
			)
			(layer "B.SilkS")
		)
		(fp_line
			(start 1.143 -0.5588)
			(end 1.143 0.5588)
			(stroke
				(width 0.1)
				(type default)
			)
			(layer "B.SilkS")
		)
		(fp_line
			(start -1.143 0.5588)
			(end -1.143 -0.5588)
			(stroke
				(width 0.1)
				(type default)
			)
			(layer "B.SilkS")
		)
		(fp_line
			(start -1.143 -0.5588)
			(end 1.143 -0.5588)
			(stroke
				(width 0.1)
				(type default)
			)
			(layer "B.SilkS")
		)
		(fp_rect
			(start -1.143 -0.5588)
			(end 1.143 0.5588)
			(stroke
				(width 0)
				(type default)
			)
			(fill no)
			(layer "B.CrtYd")
		)
		(fp_line
			(start 0.508 0.3048)
			(end -0.508 0.3048)
			(stroke
				(width 0.1)
				(type default)
			)
			(layer "B.Fab")
		)
		(fp_line
			(start 0.508 -0.3048)
			(end 0.508 0.3048)
			(stroke
				(width 0.1)
				(type default)
			)
			(layer "B.Fab")
		)
		(fp_line
			(start -0.508 0.3048)
			(end -0.508 -0.3048)
			(stroke
				(width 0.1)
				(type default)
			)
			(layer "B.Fab")
		)
		(fp_line
			(start -0.508 -0.3048)
			(end 0.508 -0.3048)
			(stroke
				(width 0.1)
				(type default)
			)
			(layer "B.Fab")
		)
		(pad "1" smd rect
			(at 0.5334 0)
			(size 0.7112 0.6096)
			(layers "B.Cu" "B.Mask" "B.Paste")
			(net "XP3R3V_FPGA")
		)
		(pad "2" smd rect
			(at -0.5334 0)
			(size 0.7112 0.6096)
			(layers "B.Cu" "B.Mask" "B.Paste")
			(net "FPGA_IN_MAC_USB_OC_N")
		)
		(zone
			(layer "B.Cu")
			(hatch none 0.5)
			(connect_pads
				(clearance 0)
			)
			(min_thickness 0.25)
			(keepout
				(tracks allowed)
				(vias not_allowed)
				(pads allowed)
				(copperpour not_allowed)
				(footprints allowed)
			)
			(placement
				(enabled no)
				(sheetname "")
			)
			(fill
				(thermal_gap 0.5)
				(thermal_bridge_width 0.5)
				(island_removal_mode 0)
			)
			(polygon
				(pts
					(xy 64.3382 -60.0202) (xy 64.3382 -60.6298) (xy 64.1858 -60.6298) (xy 64.1858 -60.0202)
				)
			)
		)
	)
	(footprint ""
		(layer "B.Cu")
		(at 83.2358 -87.122 180)
		(property "Reference" "R155"
			(at 0.6858 5.42163 0)
			(unlocked yes)
			(layer "B.SilkS")
			(effects
				(font
					(size 0.7874 0.5842)
					(thickness 0.1524)
				)
				(justify mirror)
			)
		)
		(property "Value" "VAL*"
			(at -0.02032 2.13233 180)
			(unlocked yes)
			(layer "B.Fab")
			(hide yes)
			(effects
				(font
					(size 0.7874 0.5842)
					(thickness 0.1524)
				)
				(justify mirror)
			)
		)
		(property "Tolerance" "TOL*"
			(at -0.044704 3.05435 180)
			(unlocked yes)
			(layer "Cmts.User")
			(hide yes)
			(effects
				(font
					(size 0.7874 0.5842)
					(thickness 0.1524)
				)
				(justify mirror)
			)
		)
		(property "User Part Number" "PARTNUM*"
			(at -0.02032 4.024884 180)
			(unlocked yes)
			(layer "Cmts.User")
			(hide yes)
			(effects
				(font
					(size 0.7874 0.5842)
					(thickness 0.1524)
				)
				(justify mirror)
			)
		)
		(property "Device Type" "RESISTOR-G155-14701-01,4.7KOHMA"
			(at -0.008382 1.210564 180)
			(unlocked yes)
			(layer "B.Fab")
			(hide yes)
			(effects
				(font
					(size 0.7874 0.5842)
					(thickness 0.1524)
				)
				(justify mirror)
			)
		)
		(duplicate_pad_numbers_are_jumpers no)
		(fp_line
			(start 1.143 0.5588)
			(end -1.143 0.5588)
			(stroke
				(width 0.1)
				(type default)
			)
			(layer "B.SilkS")
		)
		(fp_line
			(start 1.143 -0.5588)
			(end 1.143 0.5588)
			(stroke
				(width 0.1)
				(type default)
			)
			(layer "B.SilkS")
		)
		(fp_line
			(start -1.143 0.5588)
			(end -1.143 -0.5588)
			(stroke
				(width 0.1)
				(type default)
			)
			(layer "B.SilkS")
		)
		(fp_line
			(start -1.143 -0.5588)
			(end 1.143 -0.5588)
			(stroke
				(width 0.1)
				(type default)
			)
			(layer "B.SilkS")
		)
		(fp_rect
			(start -1.143 0.5588)
			(end 1.143 -0.5588)
			(stroke
				(width 0)
				(type default)
			)
			(fill no)
			(layer "B.CrtYd")
		)
		(fp_line
			(start 0.508 0.3048)
			(end -0.508 0.3048)
			(stroke
				(width 0.1)
				(type default)
			)
			(layer "B.Fab")
		)
		(fp_line
			(start 0.508 -0.3048)
			(end 0.508 0.3048)
			(stroke
				(width 0.1)
				(type default)
			)
			(layer "B.Fab")
		)
		(fp_line
			(start -0.508 0.3048)
			(end -0.508 -0.3048)
			(stroke
				(width 0.1)
				(type default)
			)
			(layer "B.Fab")
		)
		(fp_line
			(start -0.508 -0.3048)
			(end 0.508 -0.3048)
			(stroke
				(width 0.1)
				(type default)
			)
			(layer "B.Fab")
		)
		(pad "1" smd rect
			(at 0.5334 0)
			(size 0.7112 0.6096)
			(layers "B.Cu" "B.Mask" "B.Paste")
			(net "SG")
		)
		(pad "2" smd rect
			(at -0.5334 0)
			(size 0.7112 0.6096)
			(layers "B.Cu" "B.Mask" "B.Paste")
			(net "PCA9546_RST_N")
		)
		(zone
			(layer "B.Cu")
			(hatch none 0.5)
			(connect_pads
				(clearance 0)
			)
			(min_thickness 0.25)
			(keepout
				(tracks allowed)
				(vias not_allowed)
				(pads allowed)
				(copperpour not_allowed)
				(footprints allowed)
			)
			(placement
				(enabled no)
				(sheetname "")
			)
			(fill
				(thermal_gap 0.5)
				(thermal_bridge_width 0.5)
				(island_removal_mode 0)
			)
			(polygon
				(pts
					(xy 83.312 -87.4268) (xy 83.1596 -87.4268) (xy 83.1596 -86.8172) (xy 83.312 -86.8172)
				)
			)
		)
	)
	(footprint ""
		(layer "B.Cu")
		(at 105.847134 -42.323258 -90)
		(property "Reference" "C156"
			(at 1.015238 41.383204 270)
			(unlocked yes)
			(layer "B.SilkS")
			(effects
				(font
					(size 0.635 0.4064)
					(thickness 0.1524)
				)
				(justify mirror)
			)
		)
		(property "Value" "VAL*"
			(at 0 3.718306 270)
			(unlocked yes)
			(layer "B.Fab")
			(hide yes)
			(effects
				(font
					(size 0.7874 0.5842)
					(thickness 0.127)
				)
				(justify mirror)
			)
		)
		(property "Device Type" "CAPACITOR-G105-0B104-CK,0.1UF,A"
			(at 0 1.432306 270)
			(unlocked yes)
			(layer "B.Fab")
			(hide yes)
			(effects
				(font
					(size 0.7874 0.5842)
					(thickness 0.127)
				)
				(justify mirror)
			)
		)
		(property "User Part Number" "PARTNUM*"
			(at 0 2.575306 270)
			(unlocked yes)
			(layer "Cmts.User")
			(hide yes)
			(effects
				(font
					(size 0.7874 0.5842)
					(thickness 0.127)
				)
				(justify mirror)
			)
		)
		(property "Tolerance" "TOL*"
			(at 0 4.861306 270)
			(unlocked yes)
			(layer "Cmts.User")
			(hide yes)
			(effects
				(font
					(size 0.7874 0.5842)
					(thickness 0.127)
				)
				(justify mirror)
			)
		)
		(duplicate_pad_numbers_are_jumpers no)
		(fp_line
			(start -0.970026 0.4699)
			(end 0.970026 0.4699)
			(stroke
				(width 0.1)
				(type default)
			)
			(layer "B.SilkS")
		)
		(fp_line
			(start 0.970026 0.4699)
			(end 0.970026 -0.4699)
			(stroke
				(width 0.1)
				(type default)
			)
			(layer "B.SilkS")
		)
		(fp_line
			(start -0.970026 -0.4699)
			(end -0.970026 0.4699)
			(stroke
				(width 0.1)
				(type default)
			)
			(layer "B.SilkS")
		)
		(fp_line
			(start 0.970026 -0.4699)
			(end -0.970026 -0.4699)
			(stroke
				(width 0.1)
				(type default)
			)
			(layer "B.SilkS")
		)
		(fp_poly
			(pts
				(xy 0.970026 0.4699) (xy -0.970026 0.4699) (xy -0.970026 -0.4699) (xy 0.970026 -0.4699)
			)
			(stroke
				(width 0)
				(type default)
			)
			(fill no)
			(layer "B.CrtYd")
		)
		(fp_line
			(start -0.508 0.3048)
			(end 0.508 0.3048)
			(stroke
				(width 0.1)
				(type default)
			)
			(layer "B.Fab")
		)
		(fp_line
			(start 0.508 0.3048)
			(end 0.508 -0.3048)
			(stroke
				(width 0.1)
				(type default)
			)
			(layer "B.Fab")
		)
		(fp_line
			(start -0.508 -0.3048)
			(end -0.508 0.3048)
			(stroke
				(width 0.1)
				(type default)
			)
			(layer "B.Fab")
		)
		(fp_line
			(start 0.508 -0.3048)
			(end -0.508 -0.3048)
			(stroke
				(width 0.1)
				(type default)
			)
			(layer "B.Fab")
		)
		(pad "1" smd circle
			(at 0.500126 0 90)
			(size 0.635 0.635)
			(layers "B.Cu" "B.Mask" "B.Paste")
			(net "XP1R0V_FPGA_VCCINT")
		)
		(pad "2" smd circle
			(at -0.500126 0 90)
			(size 0.635 0.635)
			(layers "B.Cu" "B.Mask" "B.Paste")
			(net "SG")
		)
	)
	(footprint ""
		(layer "B.Cu")
		(at 53.975 -90.17)
		(property "Reference" "R446"
			(at 0.127 -4.15163 0)
			(unlocked yes)
			(layer "B.SilkS")
			(effects
				(font
					(size 0.7874 0.5842)
					(thickness 0.1524)
				)
				(justify mirror)
			)
		)
		(property "Value" "VAL*"
			(at -0.02032 2.13233 0)
			(unlocked yes)
			(layer "B.Fab")
			(hide yes)
			(effects
				(font
					(size 0.7874 0.5842)
					(thickness 0.1524)
				)
				(justify mirror)
			)
		)
		(property "Tolerance" "TOL*"
			(at -0.044704 3.05435 0)
			(unlocked yes)
			(layer "Cmts.User")
			(hide yes)
			(effects
				(font
					(size 0.7874 0.5842)
					(thickness 0.1524)
				)
				(justify mirror)
			)
		)
		(property "User Part Number" "PARTNUM*"
			(at -0.02032 4.024884 0)
			(unlocked yes)
			(layer "Cmts.User")
			(hide yes)
			(effects
				(font
					(size 0.7874 0.5842)
					(thickness 0.1524)
				)
				(justify mirror)
			)
		)
		(property "Device Type" "RESISTOR-G155-11002-01,10KOHM,A"
			(at -0.008382 1.210564 0)
			(unlocked yes)
			(layer "B.Fab")
			(hide yes)
			(effects
				(font
					(size 0.7874 0.5842)
					(thickness 0.1524)
				)
				(justify mirror)
			)
		)
		(duplicate_pad_numbers_are_jumpers no)
		(fp_line
			(start -1.143 -0.5588)
			(end 1.143 -0.5588)
			(stroke
				(width 0.1)
				(type default)
			)
			(layer "B.SilkS")
		)
		(fp_line
			(start -1.143 0.5588)
			(end -1.143 -0.5588)
			(stroke
				(width 0.1)
				(type default)
			)
			(layer "B.SilkS")
		)
		(fp_line
			(start 1.143 -0.5588)
			(end 1.143 0.5588)
			(stroke
				(width 0.1)
				(type default)
			)
			(layer "B.SilkS")
		)
		(fp_line
			(start 1.143 0.5588)
			(end -1.143 0.5588)
			(stroke
				(width 0.1)
				(type default)
			)
			(layer "B.SilkS")
		)
		(fp_poly
			(pts
				(xy 1.143 0.5588) (xy -1.143 0.5588) (xy -1.143 -0.5588) (xy 1.143 -0.5588)
			)
			(stroke
				(width 0)
				(type default)
			)
			(fill no)
			(layer "B.CrtYd")
		)
		(fp_line
			(start -0.508 -0.3048)
			(end 0.508 -0.3048)
			(stroke
				(width 0.1)
				(type default)
			)
			(layer "B.Fab")
		)
		(fp_line
			(start -0.508 0.3048)
			(end -0.508 -0.3048)
			(stroke
				(width 0.1)
				(type default)
			)
			(layer "B.Fab")
		)
		(fp_line
			(start 0.508 -0.3048)
			(end 0.508 0.3048)
			(stroke
				(width 0.1)
				(type default)
			)
			(layer "B.Fab")
		)
		(fp_line
			(start 0.508 0.3048)
			(end -0.508 0.3048)
			(stroke
				(width 0.1)
				(type default)
			)
			(layer "B.Fab")
		)
		(pad "1" smd rect
			(at 0.5334 0 180)
			(size 0.7112 0.6096)
			(layers "B.Cu" "B.Mask" "B.Paste")
			(net "XP3R3V_FT4232")
		)
		(pad "2" smd rect
			(at -0.5334 0 180)
			(size 0.7112 0.6096)
			(layers "B.Cu" "B.Mask" "B.Paste")
			(net "FTDI_EE_CS")
		)
		(zone
			(layer "B.Cu")
			(hatch none 0.5)
			(connect_pads
				(clearance 0)
			)
			(min_thickness 0.25)
			(keepout
				(tracks not_allowed)
				(vias allowed)
				(pads allowed)
				(copperpour not_allowed)
				(footprints allowed)
			)
			(placement
				(enabled no)
				(sheetname "")
			)
			(fill
				(thermal_gap 0.5)
				(thermal_bridge_width 0.5)
				(island_removal_mode 0)
			)
			(polygon
				(pts
					(xy 54.0512 -89.8652) (xy 54.0512 -90.4748) (xy 53.8988 -90.4748) (xy 53.8988 -89.8652)
				)
			)
		)
		(zone
			(layer "B.Cu")
			(hatch none 0.5)
			(connect_pads
				(clearance 0)
			)
			(min_thickness 0.25)
			(keepout
				(tracks allowed)
				(vias not_allowed)
				(pads allowed)
				(copperpour not_allowed)
				(footprints allowed)
			)
			(placement
				(enabled no)
				(sheetname "")
			)
			(fill
				(thermal_gap 0.5)
				(thermal_bridge_width 0.5)
				(island_removal_mode 0)
			)
			(polygon
				(pts
					(xy 54.0512 -89.8652) (xy 54.0512 -90.4748) (xy 53.8988 -90.4748) (xy 53.8988 -89.8652)
				)
			)
		)
	)
	(footprint ""
		(layer "B.Cu")
		(at 146.6088 -17.2466 90)
		(property "Reference" "R227"
			(at -0.3556 1.81483 270)
			(unlocked yes)
			(layer "B.SilkS")
			(effects
				(font
					(size 0.7874 0.5842)
					(thickness 0.1524)
				)
				(justify mirror)
			)
		)
		(property "Value" "VAL*"
			(at -0.02032 2.13233 90)
			(unlocked yes)
			(layer "B.Fab")
			(hide yes)
			(effects
				(font
					(size 0.7874 0.5842)
					(thickness 0.1524)
				)
				(justify mirror)
			)
		)
		(property "Tolerance" "TOL*"
			(at -0.044704 3.05435 90)
			(unlocked yes)
			(layer "Cmts.User")
			(hide yes)
			(effects
				(font
					(size 0.7874 0.5842)
					(thickness 0.1524)
				)
				(justify mirror)
			)
		)
		(property "User Part Number" "PARTNUM*"
			(at -0.02032 4.024884 90)
			(unlocked yes)
			(layer "Cmts.User")
			(hide yes)
			(effects
				(font
					(size 0.7874 0.5842)
					(thickness 0.1524)
				)
				(justify mirror)
			)
		)
		(property "Device Type" "RESISTOR-G155-11002-01,10KOHM,A"
			(at -0.008382 1.210564 90)
			(unlocked yes)
			(layer "B.Fab")
			(hide yes)
			(effects
				(font
					(size 0.7874 0.5842)
					(thickness 0.1524)
				)
				(justify mirror)
			)
		)
		(duplicate_pad_numbers_are_jumpers no)
		(fp_line
			(start 1.143 -0.5588)
			(end 1.143 0.5588)
			(stroke
				(width 0.1)
				(type default)
			)
			(layer "B.SilkS")
		)
		(fp_line
			(start -1.143 -0.5588)
			(end 1.143 -0.5588)
			(stroke
				(width 0.1)
				(type default)
			)
			(layer "B.SilkS")
		)
		(fp_line
			(start 1.143 0.5588)
			(end -1.143 0.5588)
			(stroke
				(width 0.1)
				(type default)
			)
			(layer "B.SilkS")
		)
		(fp_line
			(start -1.143 0.5588)
			(end -1.143 -0.5588)
			(stroke
				(width 0.1)
				(type default)
			)
			(layer "B.SilkS")
		)
		(fp_rect
			(start 1.143 0.5588)
			(end -1.143 -0.5588)
			(stroke
				(width 0)
				(type default)
			)
			(fill no)
			(layer "B.CrtYd")
		)
		(fp_line
			(start 0.508 -0.3048)
			(end 0.508 0.3048)
			(stroke
				(width 0.1)
				(type default)
			)
			(layer "B.Fab")
		)
		(fp_line
			(start -0.508 -0.3048)
			(end 0.508 -0.3048)
			(stroke
				(width 0.1)
				(type default)
			)
			(layer "B.Fab")
		)
		(fp_line
			(start 0.508 0.3048)
			(end -0.508 0.3048)
			(stroke
				(width 0.1)
				(type default)
			)
			(layer "B.Fab")
		)
		(fp_line
			(start -0.508 0.3048)
			(end -0.508 -0.3048)
			(stroke
				(width 0.1)
				(type default)
			)
			(layer "B.Fab")
		)
		(pad "1" smd rect
			(at 0.5334 0 270)
			(size 0.7112 0.6096)
			(layers "B.Cu" "B.Mask" "B.Paste")
			(net "UNNAMED_515_CAPACITOR_I128_1")
		)
		(pad "2" smd rect
			(at -0.5334 0 270)
			(size 0.7112 0.6096)
			(layers "B.Cu" "B.Mask" "B.Paste")
			(net "SG")
		)
		(zone
			(layer "B.Cu")
			(hatch none 0.5)
			(connect_pads
				(clearance 0)
			)
			(min_thickness 0.25)
			(keepout
				(tracks allowed)
				(vias not_allowed)
				(pads allowed)
				(copperpour not_allowed)
				(footprints allowed)
			)
			(placement
				(enabled no)
				(sheetname "")
			)
			(fill
				(thermal_gap 0.5)
				(thermal_bridge_width 0.5)
				(island_removal_mode 0)
			)
			(polygon
				(pts
					(xy 146.9136 -17.3228) (xy 146.304 -17.3228) (xy 146.304 -17.1704) (xy 146.9136 -17.1704)
				)
			)
		)
	)
	(footprint ""
		(layer "B.Cu")
		(at 20.2946 -18.5928 90)
		(property "Reference" "R2"
			(at -0.1778 -1.15697 270)
			(unlocked yes)
			(layer "B.SilkS")
			(effects
				(font
					(size 0.7874 0.5842)
					(thickness 0.1524)
				)
				(justify mirror)
			)
		)
		(property "Value" "VAL*"
			(at -0.02032 2.13233 90)
			(unlocked yes)
			(layer "B.Fab")
			(hide yes)
			(effects
				(font
					(size 0.7874 0.5842)
					(thickness 0.1524)
				)
				(justify mirror)
			)
		)
		(property "Device Type" "RESISTOR-G155-13300-01,330OHM,A"
			(at -0.008382 1.210564 90)
			(unlocked yes)
			(layer "B.Fab")
			(hide yes)
			(effects
				(font
					(size 0.7874 0.5842)
					(thickness 0.1524)
				)
				(justify mirror)
			)
		)
		(property "User Part Number" "PARTNUM*"
			(at -0.02032 4.024884 90)
			(unlocked yes)
			(layer "Cmts.User")
			(hide yes)
			(effects
				(font
					(size 0.7874 0.5842)
					(thickness 0.1524)
				)
				(justify mirror)
			)
		)
		(property "Tolerance" "TOL*"
			(at -0.044704 3.05435 90)
			(unlocked yes)
			(layer "Cmts.User")
			(hide yes)
			(effects
				(font
					(size 0.7874 0.5842)
					(thickness 0.1524)
				)
				(justify mirror)
			)
		)
		(duplicate_pad_numbers_are_jumpers no)
		(fp_line
			(start 1.143 -0.5588)
			(end 1.143 0.5588)
			(stroke
				(width 0.1)
				(type default)
			)
			(layer "B.SilkS")
		)
		(fp_line
			(start -1.143 -0.5588)
			(end 1.143 -0.5588)
			(stroke
				(width 0.1)
				(type default)
			)
			(layer "B.SilkS")
		)
		(fp_line
			(start 1.143 0.5588)
			(end -1.143 0.5588)
			(stroke
				(width 0.1)
				(type default)
			)
			(layer "B.SilkS")
		)
		(fp_line
			(start -1.143 0.5588)
			(end -1.143 -0.5588)
			(stroke
				(width 0.1)
				(type default)
			)
			(layer "B.SilkS")
		)
		(fp_rect
			(start 1.143 -0.5588)
			(end -1.143 0.5588)
			(stroke
				(width 0)
				(type default)
			)
			(fill no)
			(layer "B.CrtYd")
		)
		(fp_line
			(start 0.508 -0.3048)
			(end 0.508 0.3048)
			(stroke
				(width 0.1)
				(type default)
			)
			(layer "B.Fab")
		)
		(fp_line
			(start -0.508 -0.3048)
			(end 0.508 -0.3048)
			(stroke
				(width 0.1)
				(type default)
			)
			(layer "B.Fab")
		)
		(fp_line
			(start 0.508 0.3048)
			(end -0.508 0.3048)
			(stroke
				(width 0.1)
				(type default)
			)
			(layer "B.Fab")
		)
		(fp_line
			(start -0.508 0.3048)
			(end -0.508 -0.3048)
			(stroke
				(width 0.1)
				(type default)
			)
			(layer "B.Fab")
		)
		(pad "1" smd rect
			(at 0.5334 0 270)
			(size 0.7112 0.6096)
			(layers "B.Cu" "B.Mask" "B.Paste")
			(net "FPGA_OUT_SEC_EEPROM_WP")
		)
		(pad "2" smd rect
			(at -0.5334 0 270)
			(size 0.7112 0.6096)
			(layers "B.Cu" "B.Mask" "B.Paste")
			(net "SEC_EEPROM_WP")
		)
		(zone
			(layer "B.Cu")
			(hatch none 0.5)
			(connect_pads
				(clearance 0)
			)
			(min_thickness 0.25)
			(keepout
				(tracks allowed)
				(vias not_allowed)
				(pads allowed)
				(copperpour not_allowed)
				(footprints allowed)
			)
			(placement
				(enabled no)
				(sheetname "")
			)
			(fill
				(thermal_gap 0.5)
				(thermal_bridge_width 0.5)
				(island_removal_mode 0)
			)
			(polygon
				(pts
					(xy 19.9898 -18.669) (xy 19.9898 -18.5166) (xy 20.5994 -18.5166) (xy 20.5994 -18.669)
				)
			)
		)
	)
	(footprint ""
		(layer "B.Cu")
		(at 85.471 -104.013)
		(property "Reference" "R37"
			(at 0 1.30937 0)
			(unlocked yes)
			(layer "B.SilkS")
			(effects
				(font
					(size 0.7874 0.5842)
					(thickness 0.1524)
				)
				(justify mirror)
			)
		)
		(property "Value" "VAL*"
			(at -0.02032 2.13233 0)
			(unlocked yes)
			(layer "B.Fab")
			(hide yes)
			(effects
				(font
					(size 0.7874 0.5842)
					(thickness 0.1524)
				)
				(justify mirror)
			)
		)
		(property "Tolerance" "TOL*"
			(at -0.044704 3.05435 0)
			(unlocked yes)
			(layer "Cmts.User")
			(hide yes)
			(effects
				(font
					(size 0.7874 0.5842)
					(thickness 0.1524)
				)
				(justify mirror)
			)
		)
		(property "User Part Number" "PARTNUM*"
			(at -0.02032 4.024884 0)
			(unlocked yes)
			(layer "Cmts.User")
			(hide yes)
			(effects
				(font
					(size 0.7874 0.5842)
					(thickness 0.1524)
				)
				(justify mirror)
			)
		)
		(property "Device Type" "RESISTOR-G155-100R0-J0,0OHM,-"
			(at -0.008382 1.210564 0)
			(unlocked yes)
			(layer "B.Fab")
			(hide yes)
			(effects
				(font
					(size 0.7874 0.5842)
					(thickness 0.1524)
				)
				(justify mirror)
			)
		)
		(duplicate_pad_numbers_are_jumpers no)
		(fp_line
			(start -1.143 -0.5588)
			(end 1.143 -0.5588)
			(stroke
				(width 0.1)
				(type default)
			)
			(layer "B.SilkS")
		)
		(fp_line
			(start -1.143 0.5588)
			(end -1.143 -0.5588)
			(stroke
				(width 0.1)
				(type default)
			)
			(layer "B.SilkS")
		)
		(fp_line
			(start 1.143 -0.5588)
			(end 1.143 0.5588)
			(stroke
				(width 0.1)
				(type default)
			)
			(layer "B.SilkS")
		)
		(fp_line
			(start 1.143 0.5588)
			(end -1.143 0.5588)
			(stroke
				(width 0.1)
				(type default)
			)
			(layer "B.SilkS")
		)
		(fp_poly
			(pts
				(xy 1.143 0.5588) (xy -1.143 0.5588) (xy -1.143 -0.5588) (xy 1.143 -0.5588)
			)
			(stroke
				(width 0)
				(type default)
			)
			(fill no)
			(layer "B.CrtYd")
		)
		(fp_line
			(start -0.508 -0.3048)
			(end 0.508 -0.3048)
			(stroke
				(width 0.1)
				(type default)
			)
			(layer "B.Fab")
		)
		(fp_line
			(start -0.508 0.3048)
			(end -0.508 -0.3048)
			(stroke
				(width 0.1)
				(type default)
			)
			(layer "B.Fab")
		)
		(fp_line
			(start 0.508 -0.3048)
			(end 0.508 0.3048)
			(stroke
				(width 0.1)
				(type default)
			)
			(layer "B.Fab")
		)
		(fp_line
			(start 0.508 0.3048)
			(end -0.508 0.3048)
			(stroke
				(width 0.1)
				(type default)
			)
			(layer "B.Fab")
		)
		(pad "1" smd rect
			(at 0.5334 0 180)
			(size 0.7112 0.6096)
			(layers "B.Cu" "B.Mask" "B.Paste")
			(net "XP3R3V_BT")
		)
		(pad "2" smd rect
			(at -0.5334 0 180)
			(size 0.7112 0.6096)
			(layers "B.Cu" "B.Mask" "B.Paste")
			(net "UNNAMED_517_CAPACITOR_I27_1")
		)
		(zone
			(layer "B.Cu")
			(hatch none 0.5)
			(connect_pads
				(clearance 0)
			)
			(min_thickness 0.25)
			(keepout
				(tracks allowed)
				(vias not_allowed)
				(pads allowed)
				(copperpour not_allowed)
				(footprints allowed)
			)
			(placement
				(enabled no)
				(sheetname "")
			)
			(fill
				(thermal_gap 0.5)
				(thermal_bridge_width 0.5)
				(island_removal_mode 0)
			)
			(polygon
				(pts
					(xy 85.5472 -103.7082) (xy 85.5472 -104.3178) (xy 85.3948 -104.3178) (xy 85.3948 -103.7082)
				)
			)
		)
		(zone
			(layer "B.Cu")
			(hatch none 0.5)
			(connect_pads
				(clearance 0)
			)
			(min_thickness 0.25)
			(keepout
				(tracks not_allowed)
				(vias allowed)
				(pads allowed)
				(copperpour not_allowed)
				(footprints allowed)
			)
			(placement
				(enabled no)
				(sheetname "")
			)
			(fill
				(thermal_gap 0.5)
				(thermal_bridge_width 0.5)
				(island_removal_mode 0)
			)
			(polygon
				(pts
					(xy 85.5472 -103.7082) (xy 85.5472 -104.3178) (xy 85.3948 -104.3178) (xy 85.3948 -103.7082)
				)
			)
		)
	)
	(footprint ""
		(layer "B.Cu")
		(at 111.125 -104.521)
		(property "Reference" "R322"
			(at 0.381 -3.00863 0)
			(unlocked yes)
			(layer "B.SilkS")
			(effects
				(font
					(size 0.7874 0.5842)
					(thickness 0.1524)
				)
				(justify mirror)
			)
		)
		(property "Value" "VAL*"
			(at -0.02032 2.13233 0)
			(unlocked yes)
			(layer "B.Fab")
			(hide yes)
			(effects
				(font
					(size 0.7874 0.5842)
					(thickness 0.1524)
				)
				(justify mirror)
			)
		)
		(property "Tolerance" "TOL*"
			(at -0.044704 3.05435 0)
			(unlocked yes)
			(layer "Cmts.User")
			(hide yes)
			(effects
				(font
					(size 0.7874 0.5842)
					(thickness 0.1524)
				)
				(justify mirror)
			)
		)
		(property "User Part Number" "PARTNUM*"
			(at -0.02032 4.024884 0)
			(unlocked yes)
			(layer "Cmts.User")
			(hide yes)
			(effects
				(font
					(size 0.7874 0.5842)
					(thickness 0.1524)
				)
				(justify mirror)
			)
		)
		(property "Device Type" "RESISTOR-G155-133R0-01,33OHM,1%"
			(at -0.008382 1.210564 0)
			(unlocked yes)
			(layer "B.Fab")
			(hide yes)
			(effects
				(font
					(size 0.7874 0.5842)
					(thickness 0.1524)
				)
				(justify mirror)
			)
		)
		(duplicate_pad_numbers_are_jumpers no)
		(fp_line
			(start -1.143 -0.5588)
			(end 1.143 -0.5588)
			(stroke
				(width 0.1)
				(type default)
			)
			(layer "B.SilkS")
		)
		(fp_line
			(start -1.143 0.5588)
			(end -1.143 -0.5588)
			(stroke
				(width 0.1)
				(type default)
			)
			(layer "B.SilkS")
		)
		(fp_line
			(start 1.143 -0.5588)
			(end 1.143 0.5588)
			(stroke
				(width 0.1)
				(type default)
			)
			(layer "B.SilkS")
		)
		(fp_line
			(start 1.143 0.5588)
			(end -1.143 0.5588)
			(stroke
				(width 0.1)
				(type default)
			)
			(layer "B.SilkS")
		)
		(fp_poly
			(pts
				(xy 1.143 0.5588) (xy -1.143 0.5588) (xy -1.143 -0.5588) (xy 1.143 -0.5588)
			)
			(stroke
				(width 0)
				(type default)
			)
			(fill no)
			(layer "B.CrtYd")
		)
		(fp_line
			(start -0.508 -0.3048)
			(end 0.508 -0.3048)
			(stroke
				(width 0.1)
				(type default)
			)
			(layer "B.Fab")
		)
		(fp_line
			(start -0.508 0.3048)
			(end -0.508 -0.3048)
			(stroke
				(width 0.1)
				(type default)
			)
			(layer "B.Fab")
		)
		(fp_line
			(start 0.508 -0.3048)
			(end 0.508 0.3048)
			(stroke
				(width 0.1)
				(type default)
			)
			(layer "B.Fab")
		)
		(fp_line
			(start 0.508 0.3048)
			(end -0.508 0.3048)
			(stroke
				(width 0.1)
				(type default)
			)
			(layer "B.Fab")
		)
		(pad "1" smd rect
			(at 0.5334 0 180)
			(size 0.7112 0.6096)
			(layers "B.Cu" "B.Mask" "B.Paste")
			(net "FPGA_M_RGB_LED_I2C_SCL")
		)
		(pad "2" smd rect
			(at -0.5334 0 180)
			(size 0.7112 0.6096)
			(layers "B.Cu" "B.Mask" "B.Paste")
			(net "R_RGB_LED_I2C_SCL")
		)
		(zone
			(layer "B.Cu")
			(hatch none 0.5)
			(connect_pads
				(clearance 0)
			)
			(min_thickness 0.25)
			(keepout
				(tracks not_allowed)
				(vias allowed)
				(pads allowed)
				(copperpour not_allowed)
				(footprints allowed)
			)
			(placement
				(enabled no)
				(sheetname "")
			)
			(fill
				(thermal_gap 0.5)
				(thermal_bridge_width 0.5)
				(island_removal_mode 0)
			)
			(polygon
				(pts
					(xy 111.2012 -104.2162) (xy 111.2012 -104.8258) (xy 111.0488 -104.8258) (xy 111.0488 -104.2162)
				)
			)
		)
		(zone
			(layer "B.Cu")
			(hatch none 0.5)
			(connect_pads
				(clearance 0)
			)
			(min_thickness 0.25)
			(keepout
				(tracks allowed)
				(vias not_allowed)
				(pads allowed)
				(copperpour not_allowed)
				(footprints allowed)
			)
			(placement
				(enabled no)
				(sheetname "")
			)
			(fill
				(thermal_gap 0.5)
				(thermal_bridge_width 0.5)
				(island_removal_mode 0)
			)
			(polygon
				(pts
					(xy 111.2012 -104.2162) (xy 111.2012 -104.8258) (xy 111.0488 -104.8258) (xy 111.0488 -104.2162)
				)
			)
		)
	)
	(footprint ""
		(layer "B.Cu")
		(at 44.323 -99.314 180)
		(property "Reference" "C44"
			(at -2.4384 -0.03937 0)
			(unlocked yes)
			(layer "B.SilkS")
			(effects
				(font
					(size 0.7874 0.5842)
					(thickness 0.1524)
				)
				(justify mirror)
			)
		)
		(property "Value" "VAL*"
			(at -0.0762 2.067306 180)
			(unlocked yes)
			(layer "B.Fab")
			(hide yes)
			(effects
				(font
					(size 0.7874 0.5842)
					(thickness 0.1524)
				)
				(justify mirror)
			)
		)
		(property "Tolerance" "TOL*"
			(at -0.0762 3.032506 180)
			(unlocked yes)
			(layer "Cmts.User")
			(hide yes)
			(effects
				(font
					(size 0.7874 0.5842)
					(thickness 0.1524)
				)
				(justify mirror)
			)
		)
		(property "User Part Number" "PARTNUM*"
			(at -0.1016 4.023106 180)
			(unlocked yes)
			(layer "Cmts.User")
			(hide yes)
			(effects
				(font
					(size 0.7874 0.5842)
					(thickness 0.1524)
				)
				(justify mirror)
			)
		)
		(property "Device Type" "CAPACITOR-G105-0B104-EK,0.1UF,A"
			(at -0.0508 1.127506 180)
			(unlocked yes)
			(layer "B.Fab")
			(hide yes)
			(effects
				(font
					(size 0.7874 0.5842)
					(thickness 0.1524)
				)
				(justify mirror)
			)
		)
		(duplicate_pad_numbers_are_jumpers no)
		(fp_line
			(start 1.143 0.5588)
			(end -1.143 0.5588)
			(stroke
				(width 0.1)
				(type default)
			)
			(layer "B.SilkS")
		)
		(fp_line
			(start 1.143 -0.5588)
			(end 1.143 0.5588)
			(stroke
				(width 0.1)
				(type default)
			)
			(layer "B.SilkS")
		)
		(fp_line
			(start -1.143 0.5588)
			(end -1.143 -0.5588)
			(stroke
				(width 0.1)
				(type default)
			)
			(layer "B.SilkS")
		)
		(fp_line
			(start -1.143 -0.5588)
			(end 1.143 -0.5588)
			(stroke
				(width 0.1)
				(type default)
			)
			(layer "B.SilkS")
		)
		(fp_rect
			(start 1.143 0.5588)
			(end -1.143 -0.5588)
			(stroke
				(width 0)
				(type default)
			)
			(fill no)
			(layer "B.CrtYd")
		)
		(fp_line
			(start 0.508 0.3048)
			(end -0.508 0.3048)
			(stroke
				(width 0.1)
				(type default)
			)
			(layer "B.Fab")
		)
		(fp_line
			(start 0.508 -0.3048)
			(end 0.508 0.3048)
			(stroke
				(width 0.1)
				(type default)
			)
			(layer "B.Fab")
		)
		(fp_line
			(start -0.508 0.3048)
			(end -0.508 -0.3048)
			(stroke
				(width 0.1)
				(type default)
			)
			(layer "B.Fab")
		)
		(fp_line
			(start -0.508 -0.3048)
			(end 0.508 -0.3048)
			(stroke
				(width 0.1)
				(type default)
			)
			(layer "B.Fab")
		)
		(pad "1" smd rect
			(at 0.5334 0)
			(size 0.7112 0.6096)
			(layers "B.Cu" "B.Mask" "B.Paste")
			(net "UNNAMED_516_CAPACITOR_I27_1")
		)
		(pad "2" smd rect
			(at -0.5334 0)
			(size 0.7112 0.6096)
			(layers "B.Cu" "B.Mask" "B.Paste")
			(net "XP5R0V_SW")
		)
		(zone
			(layer "B.Cu")
			(hatch none 0.5)
			(connect_pads
				(clearance 0)
			)
			(min_thickness 0.25)
			(keepout
				(tracks allowed)
				(vias not_allowed)
				(pads allowed)
				(copperpour not_allowed)
				(footprints allowed)
			)
			(placement
				(enabled no)
				(sheetname "")
			)
			(fill
				(thermal_gap 0.5)
				(thermal_bridge_width 0.5)
				(island_removal_mode 0)
			)
			(polygon
				(pts
					(xy 44.2468 -99.6188) (xy 44.2468 -99.0092) (xy 44.3992 -99.0092) (xy 44.3992 -99.6188)
				)
			)
		)
	)
	(footprint ""
		(layer "B.Cu")
		(at 156.718 -39.497 -90)
		(property "Reference" "R428"
			(at 6.77037 0.635 0)
			(unlocked yes)
			(layer "B.SilkS")
			(effects
				(font
					(size 0.7874 0.5842)
					(thickness 0.1524)
				)
				(justify mirror)
			)
		)
		(property "Value" "VAL*"
			(at -0.02032 2.13233 270)
			(unlocked yes)
			(layer "B.Fab")
			(hide yes)
			(effects
				(font
					(size 0.7874 0.5842)
					(thickness 0.1524)
				)
				(justify mirror)
			)
		)
		(property "Tolerance" "TOL*"
			(at -0.044704 3.05435 270)
			(unlocked yes)
			(layer "Cmts.User")
			(hide yes)
			(effects
				(font
					(size 0.7874 0.5842)
					(thickness 0.1524)
				)
				(justify mirror)
			)
		)
		(property "User Part Number" "PARTNUM*"
			(at -0.02032 4.024884 270)
			(unlocked yes)
			(layer "Cmts.User")
			(hide yes)
			(effects
				(font
					(size 0.7874 0.5842)
					(thickness 0.1524)
				)
				(justify mirror)
			)
		)
		(property "Device Type" "RESISTOR-G155-133R0-01,33OHM,1%"
			(at -0.008382 1.210564 270)
			(unlocked yes)
			(layer "B.Fab")
			(hide yes)
			(effects
				(font
					(size 0.7874 0.5842)
					(thickness 0.1524)
				)
				(justify mirror)
			)
		)
		(duplicate_pad_numbers_are_jumpers no)
		(fp_line
			(start -1.143 0.5588)
			(end -1.143 -0.5588)
			(stroke
				(width 0.1)
				(type default)
			)
			(layer "B.SilkS")
		)
		(fp_line
			(start 1.143 0.5588)
			(end -1.143 0.5588)
			(stroke
				(width 0.1)
				(type default)
			)
			(layer "B.SilkS")
		)
		(fp_line
			(start -1.143 -0.5588)
			(end 1.143 -0.5588)
			(stroke
				(width 0.1)
				(type default)
			)
			(layer "B.SilkS")
		)
		(fp_line
			(start 1.143 -0.5588)
			(end 1.143 0.5588)
			(stroke
				(width 0.1)
				(type default)
			)
			(layer "B.SilkS")
		)
		(fp_poly
			(pts
				(xy 1.143 0.5588) (xy -1.143 0.5588) (xy -1.143 -0.5588) (xy 1.143 -0.5588)
			)
			(stroke
				(width 0)
				(type default)
			)
			(fill no)
			(layer "B.CrtYd")
		)
		(fp_line
			(start -0.508 0.3048)
			(end -0.508 -0.3048)
			(stroke
				(width 0.1)
				(type default)
			)
			(layer "B.Fab")
		)
		(fp_line
			(start 0.508 0.3048)
			(end -0.508 0.3048)
			(stroke
				(width 0.1)
				(type default)
			)
			(layer "B.Fab")
		)
		(fp_line
			(start -0.508 -0.3048)
			(end 0.508 -0.3048)
			(stroke
				(width 0.1)
				(type default)
			)
			(layer "B.Fab")
		)
		(fp_line
			(start 0.508 -0.3048)
			(end 0.508 0.3048)
			(stroke
				(width 0.1)
				(type default)
			)
			(layer "B.Fab")
		)
		(pad "1" smd rect
			(at 0.5334 0 90)
			(size 0.7112 0.6096)
			(layers "B.Cu" "B.Mask" "B.Paste")
			(net "FPGA_IO_6")
		)
		(pad "2" smd rect
			(at -0.5334 0 90)
			(size 0.7112 0.6096)
			(layers "B.Cu" "B.Mask" "B.Paste")
			(net "UNNAMED_16_CONNHDR2X6FSSMT_I1_6")
		)
		(zone
			(layer "B.Cu")
			(hatch none 0.5)
			(connect_pads
				(clearance 0)
			)
			(min_thickness 0.25)
			(keepout
				(tracks not_allowed)
				(vias allowed)
				(pads allowed)
				(copperpour not_allowed)
				(footprints allowed)
			)
			(placement
				(enabled no)
				(sheetname "")
			)
			(fill
				(thermal_gap 0.5)
				(thermal_bridge_width 0.5)
				(island_removal_mode 0)
			)
			(polygon
				(pts
					(xy 156.4132 -39.4208) (xy 157.0228 -39.4208) (xy 157.0228 -39.5732) (xy 156.4132 -39.5732)
				)
			)
		)
		(zone
			(layer "B.Cu")
			(hatch none 0.5)
			(connect_pads
				(clearance 0)
			)
			(min_thickness 0.25)
			(keepout
				(tracks allowed)
				(vias not_allowed)
				(pads allowed)
				(copperpour not_allowed)
				(footprints allowed)
			)
			(placement
				(enabled no)
				(sheetname "")
			)
			(fill
				(thermal_gap 0.5)
				(thermal_bridge_width 0.5)
				(island_removal_mode 0)
			)
			(polygon
				(pts
					(xy 156.4132 -39.4208) (xy 157.0228 -39.4208) (xy 157.0228 -39.5732) (xy 156.4132 -39.5732)
				)
			)
		)
	)
	(footprint ""
		(layer "B.Cu")
		(at 138.4935 -67.5259 -90)
		(property "Reference" "R402"
			(at 0.8509 1.24587 270)
			(unlocked yes)
			(layer "B.SilkS")
			(effects
				(font
					(size 0.7874 0.5842)
					(thickness 0.1524)
				)
				(justify mirror)
			)
		)
		(property "Value" "VAL*"
			(at -0.02032 2.13233 270)
			(unlocked yes)
			(layer "B.Fab")
			(hide yes)
			(effects
				(font
					(size 0.7874 0.5842)
					(thickness 0.1524)
				)
				(justify mirror)
			)
		)
		(property "Device Type" "RESISTOR-G155-14701-01,4.7KOHMA"
			(at -0.008382 1.210564 270)
			(unlocked yes)
			(layer "B.Fab")
			(hide yes)
			(effects
				(font
					(size 0.7874 0.5842)
					(thickness 0.1524)
				)
				(justify mirror)
			)
		)
		(property "User Part Number" "PARTNUM*"
			(at -0.02032 4.024884 270)
			(unlocked yes)
			(layer "Cmts.User")
			(hide yes)
			(effects
				(font
					(size 0.7874 0.5842)
					(thickness 0.1524)
				)
				(justify mirror)
			)
		)
		(property "Tolerance" "TOL*"
			(at -0.044704 3.05435 270)
			(unlocked yes)
			(layer "Cmts.User")
			(hide yes)
			(effects
				(font
					(size 0.7874 0.5842)
					(thickness 0.1524)
				)
				(justify mirror)
			)
		)
		(duplicate_pad_numbers_are_jumpers no)
		(fp_line
			(start -1.143 0.5588)
			(end -1.143 -0.5588)
			(stroke
				(width 0.1)
				(type default)
			)
			(layer "B.SilkS")
		)
		(fp_line
			(start 1.143 0.5588)
			(end -1.143 0.5588)
			(stroke
				(width 0.1)
				(type default)
			)
			(layer "B.SilkS")
		)
		(fp_line
			(start -1.143 -0.5588)
			(end 1.143 -0.5588)
			(stroke
				(width 0.1)
				(type default)
			)
			(layer "B.SilkS")
		)
		(fp_line
			(start 1.143 -0.5588)
			(end 1.143 0.5588)
			(stroke
				(width 0.1)
				(type default)
			)
			(layer "B.SilkS")
		)
		(fp_rect
			(start 1.143 0.5588)
			(end -1.143 -0.5588)
			(stroke
				(width 0)
				(type default)
			)
			(fill no)
			(layer "B.CrtYd")
		)
		(fp_line
			(start -0.508 0.3048)
			(end -0.508 -0.3048)
			(stroke
				(width 0.1)
				(type default)
			)
			(layer "B.Fab")
		)
		(fp_line
			(start 0.508 0.3048)
			(end -0.508 0.3048)
			(stroke
				(width 0.1)
				(type default)
			)
			(layer "B.Fab")
		)
		(fp_line
			(start -0.508 -0.3048)
			(end 0.508 -0.3048)
			(stroke
				(width 0.1)
				(type default)
			)
			(layer "B.Fab")
		)
		(fp_line
			(start 0.508 -0.3048)
			(end 0.508 0.3048)
			(stroke
				(width 0.1)
				(type default)
			)
			(layer "B.Fab")
		)
		(pad "1" smd rect
			(at 0.5334 0 90)
			(size 0.7112 0.6096)
			(layers "B.Cu" "B.Mask" "B.Paste")
			(net "FPGA_TCK")
		)
		(pad "2" smd rect
			(at -0.5334 0 90)
			(size 0.7112 0.6096)
			(layers "B.Cu" "B.Mask" "B.Paste")
			(net "SG")
		)
		(zone
			(layer "B.Cu")
			(hatch none 0.5)
			(connect_pads
				(clearance 0)
			)
			(min_thickness 0.25)
			(keepout
				(tracks allowed)
				(vias not_allowed)
				(pads allowed)
				(copperpour not_allowed)
				(footprints allowed)
			)
			(placement
				(enabled no)
				(sheetname "")
			)
			(fill
				(thermal_gap 0.5)
				(thermal_bridge_width 0.5)
				(island_removal_mode 0)
			)
			(polygon
				(pts
					(xy 138.1887 -67.4497) (xy 138.7983 -67.4497) (xy 138.7983 -67.6021) (xy 138.1887 -67.6021)
				)
			)
		)
		(zone
			(layer "B.Cu")
			(hatch none 0.5)
			(connect_pads
				(clearance 0)
			)
			(min_thickness 0.25)
			(keepout
				(tracks not_allowed)
				(vias allowed)
				(pads allowed)
				(copperpour not_allowed)
				(footprints allowed)
			)
			(placement
				(enabled no)
				(sheetname "")
			)
			(fill
				(thermal_gap 0.5)
				(thermal_bridge_width 0.5)
				(island_removal_mode 0)
			)
			(polygon
				(pts
					(xy 138.1887 -67.4497) (xy 138.7983 -67.4497) (xy 138.7983 -67.6021) (xy 138.1887 -67.6021)
				)
			)
		)
	)
	(footprint ""
		(layer "B.Cu")
		(at 145.8214 -97.9678 180)
		(property "Reference" "R10"
			(at -3.1496 0.03683 0)
			(unlocked yes)
			(layer "B.SilkS")
			(effects
				(font
					(size 0.7874 0.5842)
					(thickness 0.1524)
				)
				(justify mirror)
			)
		)
		(property "Value" "VAL*"
			(at -0.02032 2.13233 180)
			(unlocked yes)
			(layer "B.Fab")
			(hide yes)
			(effects
				(font
					(size 0.7874 0.5842)
					(thickness 0.1524)
				)
				(justify mirror)
			)
		)
		(property "Device Type" "RESISTOR-G155-11002-01,10KOHM,A"
			(at -0.008382 1.210564 180)
			(unlocked yes)
			(layer "B.Fab")
			(hide yes)
			(effects
				(font
					(size 0.7874 0.5842)
					(thickness 0.1524)
				)
				(justify mirror)
			)
		)
		(property "User Part Number" "PARTNUM*"
			(at -0.02032 4.024884 180)
			(unlocked yes)
			(layer "Cmts.User")
			(hide yes)
			(effects
				(font
					(size 0.7874 0.5842)
					(thickness 0.1524)
				)
				(justify mirror)
			)
		)
		(property "Tolerance" "TOL*"
			(at -0.044704 3.05435 180)
			(unlocked yes)
			(layer "Cmts.User")
			(hide yes)
			(effects
				(font
					(size 0.7874 0.5842)
					(thickness 0.1524)
				)
				(justify mirror)
			)
		)
		(duplicate_pad_numbers_are_jumpers no)
		(fp_line
			(start 1.143 0.5588)
			(end -1.143 0.5588)
			(stroke
				(width 0.1)
				(type default)
			)
			(layer "B.SilkS")
		)
		(fp_line
			(start 1.143 -0.5588)
			(end 1.143 0.5588)
			(stroke
				(width 0.1)
				(type default)
			)
			(layer "B.SilkS")
		)
		(fp_line
			(start -1.143 0.5588)
			(end -1.143 -0.5588)
			(stroke
				(width 0.1)
				(type default)
			)
			(layer "B.SilkS")
		)
		(fp_line
			(start -1.143 -0.5588)
			(end 1.143 -0.5588)
			(stroke
				(width 0.1)
				(type default)
			)
			(layer "B.SilkS")
		)
		(fp_rect
			(start 1.143 -0.5588)
			(end -1.143 0.5588)
			(stroke
				(width 0)
				(type default)
			)
			(fill no)
			(layer "B.CrtYd")
		)
		(fp_line
			(start 0.508 0.3048)
			(end -0.508 0.3048)
			(stroke
				(width 0.1)
				(type default)
			)
			(layer "B.Fab")
		)
		(fp_line
			(start 0.508 -0.3048)
			(end 0.508 0.3048)
			(stroke
				(width 0.1)
				(type default)
			)
			(layer "B.Fab")
		)
		(fp_line
			(start -0.508 0.3048)
			(end -0.508 -0.3048)
			(stroke
				(width 0.1)
				(type default)
			)
			(layer "B.Fab")
		)
		(fp_line
			(start -0.508 -0.3048)
			(end 0.508 -0.3048)
			(stroke
				(width 0.1)
				(type default)
			)
			(layer "B.Fab")
		)
		(pad "1" smd rect
			(at 0.5334 0)
			(size 0.7112 0.6096)
			(layers "B.Cu" "B.Mask" "B.Paste")
			(net "XP12R0V_A_IMON")
		)
		(pad "2" smd rect
			(at -0.5334 0)
			(size 0.7112 0.6096)
			(layers "B.Cu" "B.Mask" "B.Paste")
			(net "SG")
		)
		(zone
			(layer "B.Cu")
			(hatch none 0.5)
			(connect_pads
				(clearance 0)
			)
			(min_thickness 0.25)
			(keepout
				(tracks allowed)
				(vias not_allowed)
				(pads allowed)
				(copperpour not_allowed)
				(footprints allowed)
			)
			(placement
				(enabled no)
				(sheetname "")
			)
			(fill
				(thermal_gap 0.5)
				(thermal_bridge_width 0.5)
				(island_removal_mode 0)
			)
			(polygon
				(pts
					(xy 145.7452 -97.663) (xy 145.8976 -97.663) (xy 145.8976 -98.2726) (xy 145.7452 -98.2726)
				)
			)
		)
	)
	(footprint ""
		(layer "B.Cu")
		(at 99.346766 -54.823106)
		(property "Reference" "C216"
			(at -1.556766 -1.271524 0)
			(unlocked yes)
			(layer "B.SilkS")
			(effects
				(font
					(size 0.7874 0.5842)
					(thickness 0.1524)
				)
				(justify mirror)
			)
		)
		(property "Value" "VAL*"
			(at 0 3.718306 0)
			(unlocked yes)
			(layer "B.Fab")
			(hide yes)
			(effects
				(font
					(size 0.7874 0.5842)
					(thickness 0.127)
				)
				(justify mirror)
			)
		)
		(property "Tolerance" "TOL*"
			(at 0 4.861306 0)
			(unlocked yes)
			(layer "Cmts.User")
			(hide yes)
			(effects
				(font
					(size 0.7874 0.5842)
					(thickness 0.127)
				)
				(justify mirror)
			)
		)
		(property "User Part Number" "PARTNUM*"
			(at 0 2.575306 0)
			(unlocked yes)
			(layer "Cmts.User")
			(hide yes)
			(effects
				(font
					(size 0.7874 0.5842)
					(thickness 0.127)
				)
				(justify mirror)
			)
		)
		(property "Device Type" "CAPACITOR-G105-0B104-CK,0.1UF,A"
			(at 0 1.432306 0)
			(unlocked yes)
			(layer "B.Fab")
			(hide yes)
			(effects
				(font
					(size 0.7874 0.5842)
					(thickness 0.127)
				)
				(justify mirror)
			)
		)
		(duplicate_pad_numbers_are_jumpers no)
		(fp_line
			(start -0.970026 -0.4699)
			(end -0.970026 0.4699)
			(stroke
				(width 0.1)
				(type default)
			)
			(layer "B.SilkS")
		)
		(fp_line
			(start -0.970026 0.4699)
			(end 0.970026 0.4699)
			(stroke
				(width 0.1)
				(type default)
			)
			(layer "B.SilkS")
		)
		(fp_line
			(start 0.970026 -0.4699)
			(end -0.970026 -0.4699)
			(stroke
				(width 0.1)
				(type default)
			)
			(layer "B.SilkS")
		)
		(fp_line
			(start 0.970026 0.4699)
			(end 0.970026 -0.4699)
			(stroke
				(width 0.1)
				(type default)
			)
			(layer "B.SilkS")
		)
		(fp_poly
			(pts
				(xy 0.970026 0.4699) (xy -0.970026 0.4699) (xy -0.970026 -0.4699) (xy 0.970026 -0.4699)
			)
			(stroke
				(width 0)
				(type default)
			)
			(fill no)
			(layer "B.CrtYd")
		)
		(fp_line
			(start -0.508 -0.3048)
			(end -0.508 0.3048)
			(stroke
				(width 0.1)
				(type default)
			)
			(layer "B.Fab")
		)
		(fp_line
			(start -0.508 0.3048)
			(end 0.508 0.3048)
			(stroke
				(width 0.1)
				(type default)
			)
			(layer "B.Fab")
		)
		(fp_line
			(start 0.508 -0.3048)
			(end -0.508 -0.3048)
			(stroke
				(width 0.1)
				(type default)
			)
			(layer "B.Fab")
		)
		(fp_line
			(start 0.508 0.3048)
			(end 0.508 -0.3048)
			(stroke
				(width 0.1)
				(type default)
			)
			(layer "B.Fab")
		)
		(pad "1" smd circle
			(at 0.500126 0 180)
			(size 0.635 0.635)
			(layers "B.Cu" "B.Mask" "B.Paste")
			(net "XP3R3V_FPGA")
		)
		(pad "2" smd circle
			(at -0.500126 0 180)
			(size 0.635 0.635)
			(layers "B.Cu" "B.Mask" "B.Paste")
			(net "SG")
		)
	)
	(footprint ""
		(layer "B.Cu")
		(at 117.347238 -49.823116 180)
		(property "Reference" "C130"
			(at 0.634238 1.834134 0)
			(unlocked yes)
			(layer "B.SilkS")
			(effects
				(font
					(size 0.635 0.4064)
					(thickness 0.1524)
				)
				(justify mirror)
			)
		)
		(property "Value" "VAL*"
			(at 0 3.718306 180)
			(unlocked yes)
			(layer "B.Fab")
			(hide yes)
			(effects
				(font
					(size 0.7874 0.5842)
					(thickness 0.127)
				)
				(justify mirror)
			)
		)
		(property "Device Type" "CAPACITOR-G105-0B104-CK,0.1UF,A"
			(at 0 1.432306 180)
			(unlocked yes)
			(layer "B.Fab")
			(hide yes)
			(effects
				(font
					(size 0.7874 0.5842)
					(thickness 0.127)
				)
				(justify mirror)
			)
		)
		(property "User Part Number" "PARTNUM*"
			(at 0 2.575306 180)
			(unlocked yes)
			(layer "Cmts.User")
			(hide yes)
			(effects
				(font
					(size 0.7874 0.5842)
					(thickness 0.127)
				)
				(justify mirror)
			)
		)
		(property "Tolerance" "TOL*"
			(at 0 4.861306 180)
			(unlocked yes)
			(layer "Cmts.User")
			(hide yes)
			(effects
				(font
					(size 0.7874 0.5842)
					(thickness 0.127)
				)
				(justify mirror)
			)
		)
		(duplicate_pad_numbers_are_jumpers no)
		(fp_line
			(start 0.970026 0.4699)
			(end 0.970026 -0.4699)
			(stroke
				(width 0.1)
				(type default)
			)
			(layer "B.SilkS")
		)
		(fp_line
			(start 0.970026 -0.4699)
			(end -0.970026 -0.4699)
			(stroke
				(width 0.1)
				(type default)
			)
			(layer "B.SilkS")
		)
		(fp_line
			(start -0.970026 0.4699)
			(end 0.970026 0.4699)
			(stroke
				(width 0.1)
				(type default)
			)
			(layer "B.SilkS")
		)
		(fp_line
			(start -0.970026 -0.4699)
			(end -0.970026 0.4699)
			(stroke
				(width 0.1)
				(type default)
			)
			(layer "B.SilkS")
		)
		(fp_poly
			(pts
				(xy 0.970026 0.4699) (xy -0.970026 0.4699) (xy -0.970026 -0.4699) (xy 0.970026 -0.4699)
			)
			(stroke
				(width 0)
				(type default)
			)
			(fill no)
			(layer "B.CrtYd")
		)
		(fp_line
			(start 0.508 0.3048)
			(end 0.508 -0.3048)
			(stroke
				(width 0.1)
				(type default)
			)
			(layer "B.Fab")
		)
		(fp_line
			(start 0.508 -0.3048)
			(end -0.508 -0.3048)
			(stroke
				(width 0.1)
				(type default)
			)
			(layer "B.Fab")
		)
		(fp_line
			(start -0.508 0.3048)
			(end 0.508 0.3048)
			(stroke
				(width 0.1)
				(type default)
			)
			(layer "B.Fab")
		)
		(fp_line
			(start -0.508 -0.3048)
			(end -0.508 0.3048)
			(stroke
				(width 0.1)
				(type default)
			)
			(layer "B.Fab")
		)
		(pad "1" smd circle
			(at 0.500126 0)
			(size 0.635 0.635)
			(layers "B.Cu" "B.Mask" "B.Paste")
			(net "XP3R3V_FPGA")
		)
		(pad "2" smd circle
			(at -0.500126 0)
			(size 0.635 0.635)
			(layers "B.Cu" "B.Mask" "B.Paste")
			(net "SG")
		)
	)
	(footprint ""
		(layer "B.Cu")
		(at 140.2842 -69.1134)
		(property "Reference" "R133"
			(at -5.0292 -0.57023 0)
			(unlocked yes)
			(layer "B.SilkS")
			(effects
				(font
					(size 0.7874 0.5842)
					(thickness 0.1524)
				)
				(justify mirror)
			)
		)
		(property "Value" "VAL*"
			(at -0.02032 2.13233 0)
			(unlocked yes)
			(layer "B.Fab")
			(hide yes)
			(effects
				(font
					(size 0.7874 0.5842)
					(thickness 0.1524)
				)
				(justify mirror)
			)
		)
		(property "Tolerance" "TOL*"
			(at -0.044704 3.05435 0)
			(unlocked yes)
			(layer "Cmts.User")
			(hide yes)
			(effects
				(font
					(size 0.7874 0.5842)
					(thickness 0.1524)
				)
				(justify mirror)
			)
		)
		(property "User Part Number" "PARTNUM*"
			(at -0.02032 4.024884 0)
			(unlocked yes)
			(layer "Cmts.User")
			(hide yes)
			(effects
				(font
					(size 0.7874 0.5842)
					(thickness 0.1524)
				)
				(justify mirror)
			)
		)
		(property "Device Type" "RESISTOR-G155-133R0-01,33OHM,1%"
			(at -0.008382 1.210564 0)
			(unlocked yes)
			(layer "B.Fab")
			(hide yes)
			(effects
				(font
					(size 0.7874 0.5842)
					(thickness 0.1524)
				)
				(justify mirror)
			)
		)
		(duplicate_pad_numbers_are_jumpers no)
		(fp_line
			(start -1.143 -0.5588)
			(end 1.143 -0.5588)
			(stroke
				(width 0.1)
				(type default)
			)
			(layer "B.SilkS")
		)
		(fp_line
			(start -1.143 0.5588)
			(end -1.143 -0.5588)
			(stroke
				(width 0.1)
				(type default)
			)
			(layer "B.SilkS")
		)
		(fp_line
			(start 1.143 -0.5588)
			(end 1.143 0.5588)
			(stroke
				(width 0.1)
				(type default)
			)
			(layer "B.SilkS")
		)
		(fp_line
			(start 1.143 0.5588)
			(end -1.143 0.5588)
			(stroke
				(width 0.1)
				(type default)
			)
			(layer "B.SilkS")
		)
		(fp_rect
			(start 1.143 0.5588)
			(end -1.143 -0.5588)
			(stroke
				(width 0)
				(type default)
			)
			(fill no)
			(layer "B.CrtYd")
		)
		(fp_line
			(start -0.508 -0.3048)
			(end 0.508 -0.3048)
			(stroke
				(width 0.1)
				(type default)
			)
			(layer "B.Fab")
		)
		(fp_line
			(start -0.508 0.3048)
			(end -0.508 -0.3048)
			(stroke
				(width 0.1)
				(type default)
			)
			(layer "B.Fab")
		)
		(fp_line
			(start 0.508 -0.3048)
			(end 0.508 0.3048)
			(stroke
				(width 0.1)
				(type default)
			)
			(layer "B.Fab")
		)
		(fp_line
			(start 0.508 0.3048)
			(end -0.508 0.3048)
			(stroke
				(width 0.1)
				(type default)
			)
			(layer "B.Fab")
		)
		(pad "1" smd rect
			(at 0.5334 0 180)
			(size 0.7112 0.6096)
			(layers "B.Cu" "B.Mask" "B.Paste")
			(net "XP3R3V_FPGA")
		)
		(pad "2" smd rect
			(at -0.5334 0 180)
			(size 0.7112 0.6096)
			(layers "B.Cu" "B.Mask" "B.Paste")
			(net "UNNAMED_127_G2001028301_I427_4")
		)
		(zone
			(layer "B.Cu")
			(hatch none 0.5)
			(connect_pads
				(clearance 0)
			)
			(min_thickness 0.25)
			(keepout
				(tracks allowed)
				(vias not_allowed)
				(pads allowed)
				(copperpour not_allowed)
				(footprints allowed)
			)
			(placement
				(enabled no)
				(sheetname "")
			)
			(fill
				(thermal_gap 0.5)
				(thermal_bridge_width 0.5)
				(island_removal_mode 0)
			)
			(polygon
				(pts
					(xy 140.3604 -68.8086) (xy 140.3604 -69.4182) (xy 140.208 -69.4182) (xy 140.208 -68.8086)
				)
			)
		)
	)
	(footprint ""
		(layer "B.Cu")
		(at 110.998 -27.94 90)
		(property "Reference" "R355"
			(at -2.667 -0.03937 270)
			(unlocked yes)
			(layer "B.SilkS")
			(effects
				(font
					(size 0.7874 0.5842)
					(thickness 0.1524)
				)
				(justify mirror)
			)
		)
		(property "Value" "VAL*"
			(at -0.02032 2.13233 90)
			(unlocked yes)
			(layer "B.Fab")
			(hide yes)
			(effects
				(font
					(size 0.7874 0.5842)
					(thickness 0.1524)
				)
				(justify mirror)
			)
		)
		(property "Tolerance" "TOL*"
			(at -0.044704 3.05435 90)
			(unlocked yes)
			(layer "Cmts.User")
			(hide yes)
			(effects
				(font
					(size 0.7874 0.5842)
					(thickness 0.1524)
				)
				(justify mirror)
			)
		)
		(property "User Part Number" "PARTNUM*"
			(at -0.02032 4.024884 90)
			(unlocked yes)
			(layer "Cmts.User")
			(hide yes)
			(effects
				(font
					(size 0.7874 0.5842)
					(thickness 0.1524)
				)
				(justify mirror)
			)
		)
		(property "Device Type" "RESISTOR-G155-11002-01,10KOHM,A"
			(at -0.008382 1.210564 90)
			(unlocked yes)
			(layer "B.Fab")
			(hide yes)
			(effects
				(font
					(size 0.7874 0.5842)
					(thickness 0.1524)
				)
				(justify mirror)
			)
		)
		(duplicate_pad_numbers_are_jumpers no)
		(fp_line
			(start 1.143 -0.5588)
			(end 1.143 0.5588)
			(stroke
				(width 0.1)
				(type default)
			)
			(layer "B.SilkS")
		)
		(fp_line
			(start -1.143 -0.5588)
			(end 1.143 -0.5588)
			(stroke
				(width 0.1)
				(type default)
			)
			(layer "B.SilkS")
		)
		(fp_line
			(start 1.143 0.5588)
			(end -1.143 0.5588)
			(stroke
				(width 0.1)
				(type default)
			)
			(layer "B.SilkS")
		)
		(fp_line
			(start -1.143 0.5588)
			(end -1.143 -0.5588)
			(stroke
				(width 0.1)
				(type default)
			)
			(layer "B.SilkS")
		)
		(fp_poly
			(pts
				(xy 1.143 0.5588) (xy -1.143 0.5588) (xy -1.143 -0.5588) (xy 1.143 -0.5588)
			)
			(stroke
				(width 0)
				(type default)
			)
			(fill no)
			(layer "B.CrtYd")
		)
		(fp_line
			(start 0.508 -0.3048)
			(end 0.508 0.3048)
			(stroke
				(width 0.1)
				(type default)
			)
			(layer "B.Fab")
		)
		(fp_line
			(start -0.508 -0.3048)
			(end 0.508 -0.3048)
			(stroke
				(width 0.1)
				(type default)
			)
			(layer "B.Fab")
		)
		(fp_line
			(start 0.508 0.3048)
			(end -0.508 0.3048)
			(stroke
				(width 0.1)
				(type default)
			)
			(layer "B.Fab")
		)
		(fp_line
			(start -0.508 0.3048)
			(end -0.508 -0.3048)
			(stroke
				(width 0.1)
				(type default)
			)
			(layer "B.Fab")
		)
		(pad "1" smd rect
			(at 0.5334 0 270)
			(size 0.7112 0.6096)
			(layers "B.Cu" "B.Mask" "B.Paste")
			(net "MHZ200CLKN_CLKIN")
		)
		(pad "2" smd rect
			(at -0.5334 0 270)
			(size 0.7112 0.6096)
			(layers "B.Cu" "B.Mask" "B.Paste")
			(net "XP2R5V_FPGA")
		)
		(zone
			(layer "B.Cu")
			(hatch none 0.5)
			(connect_pads
				(clearance 0)
			)
			(min_thickness 0.25)
			(keepout
				(tracks allowed)
				(vias not_allowed)
				(pads allowed)
				(copperpour not_allowed)
				(footprints allowed)
			)
			(placement
				(enabled no)
				(sheetname "")
			)
			(fill
				(thermal_gap 0.5)
				(thermal_bridge_width 0.5)
				(island_removal_mode 0)
			)
			(polygon
				(pts
					(xy 111.3028 -28.0162) (xy 110.6932 -28.0162) (xy 110.6932 -27.8638) (xy 111.3028 -27.8638)
				)
			)
		)
		(zone
			(layer "B.Cu")
			(hatch none 0.5)
			(connect_pads
				(clearance 0)
			)
			(min_thickness 0.25)
			(keepout
				(tracks not_allowed)
				(vias allowed)
				(pads allowed)
				(copperpour not_allowed)
				(footprints allowed)
			)
			(placement
				(enabled no)
				(sheetname "")
			)
			(fill
				(thermal_gap 0.5)
				(thermal_bridge_width 0.5)
				(island_removal_mode 0)
			)
			(polygon
				(pts
					(xy 111.3028 -28.0162) (xy 110.6932 -28.0162) (xy 110.6932 -27.8638) (xy 111.3028 -27.8638)
				)
			)
		)
	)
	(footprint ""
		(layer "B.Cu")
		(at 90.2716 -47.916846 180)
		(property "Reference" "R106"
			(at -0.762 2.500884 0)
			(unlocked yes)
			(layer "B.SilkS")
			(effects
				(font
					(size 0.7874 0.5842)
					(thickness 0.1524)
				)
				(justify mirror)
			)
		)
		(property "Value" "VAL*"
			(at -0.02032 2.13233 180)
			(unlocked yes)
			(layer "B.Fab")
			(hide yes)
			(effects
				(font
					(size 0.7874 0.5842)
					(thickness 0.1524)
				)
				(justify mirror)
			)
		)
		(property "Tolerance" "TOL*"
			(at -0.044704 3.05435 180)
			(unlocked yes)
			(layer "Cmts.User")
			(hide yes)
			(effects
				(font
					(size 0.7874 0.5842)
					(thickness 0.1524)
				)
				(justify mirror)
			)
		)
		(property "User Part Number" "PARTNUM*"
			(at -0.02032 4.024884 180)
			(unlocked yes)
			(layer "Cmts.User")
			(hide yes)
			(effects
				(font
					(size 0.7874 0.5842)
					(thickness 0.1524)
				)
				(justify mirror)
			)
		)
		(property "Device Type" "RESISTOR-G155-100R0-J0,0OHM,-"
			(at -0.008382 1.210564 180)
			(unlocked yes)
			(layer "B.Fab")
			(hide yes)
			(effects
				(font
					(size 0.7874 0.5842)
					(thickness 0.1524)
				)
				(justify mirror)
			)
		)
		(duplicate_pad_numbers_are_jumpers no)
		(fp_line
			(start 1.143 0.5588)
			(end -1.143 0.5588)
			(stroke
				(width 0.1)
				(type default)
			)
			(layer "B.SilkS")
		)
		(fp_line
			(start 1.143 -0.5588)
			(end 1.143 0.5588)
			(stroke
				(width 0.1)
				(type default)
			)
			(layer "B.SilkS")
		)
		(fp_line
			(start -1.143 0.5588)
			(end -1.143 -0.5588)
			(stroke
				(width 0.1)
				(type default)
			)
			(layer "B.SilkS")
		)
		(fp_line
			(start -1.143 -0.5588)
			(end 1.143 -0.5588)
			(stroke
				(width 0.1)
				(type default)
			)
			(layer "B.SilkS")
		)
		(fp_rect
			(start 1.143 -0.5588)
			(end -1.143 0.5588)
			(stroke
				(width 0)
				(type default)
			)
			(fill no)
			(layer "B.CrtYd")
		)
		(fp_line
			(start 0.508 0.3048)
			(end -0.508 0.3048)
			(stroke
				(width 0.1)
				(type default)
			)
			(layer "B.Fab")
		)
		(fp_line
			(start 0.508 -0.3048)
			(end 0.508 0.3048)
			(stroke
				(width 0.1)
				(type default)
			)
			(layer "B.Fab")
		)
		(fp_line
			(start -0.508 0.3048)
			(end -0.508 -0.3048)
			(stroke
				(width 0.1)
				(type default)
			)
			(layer "B.Fab")
		)
		(fp_line
			(start -0.508 -0.3048)
			(end 0.508 -0.3048)
			(stroke
				(width 0.1)
				(type default)
			)
			(layer "B.Fab")
		)
		(pad "1" smd rect
			(at 0.5334 0)
			(size 0.7112 0.6096)
			(layers "B.Cu" "B.Mask" "B.Paste")
			(net "MUX_USB_DP")
		)
		(pad "2" smd rect
			(at -0.5334 0)
			(size 0.7112 0.6096)
			(layers "B.Cu" "B.Mask" "B.Paste")
			(net "MAC_USB_DP")
		)
		(zone
			(layer "B.Cu")
			(hatch none 0.5)
			(connect_pads
				(clearance 0)
			)
			(min_thickness 0.25)
			(keepout
				(tracks allowed)
				(vias not_allowed)
				(pads allowed)
				(copperpour not_allowed)
				(footprints allowed)
			)
			(placement
				(enabled no)
				(sheetname "")
			)
			(fill
				(thermal_gap 0.5)
				(thermal_bridge_width 0.5)
				(island_removal_mode 0)
			)
			(polygon
				(pts
					(xy 90.1954 -47.612046) (xy 90.3478 -47.612046) (xy 90.3478 -48.221646) (xy 90.1954 -48.221646)
				)
			)
		)
	)
	(footprint ""
		(layer "B.Cu")
		(at 18.415 -82.423 180)
		(property "Reference" "R478"
			(at -3.683 -0.42037 0)
			(unlocked yes)
			(layer "B.SilkS")
			(effects
				(font
					(size 0.7874 0.5842)
					(thickness 0.1524)
				)
				(justify mirror)
			)
		)
		(property "Value" "VAL*"
			(at -0.02032 2.13233 180)
			(unlocked yes)
			(layer "B.Fab")
			(hide yes)
			(effects
				(font
					(size 0.7874 0.5842)
					(thickness 0.1524)
				)
				(justify mirror)
			)
		)
		(property "Tolerance" "TOL*"
			(at -0.044704 3.05435 180)
			(unlocked yes)
			(layer "Cmts.User")
			(hide yes)
			(effects
				(font
					(size 0.7874 0.5842)
					(thickness 0.1524)
				)
				(justify mirror)
			)
		)
		(property "User Part Number" "PARTNUM*"
			(at -0.02032 4.024884 180)
			(unlocked yes)
			(layer "Cmts.User")
			(hide yes)
			(effects
				(font
					(size 0.7874 0.5842)
					(thickness 0.1524)
				)
				(justify mirror)
			)
		)
		(property "Device Type" "RESISTOR-G155-11003-01,100KOHMA"
			(at -0.008382 1.210564 180)
			(unlocked yes)
			(layer "B.Fab")
			(hide yes)
			(effects
				(font
					(size 0.7874 0.5842)
					(thickness 0.1524)
				)
				(justify mirror)
			)
		)
		(duplicate_pad_numbers_are_jumpers no)
		(fp_line
			(start 1.143 0.5588)
			(end -1.143 0.5588)
			(stroke
				(width 0.1)
				(type default)
			)
			(layer "B.SilkS")
		)
		(fp_line
			(start 1.143 -0.5588)
			(end 1.143 0.5588)
			(stroke
				(width 0.1)
				(type default)
			)
			(layer "B.SilkS")
		)
		(fp_line
			(start -1.143 0.5588)
			(end -1.143 -0.5588)
			(stroke
				(width 0.1)
				(type default)
			)
			(layer "B.SilkS")
		)
		(fp_line
			(start -1.143 -0.5588)
			(end 1.143 -0.5588)
			(stroke
				(width 0.1)
				(type default)
			)
			(layer "B.SilkS")
		)
		(fp_poly
			(pts
				(xy 1.143 0.5588) (xy -1.143 0.5588) (xy -1.143 -0.5588) (xy 1.143 -0.5588)
			)
			(stroke
				(width 0)
				(type default)
			)
			(fill no)
			(layer "B.CrtYd")
		)
		(fp_line
			(start 0.508 0.3048)
			(end -0.508 0.3048)
			(stroke
				(width 0.1)
				(type default)
			)
			(layer "B.Fab")
		)
		(fp_line
			(start 0.508 -0.3048)
			(end 0.508 0.3048)
			(stroke
				(width 0.1)
				(type default)
			)
			(layer "B.Fab")
		)
		(fp_line
			(start -0.508 0.3048)
			(end -0.508 -0.3048)
			(stroke
				(width 0.1)
				(type default)
			)
			(layer "B.Fab")
		)
		(fp_line
			(start -0.508 -0.3048)
			(end 0.508 -0.3048)
			(stroke
				(width 0.1)
				(type default)
			)
			(layer "B.Fab")
		)
		(pad "1" smd rect
			(at 0.5334 0)
			(size 0.7112 0.6096)
			(layers "B.Cu" "B.Mask" "B.Paste")
			(net "FT4232_I2C_SCL")
		)
		(pad "2" smd rect
			(at -0.5334 0)
			(size 0.7112 0.6096)
			(layers "B.Cu" "B.Mask" "B.Paste")
			(net "XP3R3V_FT4232")
		)
		(zone
			(layer "B.Cu")
			(hatch none 0.5)
			(connect_pads
				(clearance 0)
			)
			(min_thickness 0.25)
			(keepout
				(tracks not_allowed)
				(vias allowed)
				(pads allowed)
				(copperpour not_allowed)
				(footprints allowed)
			)
			(placement
				(enabled no)
				(sheetname "")
			)
			(fill
				(thermal_gap 0.5)
				(thermal_bridge_width 0.5)
				(island_removal_mode 0)
			)
			(polygon
				(pts
					(xy 18.3388 -82.7278) (xy 18.3388 -82.1182) (xy 18.4912 -82.1182) (xy 18.4912 -82.7278)
				)
			)
		)
		(zone
			(layer "B.Cu")
			(hatch none 0.5)
			(connect_pads
				(clearance 0)
			)
			(min_thickness 0.25)
			(keepout
				(tracks allowed)
				(vias not_allowed)
				(pads allowed)
				(copperpour not_allowed)
				(footprints allowed)
			)
			(placement
				(enabled no)
				(sheetname "")
			)
			(fill
				(thermal_gap 0.5)
				(thermal_bridge_width 0.5)
				(island_removal_mode 0)
			)
			(polygon
				(pts
					(xy 18.3388 -82.7278) (xy 18.3388 -82.1182) (xy 18.4912 -82.1182) (xy 18.4912 -82.7278)
				)
			)
		)
	)
	(footprint ""
		(layer "B.Cu")
		(at 17.7038 -40.6146 180)
		(property "Reference" "R144"
			(at 0.4318 1.12903 0)
			(unlocked yes)
			(layer "B.SilkS")
			(effects
				(font
					(size 0.7874 0.5842)
					(thickness 0.1524)
				)
				(justify mirror)
			)
		)
		(property "Value" "VAL*"
			(at -0.02032 2.13233 180)
			(unlocked yes)
			(layer "B.Fab")
			(hide yes)
			(effects
				(font
					(size 0.7874 0.5842)
					(thickness 0.1524)
				)
				(justify mirror)
			)
		)
		(property "Device Type" "RESISTOR-G155-133R0-01,33OHM,1%"
			(at -0.008382 1.210564 180)
			(unlocked yes)
			(layer "B.Fab")
			(hide yes)
			(effects
				(font
					(size 0.7874 0.5842)
					(thickness 0.1524)
				)
				(justify mirror)
			)
		)
		(property "User Part Number" "PARTNUM*"
			(at -0.02032 4.024884 180)
			(unlocked yes)
			(layer "Cmts.User")
			(hide yes)
			(effects
				(font
					(size 0.7874 0.5842)
					(thickness 0.1524)
				)
				(justify mirror)
			)
		)
		(property "Tolerance" "TOL*"
			(at -0.044704 3.05435 180)
			(unlocked yes)
			(layer "Cmts.User")
			(hide yes)
			(effects
				(font
					(size 0.7874 0.5842)
					(thickness 0.1524)
				)
				(justify mirror)
			)
		)
		(duplicate_pad_numbers_are_jumpers no)
		(fp_line
			(start 1.143 0.5588)
			(end -1.143 0.5588)
			(stroke
				(width 0.1)
				(type default)
			)
			(layer "B.SilkS")
		)
		(fp_line
			(start 1.143 -0.5588)
			(end 1.143 0.5588)
			(stroke
				(width 0.1)
				(type default)
			)
			(layer "B.SilkS")
		)
		(fp_line
			(start -1.143 0.5588)
			(end -1.143 -0.5588)
			(stroke
				(width 0.1)
				(type default)
			)
			(layer "B.SilkS")
		)
		(fp_line
			(start -1.143 -0.5588)
			(end 1.143 -0.5588)
			(stroke
				(width 0.1)
				(type default)
			)
			(layer "B.SilkS")
		)
		(fp_rect
			(start 1.143 0.5588)
			(end -1.143 -0.5588)
			(stroke
				(width 0)
				(type default)
			)
			(fill no)
			(layer "B.CrtYd")
		)
		(fp_line
			(start 0.508 0.3048)
			(end -0.508 0.3048)
			(stroke
				(width 0.1)
				(type default)
			)
			(layer "B.Fab")
		)
		(fp_line
			(start 0.508 -0.3048)
			(end 0.508 0.3048)
			(stroke
				(width 0.1)
				(type default)
			)
			(layer "B.Fab")
		)
		(fp_line
			(start -0.508 0.3048)
			(end -0.508 -0.3048)
			(stroke
				(width 0.1)
				(type default)
			)
			(layer "B.Fab")
		)
		(fp_line
			(start -0.508 -0.3048)
			(end 0.508 -0.3048)
			(stroke
				(width 0.1)
				(type default)
			)
			(layer "B.Fab")
		)
		(pad "1" smd rect
			(at 0.5334 0)
			(size 0.7112 0.6096)
			(layers "B.Cu" "B.Mask" "B.Paste")
			(net "PCA9546_I2C_SDA")
		)
		(pad "2" smd rect
			(at -0.5334 0)
			(size 0.7112 0.6096)
			(layers "B.Cu" "B.Mask" "B.Paste")
			(net "R_PCA9546_I2C_SDA")
		)
		(zone
			(layer "B.Cu")
			(hatch none 0.5)
			(connect_pads
				(clearance 0)
			)
			(min_thickness 0.25)
			(keepout
				(tracks allowed)
				(vias not_allowed)
				(pads allowed)
				(copperpour not_allowed)
				(footprints allowed)
			)
			(placement
				(enabled no)
				(sheetname "")
			)
			(fill
				(thermal_gap 0.5)
				(thermal_bridge_width 0.5)
				(island_removal_mode 0)
			)
			(polygon
				(pts
					(xy 17.6276 -40.9194) (xy 17.6276 -40.3098) (xy 17.78 -40.3098) (xy 17.78 -40.9194)
				)
			)
		)
	)
	(footprint ""
		(layer "B.Cu")
		(at 85.5472 -100.2538 180)
		(property "Reference" "SP2"
			(at 0.8382 -1.74117 0)
			(unlocked yes)
			(layer "B.SilkS")
			(effects
				(font
					(size 0.7874 0.5842)
					(thickness 0.1524)
				)
				(justify mirror)
			)
		)
		(property "Value" ""
			(at 0 0 0)
			(layer "B.Fab")
			(effects
				(font
					(size 1.27 1.27)
				)
				(justify mirror)
			)
		)
		(duplicate_pad_numbers_are_jumpers no)
		(fp_rect
			(start 0.1778 -0.3048)
			(end -0.1778 0.3048)
			(stroke
				(width 0)
				(type default)
			)
			(fill yes)
			(layer "B.Paste")
		)
		(fp_rect
			(start 0.2286 -0.3556)
			(end -0.2286 0.3556)
			(stroke
				(width 0)
				(type default)
			)
			(fill no)
			(layer "B.CrtYd")
		)
		(fp_line
			(start 0.1397 0.2413)
			(end 0.1397 -0.2413)
			(stroke
				(width 0.1)
				(type default)
			)
			(layer "B.Fab")
		)
		(fp_line
			(start 0.1397 -0.2413)
			(end -0.1397 -0.2413)
			(stroke
				(width 0.1)
				(type default)
			)
			(layer "B.Fab")
		)
		(fp_line
			(start -0.1397 0.2413)
			(end 0.1397 0.2413)
			(stroke
				(width 0.1)
				(type default)
			)
			(layer "B.Fab")
		)
		(fp_line
			(start -0.1397 -0.2413)
			(end -0.1397 0.2413)
			(stroke
				(width 0.1)
				(type default)
			)
			(layer "B.Fab")
		)
		(pad "1" smd rect
			(at 0.1143 0)
			(size 0.127 0.6096)
			(layers "B.Cu" "B.Mask" "B.Paste")
			(net "SG")
		)
		(pad "2" smd rect
			(at -0.1143 0)
			(size 0.127 0.6096)
			(layers "B.Cu" "B.Mask" "B.Paste")
			(net "XP3R3V_AGND")
		)
	)
	(footprint ""
		(layer "B.Cu")
		(at 112.141 -27.94 90)
		(property "Reference" "R358"
			(at -2.667 -0.16637 270)
			(unlocked yes)
			(layer "B.SilkS")
			(effects
				(font
					(size 0.7874 0.5842)
					(thickness 0.1524)
				)
				(justify mirror)
			)
		)
		(property "Value" "VAL*"
			(at -0.02032 2.13233 90)
			(unlocked yes)
			(layer "B.Fab")
			(hide yes)
			(effects
				(font
					(size 0.7874 0.5842)
					(thickness 0.1524)
				)
				(justify mirror)
			)
		)
		(property "Tolerance" "TOL*"
			(at -0.044704 3.05435 90)
			(unlocked yes)
			(layer "Cmts.User")
			(hide yes)
			(effects
				(font
					(size 0.7874 0.5842)
					(thickness 0.1524)
				)
				(justify mirror)
			)
		)
		(property "User Part Number" "PARTNUM*"
			(at -0.02032 4.024884 90)
			(unlocked yes)
			(layer "Cmts.User")
			(hide yes)
			(effects
				(font
					(size 0.7874 0.5842)
					(thickness 0.1524)
				)
				(justify mirror)
			)
		)
		(property "Device Type" "RESISTOR-G155-11002-01,10KOHM,A"
			(at -0.008382 1.210564 90)
			(unlocked yes)
			(layer "B.Fab")
			(hide yes)
			(effects
				(font
					(size 0.7874 0.5842)
					(thickness 0.1524)
				)
				(justify mirror)
			)
		)
		(duplicate_pad_numbers_are_jumpers no)
		(fp_line
			(start 1.143 -0.5588)
			(end 1.143 0.5588)
			(stroke
				(width 0.1)
				(type default)
			)
			(layer "B.SilkS")
		)
		(fp_line
			(start -1.143 -0.5588)
			(end 1.143 -0.5588)
			(stroke
				(width 0.1)
				(type default)
			)
			(layer "B.SilkS")
		)
		(fp_line
			(start 1.143 0.5588)
			(end -1.143 0.5588)
			(stroke
				(width 0.1)
				(type default)
			)
			(layer "B.SilkS")
		)
		(fp_line
			(start -1.143 0.5588)
			(end -1.143 -0.5588)
			(stroke
				(width 0.1)
				(type default)
			)
			(layer "B.SilkS")
		)
		(fp_poly
			(pts
				(xy 1.143 0.5588) (xy -1.143 0.5588) (xy -1.143 -0.5588) (xy 1.143 -0.5588)
			)
			(stroke
				(width 0)
				(type default)
			)
			(fill no)
			(layer "B.CrtYd")
		)
		(fp_line
			(start 0.508 -0.3048)
			(end 0.508 0.3048)
			(stroke
				(width 0.1)
				(type default)
			)
			(layer "B.Fab")
		)
		(fp_line
			(start -0.508 -0.3048)
			(end 0.508 -0.3048)
			(stroke
				(width 0.1)
				(type default)
			)
			(layer "B.Fab")
		)
		(fp_line
			(start 0.508 0.3048)
			(end -0.508 0.3048)
			(stroke
				(width 0.1)
				(type default)
			)
			(layer "B.Fab")
		)
		(fp_line
			(start -0.508 0.3048)
			(end -0.508 -0.3048)
			(stroke
				(width 0.1)
				(type default)
			)
			(layer "B.Fab")
		)
		(pad "1" smd rect
			(at 0.5334 0 270)
			(size 0.7112 0.6096)
			(layers "B.Cu" "B.Mask" "B.Paste")
			(net "MHZ200CLKP_CLKIN")
		)
		(pad "2" smd rect
			(at -0.5334 0 270)
			(size 0.7112 0.6096)
			(layers "B.Cu" "B.Mask" "B.Paste")
			(net "XP2R5V_FPGA")
		)
		(zone
			(layer "B.Cu")
			(hatch none 0.5)
			(connect_pads
				(clearance 0)
			)
			(min_thickness 0.25)
			(keepout
				(tracks allowed)
				(vias not_allowed)
				(pads allowed)
				(copperpour not_allowed)
				(footprints allowed)
			)
			(placement
				(enabled no)
				(sheetname "")
			)
			(fill
				(thermal_gap 0.5)
				(thermal_bridge_width 0.5)
				(island_removal_mode 0)
			)
			(polygon
				(pts
					(xy 112.4458 -28.0162) (xy 111.8362 -28.0162) (xy 111.8362 -27.8638) (xy 112.4458 -27.8638)
				)
			)
		)
		(zone
			(layer "B.Cu")
			(hatch none 0.5)
			(connect_pads
				(clearance 0)
			)
			(min_thickness 0.25)
			(keepout
				(tracks not_allowed)
				(vias allowed)
				(pads allowed)
				(copperpour not_allowed)
				(footprints allowed)
			)
			(placement
				(enabled no)
				(sheetname "")
			)
			(fill
				(thermal_gap 0.5)
				(thermal_bridge_width 0.5)
				(island_removal_mode 0)
			)
			(polygon
				(pts
					(xy 112.4458 -28.0162) (xy 111.8362 -28.0162) (xy 111.8362 -27.8638) (xy 112.4458 -27.8638)
				)
			)
		)
	)
	(footprint ""
		(layer "B.Cu")
		(at 27.686 -88.519 -90)
		(property "Reference" "L4"
			(at 2.286 0.03937 270)
			(unlocked yes)
			(layer "B.SilkS")
			(effects
				(font
					(size 0.7874 0.5842)
					(thickness 0.1524)
				)
				(justify mirror)
			)
		)
		(property "Value" "VAL*"
			(at -0.014732 2.526538 270)
			(unlocked yes)
			(layer "B.Fab")
			(hide yes)
			(effects
				(font
					(size 0.7874 0.5842)
					(thickness 0.000001)
				)
				(justify mirror)
			)
		)
		(property "Tolerance" "TOL*"
			(at -0.014732 3.503676 270)
			(unlocked yes)
			(layer "Cmts.User")
			(hide yes)
			(effects
				(font
					(size 0.7874 0.5842)
					(thickness 0.000001)
				)
				(justify mirror)
			)
		)
		(property "User Part Number" "PARTNUM*"
			(at -0.02794 4.480814 270)
			(unlocked yes)
			(layer "Cmts.User")
			(hide yes)
			(effects
				(font
					(size 0.7874 0.5842)
					(thickness 0.000001)
				)
				(justify mirror)
			)
		)
		(property "Device Type" "FERRITEBEAD-G191-10097-01,600OA"
			(at -0.014732 1.600708 270)
			(unlocked yes)
			(layer "B.Fab")
			(hide yes)
			(effects
				(font
					(size 0.7874 0.5842)
					(thickness 0.000001)
				)
				(justify mirror)
			)
		)
		(duplicate_pad_numbers_are_jumpers no)
		(fp_line
			(start -1.3208 0.7112)
			(end 1.3208 0.7112)
			(stroke
				(width 0.1)
				(type default)
			)
			(layer "B.SilkS")
		)
		(fp_line
			(start 1.3208 0.7112)
			(end 1.3208 -0.7112)
			(stroke
				(width 0.1)
				(type default)
			)
			(layer "B.SilkS")
		)
		(fp_line
			(start -1.3208 -0.7112)
			(end -1.3208 0.7112)
			(stroke
				(width 0.1)
				(type default)
			)
			(layer "B.SilkS")
		)
		(fp_line
			(start 1.3208 -0.7112)
			(end -1.3208 -0.7112)
			(stroke
				(width 0.1)
				(type default)
			)
			(layer "B.SilkS")
		)
		(fp_rect
			(start 1.3208 0.7112)
			(end -1.3208 -0.7112)
			(stroke
				(width 0)
				(type default)
			)
			(fill no)
			(layer "B.CrtYd")
		)
		(fp_line
			(start -0.8128 0.4572)
			(end 0.8128 0.4572)
			(stroke
				(width 0.1)
				(type default)
			)
			(layer "B.Fab")
		)
		(fp_line
			(start 0.8128 0.4572)
			(end 0.8128 -0.4572)
			(stroke
				(width 0.1)
				(type default)
			)
			(layer "B.Fab")
		)
		(fp_line
			(start -0.8128 -0.4572)
			(end -0.8128 0.4572)
			(stroke
				(width 0.1)
				(type default)
			)
			(layer "B.Fab")
		)
		(fp_line
			(start 0.8128 -0.4572)
			(end -0.8128 -0.4572)
			(stroke
				(width 0.1)
				(type default)
			)
			(layer "B.Fab")
		)
		(pad "1" smd rect
			(at 0.6858 0 90)
			(size 0.762 0.8636)
			(layers "B.Cu" "B.Mask" "B.Paste")
			(net "XP3R3V_FT4232")
		)
		(pad "2" smd rect
			(at -0.6858 0 90)
			(size 0.762 0.8636)
			(layers "B.Cu" "B.Mask" "B.Paste")
			(net "XP3R3V_VPLL")
		)
		(zone
			(layer "B.Cu")
			(hatch none 0.5)
			(connect_pads
				(clearance 0)
			)
			(min_thickness 0.25)
			(keepout
				(tracks not_allowed)
				(vias allowed)
				(pads allowed)
				(copperpour not_allowed)
				(footprints allowed)
			)
			(placement
				(enabled no)
				(sheetname "")
			)
			(fill
				(thermal_gap 0.5)
				(thermal_bridge_width 0.5)
				(island_removal_mode 0)
			)
			(polygon
				(pts
					(xy 27.2288 -88.3666) (xy 28.1432 -88.3666) (xy 28.1432 -88.6714) (xy 27.2288 -88.6714)
				)
			)
		)
		(zone
			(layer "B.Cu")
			(hatch none 0.5)
			(connect_pads
				(clearance 0)
			)
			(min_thickness 0.25)
			(keepout
				(tracks allowed)
				(vias not_allowed)
				(pads allowed)
				(copperpour not_allowed)
				(footprints allowed)
			)
			(placement
				(enabled no)
				(sheetname "")
			)
			(fill
				(thermal_gap 0.5)
				(thermal_bridge_width 0.5)
				(island_removal_mode 0)
			)
			(polygon
				(pts
					(xy 27.2288 -88.3666) (xy 28.1432 -88.3666) (xy 28.1432 -88.6714) (xy 27.2288 -88.6714)
				)
			)
		)
	)
	(footprint ""
		(layer "B.Cu")
		(at 77.089 -73.152 -90)
		(property "Reference" "C282"
			(at -3.556 0.03937 270)
			(unlocked yes)
			(layer "B.SilkS")
			(effects
				(font
					(size 0.7874 0.5842)
					(thickness 0.1524)
				)
				(justify mirror)
			)
		)
		(property "Value" "VAL*"
			(at -0.0762 3.134106 270)
			(unlocked yes)
			(layer "B.Fab")
			(hide yes)
			(effects
				(font
					(size 0.7874 0.5842)
					(thickness 0.1524)
				)
				(justify mirror)
			)
		)
		(property "Device Type" "CAPACITOR-G107-0F106-EM,10UF,2A"
			(at -0.0508 2.194306 270)
			(unlocked yes)
			(layer "B.Fab")
			(hide yes)
			(effects
				(font
					(size 0.7874 0.5842)
					(thickness 0.1524)
				)
				(justify mirror)
			)
		)
		(property "User Part Number" "PARTNUM*"
			(at -0.1016 5.013706 270)
			(unlocked yes)
			(layer "Cmts.User")
			(hide yes)
			(effects
				(font
					(size 0.7874 0.5842)
					(thickness 0.1524)
				)
				(justify mirror)
			)
		)
		(property "Tolerance" "TOL*"
			(at -0.0762 4.048506 270)
			(unlocked yes)
			(layer "Cmts.User")
			(hide yes)
			(effects
				(font
					(size 0.7874 0.5842)
					(thickness 0.1524)
				)
				(justify mirror)
			)
		)
		(duplicate_pad_numbers_are_jumpers no)
		(fp_line
			(start -1.5748 0.9398)
			(end -1.5748 -0.9398)
			(stroke
				(width 0.1)
				(type default)
			)
			(layer "B.SilkS")
		)
		(fp_line
			(start 1.5748 0.9398)
			(end -1.5748 0.9398)
			(stroke
				(width 0.1)
				(type default)
			)
			(layer "B.SilkS")
		)
		(fp_line
			(start -1.5748 -0.9398)
			(end 1.5748 -0.9398)
			(stroke
				(width 0.1)
				(type default)
			)
			(layer "B.SilkS")
		)
		(fp_line
			(start 1.5748 -0.9398)
			(end 1.5748 0.9398)
			(stroke
				(width 0.1)
				(type default)
			)
			(layer "B.SilkS")
		)
		(fp_rect
			(start 1.5748 -0.9398)
			(end -1.5748 0.9398)
			(stroke
				(width 0)
				(type default)
			)
			(fill no)
			(layer "B.CrtYd")
		)
		(fp_line
			(start -1.016 0.635)
			(end -1.016 -0.635)
			(stroke
				(width 0.1)
				(type default)
			)
			(layer "B.Fab")
		)
		(fp_line
			(start 1.016 0.635)
			(end -1.016 0.635)
			(stroke
				(width 0.1)
				(type default)
			)
			(layer "B.Fab")
		)
		(fp_line
			(start -1.016 -0.635)
			(end 1.016 -0.635)
			(stroke
				(width 0.1)
				(type default)
			)
			(layer "B.Fab")
		)
		(fp_line
			(start 1.016 -0.635)
			(end 1.016 0.635)
			(stroke
				(width 0.1)
				(type default)
			)
			(layer "B.Fab")
		)
		(pad "1" smd rect
			(at 0.8382 0 90)
			(size 0.9652 1.3716)
			(layers "B.Cu" "B.Mask" "B.Paste")
			(net "XP5R0V_MAC")
		)
		(pad "2" smd rect
			(at -0.8382 0 90)
			(size 0.9652 1.3716)
			(layers "B.Cu" "B.Mask" "B.Paste")
			(net "SG")
		)
		(zone
			(layer "B.Cu")
			(hatch none 0.5)
			(connect_pads
				(clearance 0)
			)
			(min_thickness 0.25)
			(keepout
				(tracks allowed)
				(vias not_allowed)
				(pads allowed)
				(copperpour not_allowed)
				(footprints allowed)
			)
			(placement
				(enabled no)
				(sheetname "")
			)
			(fill
				(thermal_gap 0.5)
				(thermal_bridge_width 0.5)
				(island_removal_mode 0)
			)
			(polygon
				(pts
					(xy 77.724 -72.9234) (xy 77.724 -73.3806) (xy 76.454 -73.3806) (xy 76.454 -72.9234)
				)
			)
		)
	)
	(footprint ""
		(layer "B.Cu")
		(at 138.4808 -77.216 90)
		(property "Reference" "R405"
			(at 1.778 -1.10617 270)
			(unlocked yes)
			(layer "B.SilkS")
			(effects
				(font
					(size 0.7874 0.5842)
					(thickness 0.1524)
				)
				(justify mirror)
			)
		)
		(property "Value" "VAL*"
			(at -0.02032 2.13233 90)
			(unlocked yes)
			(layer "B.Fab")
			(hide yes)
			(effects
				(font
					(size 0.7874 0.5842)
					(thickness 0.1524)
				)
				(justify mirror)
			)
		)
		(property "Device Type" "RESISTOR-G155-11002-01,10KOHM,A"
			(at -0.008382 1.210564 90)
			(unlocked yes)
			(layer "B.Fab")
			(hide yes)
			(effects
				(font
					(size 0.7874 0.5842)
					(thickness 0.1524)
				)
				(justify mirror)
			)
		)
		(property "User Part Number" "PARTNUM*"
			(at -0.02032 4.024884 90)
			(unlocked yes)
			(layer "Cmts.User")
			(hide yes)
			(effects
				(font
					(size 0.7874 0.5842)
					(thickness 0.1524)
				)
				(justify mirror)
			)
		)
		(property "Tolerance" "TOL*"
			(at -0.044704 3.05435 90)
			(unlocked yes)
			(layer "Cmts.User")
			(hide yes)
			(effects
				(font
					(size 0.7874 0.5842)
					(thickness 0.1524)
				)
				(justify mirror)
			)
		)
		(duplicate_pad_numbers_are_jumpers no)
		(fp_line
			(start 1.143 -0.5588)
			(end 1.143 0.5588)
			(stroke
				(width 0.1)
				(type default)
			)
			(layer "B.SilkS")
		)
		(fp_line
			(start -1.143 -0.5588)
			(end 1.143 -0.5588)
			(stroke
				(width 0.1)
				(type default)
			)
			(layer "B.SilkS")
		)
		(fp_line
			(start 1.143 0.5588)
			(end -1.143 0.5588)
			(stroke
				(width 0.1)
				(type default)
			)
			(layer "B.SilkS")
		)
		(fp_line
			(start -1.143 0.5588)
			(end -1.143 -0.5588)
			(stroke
				(width 0.1)
				(type default)
			)
			(layer "B.SilkS")
		)
		(fp_rect
			(start 1.143 0.5588)
			(end -1.143 -0.5588)
			(stroke
				(width 0)
				(type default)
			)
			(fill no)
			(layer "B.CrtYd")
		)
		(fp_line
			(start 0.508 -0.3048)
			(end 0.508 0.3048)
			(stroke
				(width 0.1)
				(type default)
			)
			(layer "B.Fab")
		)
		(fp_line
			(start -0.508 -0.3048)
			(end 0.508 -0.3048)
			(stroke
				(width 0.1)
				(type default)
			)
			(layer "B.Fab")
		)
		(fp_line
			(start 0.508 0.3048)
			(end -0.508 0.3048)
			(stroke
				(width 0.1)
				(type default)
			)
			(layer "B.Fab")
		)
		(fp_line
			(start -0.508 0.3048)
			(end -0.508 -0.3048)
			(stroke
				(width 0.1)
				(type default)
			)
			(layer "B.Fab")
		)
		(pad "1" smd rect
			(at 0.5334 0 270)
			(size 0.7112 0.6096)
			(layers "B.Cu" "B.Mask" "B.Paste")
			(net "XP3R3V_FPGA")
		)
		(pad "2" smd rect
			(at -0.5334 0 270)
			(size 0.7112 0.6096)
			(layers "B.Cu" "B.Mask" "B.Paste")
			(net "FPGA_TDI")
		)
		(zone
			(layer "B.Cu")
			(hatch none 0.5)
			(connect_pads
				(clearance 0)
			)
			(min_thickness 0.25)
			(keepout
				(tracks not_allowed)
				(vias allowed)
				(pads allowed)
				(copperpour not_allowed)
				(footprints allowed)
			)
			(placement
				(enabled no)
				(sheetname "")
			)
			(fill
				(thermal_gap 0.5)
				(thermal_bridge_width 0.5)
				(island_removal_mode 0)
			)
			(polygon
				(pts
					(xy 138.7856 -77.2922) (xy 138.176 -77.2922) (xy 138.176 -77.1398) (xy 138.7856 -77.1398)
				)
			)
		)
		(zone
			(layer "B.Cu")
			(hatch none 0.5)
			(connect_pads
				(clearance 0)
			)
			(min_thickness 0.25)
			(keepout
				(tracks allowed)
				(vias not_allowed)
				(pads allowed)
				(copperpour not_allowed)
				(footprints allowed)
			)
			(placement
				(enabled no)
				(sheetname "")
			)
			(fill
				(thermal_gap 0.5)
				(thermal_bridge_width 0.5)
				(island_removal_mode 0)
			)
			(polygon
				(pts
					(xy 138.7856 -77.2922) (xy 138.176 -77.2922) (xy 138.176 -77.1398) (xy 138.7856 -77.1398)
				)
			)
		)
	)
	(footprint ""
		(layer "B.Cu")
		(at 99.846892 -53.322982 90)
		(property "Reference" "C140"
			(at 1.414018 1.086358 270)
			(unlocked yes)
			(layer "B.SilkS")
			(effects
				(font
					(size 0.635 0.4064)
					(thickness 0.1524)
				)
				(justify mirror)
			)
		)
		(property "Value" "VAL*"
			(at 0 3.718306 90)
			(unlocked yes)
			(layer "B.Fab")
			(hide yes)
			(effects
				(font
					(size 0.7874 0.5842)
					(thickness 0.127)
				)
				(justify mirror)
			)
		)
		(property "Tolerance" "TOL*"
			(at 0 4.861306 90)
			(unlocked yes)
			(layer "Cmts.User")
			(hide yes)
			(effects
				(font
					(size 0.7874 0.5842)
					(thickness 0.127)
				)
				(justify mirror)
			)
		)
		(property "User Part Number" "PARTNUM*"
			(at 0 2.575306 90)
			(unlocked yes)
			(layer "Cmts.User")
			(hide yes)
			(effects
				(font
					(size 0.7874 0.5842)
					(thickness 0.127)
				)
				(justify mirror)
			)
		)
		(property "Device Type" "CAPACITOR-G105-0B104-CK,0.1UF,A"
			(at 0 1.432306 90)
			(unlocked yes)
			(layer "B.Fab")
			(hide yes)
			(effects
				(font
					(size 0.7874 0.5842)
					(thickness 0.127)
				)
				(justify mirror)
			)
		)
		(duplicate_pad_numbers_are_jumpers no)
		(fp_line
			(start 0.970026 -0.4699)
			(end -0.970026 -0.4699)
			(stroke
				(width 0.1)
				(type default)
			)
			(layer "B.SilkS")
		)
		(fp_line
			(start -0.970026 -0.4699)
			(end -0.970026 0.4699)
			(stroke
				(width 0.1)
				(type default)
			)
			(layer "B.SilkS")
		)
		(fp_line
			(start 0.970026 0.4699)
			(end 0.970026 -0.4699)
			(stroke
				(width 0.1)
				(type default)
			)
			(layer "B.SilkS")
		)
		(fp_line
			(start -0.970026 0.4699)
			(end 0.970026 0.4699)
			(stroke
				(width 0.1)
				(type default)
			)
			(layer "B.SilkS")
		)
		(fp_poly
			(pts
				(xy 0.970026 0.4699) (xy -0.970026 0.4699) (xy -0.970026 -0.4699) (xy 0.970026 -0.4699)
			)
			(stroke
				(width 0)
				(type default)
			)
			(fill no)
			(layer "B.CrtYd")
		)
		(fp_line
			(start 0.508 -0.3048)
			(end -0.508 -0.3048)
			(stroke
				(width 0.1)
				(type default)
			)
			(layer "B.Fab")
		)
		(fp_line
			(start -0.508 -0.3048)
			(end -0.508 0.3048)
			(stroke
				(width 0.1)
				(type default)
			)
			(layer "B.Fab")
		)
		(fp_line
			(start 0.508 0.3048)
			(end 0.508 -0.3048)
			(stroke
				(width 0.1)
				(type default)
			)
			(layer "B.Fab")
		)
		(fp_line
			(start -0.508 0.3048)
			(end 0.508 0.3048)
			(stroke
				(width 0.1)
				(type default)
			)
			(layer "B.Fab")
		)
		(pad "1" smd circle
			(at 0.500126 0 270)
			(size 0.635 0.635)
			(layers "B.Cu" "B.Mask" "B.Paste")
			(net "XP3R3V_FPGA")
		)
		(pad "2" smd circle
			(at -0.500126 0 270)
			(size 0.635 0.635)
			(layers "B.Cu" "B.Mask" "B.Paste")
			(net "SG")
		)
	)
	(footprint ""
		(layer "B.Cu")
		(at 95.631 -85.598)
		(property "Reference" "R201"
			(at -0.254 -5.54863 0)
			(unlocked yes)
			(layer "B.SilkS")
			(effects
				(font
					(size 0.7874 0.5842)
					(thickness 0.1524)
				)
				(justify mirror)
			)
		)
		(property "Value" "VAL*"
			(at -0.02032 2.13233 0)
			(unlocked yes)
			(layer "B.Fab")
			(hide yes)
			(effects
				(font
					(size 0.7874 0.5842)
					(thickness 0.1524)
				)
				(justify mirror)
			)
		)
		(property "Tolerance" "TOL*"
			(at -0.044704 3.05435 0)
			(unlocked yes)
			(layer "Cmts.User")
			(hide yes)
			(effects
				(font
					(size 0.7874 0.5842)
					(thickness 0.1524)
				)
				(justify mirror)
			)
		)
		(property "User Part Number" "PARTNUM*"
			(at -0.02032 4.024884 0)
			(unlocked yes)
			(layer "Cmts.User")
			(hide yes)
			(effects
				(font
					(size 0.7874 0.5842)
					(thickness 0.1524)
				)
				(justify mirror)
			)
		)
		(property "Device Type" "RESISTOR-G155-14701-01,4.7KOHMA"
			(at -0.008382 1.210564 0)
			(unlocked yes)
			(layer "B.Fab")
			(hide yes)
			(effects
				(font
					(size 0.7874 0.5842)
					(thickness 0.1524)
				)
				(justify mirror)
			)
		)
		(duplicate_pad_numbers_are_jumpers no)
		(fp_line
			(start -1.143 -0.5588)
			(end 1.143 -0.5588)
			(stroke
				(width 0.1)
				(type default)
			)
			(layer "B.SilkS")
		)
		(fp_line
			(start -1.143 0.5588)
			(end -1.143 -0.5588)
			(stroke
				(width 0.1)
				(type default)
			)
			(layer "B.SilkS")
		)
		(fp_line
			(start 1.143 -0.5588)
			(end 1.143 0.5588)
			(stroke
				(width 0.1)
				(type default)
			)
			(layer "B.SilkS")
		)
		(fp_line
			(start 1.143 0.5588)
			(end -1.143 0.5588)
			(stroke
				(width 0.1)
				(type default)
			)
			(layer "B.SilkS")
		)
		(fp_rect
			(start -1.143 0.5588)
			(end 1.143 -0.5588)
			(stroke
				(width 0)
				(type default)
			)
			(fill no)
			(layer "B.CrtYd")
		)
		(fp_line
			(start -0.508 -0.3048)
			(end 0.508 -0.3048)
			(stroke
				(width 0.1)
				(type default)
			)
			(layer "B.Fab")
		)
		(fp_line
			(start -0.508 0.3048)
			(end -0.508 -0.3048)
			(stroke
				(width 0.1)
				(type default)
			)
			(layer "B.Fab")
		)
		(fp_line
			(start 0.508 -0.3048)
			(end 0.508 0.3048)
			(stroke
				(width 0.1)
				(type default)
			)
			(layer "B.Fab")
		)
		(fp_line
			(start 0.508 0.3048)
			(end -0.508 0.3048)
			(stroke
				(width 0.1)
				(type default)
			)
			(layer "B.Fab")
		)
		(pad "1" smd rect
			(at 0.5334 0 180)
			(size 0.7112 0.6096)
			(layers "B.Cu" "B.Mask" "B.Paste")
			(net "UNNAMED_127_MT25QL128ABA1ESES_3")
		)
		(pad "2" smd rect
			(at -0.5334 0 180)
			(size 0.7112 0.6096)
			(layers "B.Cu" "B.Mask" "B.Paste")
			(net "XP3R3V_FPGA")
		)
		(zone
			(layer "B.Cu")
			(hatch none 0.5)
			(connect_pads
				(clearance 0)
			)
			(min_thickness 0.25)
			(keepout
				(tracks allowed)
				(vias not_allowed)
				(pads allowed)
				(copperpour not_allowed)
				(footprints allowed)
			)
			(placement
				(enabled no)
				(sheetname "")
			)
			(fill
				(thermal_gap 0.5)
				(thermal_bridge_width 0.5)
				(island_removal_mode 0)
			)
			(polygon
				(pts
					(xy 95.5548 -85.2932) (xy 95.7072 -85.2932) (xy 95.7072 -85.9028) (xy 95.5548 -85.9028)
				)
			)
		)
	)
	(footprint ""
		(layer "B.Cu")
		(at 124.587 -50.165)
		(property "Reference" "R265"
			(at 3.302 0.03937 0)
			(unlocked yes)
			(layer "B.SilkS")
			(effects
				(font
					(size 0.7874 0.5842)
					(thickness 0.1524)
				)
				(justify mirror)
			)
		)
		(property "Value" "VAL*"
			(at -0.02032 2.13233 0)
			(unlocked yes)
			(layer "B.Fab")
			(hide yes)
			(effects
				(font
					(size 0.7874 0.5842)
					(thickness 0.1524)
				)
				(justify mirror)
			)
		)
		(property "Device Type" "RESISTOR-G155-11003-01,100KOHMA"
			(at -0.008382 1.210564 0)
			(unlocked yes)
			(layer "B.Fab")
			(hide yes)
			(effects
				(font
					(size 0.7874 0.5842)
					(thickness 0.1524)
				)
				(justify mirror)
			)
		)
		(property "User Part Number" "PARTNUM*"
			(at -0.02032 4.024884 0)
			(unlocked yes)
			(layer "Cmts.User")
			(hide yes)
			(effects
				(font
					(size 0.7874 0.5842)
					(thickness 0.1524)
				)
				(justify mirror)
			)
		)
		(property "Tolerance" "TOL*"
			(at -0.044704 3.05435 0)
			(unlocked yes)
			(layer "Cmts.User")
			(hide yes)
			(effects
				(font
					(size 0.7874 0.5842)
					(thickness 0.1524)
				)
				(justify mirror)
			)
		)
		(duplicate_pad_numbers_are_jumpers no)
		(fp_line
			(start -1.143 -0.5588)
			(end 1.143 -0.5588)
			(stroke
				(width 0.1)
				(type default)
			)
			(layer "B.SilkS")
		)
		(fp_line
			(start -1.143 0.5588)
			(end -1.143 -0.5588)
			(stroke
				(width 0.1)
				(type default)
			)
			(layer "B.SilkS")
		)
		(fp_line
			(start 1.143 -0.5588)
			(end 1.143 0.5588)
			(stroke
				(width 0.1)
				(type default)
			)
			(layer "B.SilkS")
		)
		(fp_line
			(start 1.143 0.5588)
			(end -1.143 0.5588)
			(stroke
				(width 0.1)
				(type default)
			)
			(layer "B.SilkS")
		)
		(fp_rect
			(start -1.143 -0.5588)
			(end 1.143 0.5588)
			(stroke
				(width 0)
				(type default)
			)
			(fill no)
			(layer "B.CrtYd")
		)
		(fp_line
			(start -0.508 -0.3048)
			(end 0.508 -0.3048)
			(stroke
				(width 0.1)
				(type default)
			)
			(layer "B.Fab")
		)
		(fp_line
			(start -0.508 0.3048)
			(end -0.508 -0.3048)
			(stroke
				(width 0.1)
				(type default)
			)
			(layer "B.Fab")
		)
		(fp_line
			(start 0.508 -0.3048)
			(end 0.508 0.3048)
			(stroke
				(width 0.1)
				(type default)
			)
			(layer "B.Fab")
		)
		(fp_line
			(start 0.508 0.3048)
			(end -0.508 0.3048)
			(stroke
				(width 0.1)
				(type default)
			)
			(layer "B.Fab")
		)
		(pad "1" smd rect
			(at 0.5334 0 180)
			(size 0.7112 0.6096)
			(layers "B.Cu" "B.Mask" "B.Paste")
			(net "XP3R3V_FPGA")
		)
		(pad "2" smd rect
			(at -0.5334 0 180)
			(size 0.7112 0.6096)
			(layers "B.Cu" "B.Mask" "B.Paste")
			(net "UART_MAC_TX_FPGA_RX")
		)
		(zone
			(layer "B.Cu")
			(hatch none 0.5)
			(connect_pads
				(clearance 0)
			)
			(min_thickness 0.25)
			(keepout
				(tracks allowed)
				(vias not_allowed)
				(pads allowed)
				(copperpour not_allowed)
				(footprints allowed)
			)
			(placement
				(enabled no)
				(sheetname "")
			)
			(fill
				(thermal_gap 0.5)
				(thermal_bridge_width 0.5)
				(island_removal_mode 0)
			)
			(polygon
				(pts
					(xy 124.5108 -50.4698) (xy 124.5108 -49.8602) (xy 124.6632 -49.8602) (xy 124.6632 -50.4698)
				)
			)
		)
		(zone
			(layer "B.Cu")
			(hatch none 0.5)
			(connect_pads
				(clearance 0)
			)
			(min_thickness 0.25)
			(keepout
				(tracks not_allowed)
				(vias allowed)
				(pads allowed)
				(copperpour not_allowed)
				(footprints allowed)
			)
			(placement
				(enabled no)
				(sheetname "")
			)
			(fill
				(thermal_gap 0.5)
				(thermal_bridge_width 0.5)
				(island_removal_mode 0)
			)
			(polygon
				(pts
					(xy 124.5108 -50.4698) (xy 124.5108 -49.8602) (xy 124.6632 -49.8602) (xy 124.6632 -50.4698)
				)
			)
		)
	)
	(footprint ""
		(layer "B.Cu")
		(at 146.685 -19.685 90)
		(property "Reference" "R225"
			(at 2.794 -0.03937 270)
			(unlocked yes)
			(layer "B.SilkS")
			(effects
				(font
					(size 0.7874 0.5842)
					(thickness 0.1524)
				)
				(justify mirror)
			)
		)
		(property "Value" "VAL*"
			(at -0.02032 2.13233 90)
			(unlocked yes)
			(layer "B.Fab")
			(hide yes)
			(effects
				(font
					(size 0.7874 0.5842)
					(thickness 0.1524)
				)
				(justify mirror)
			)
		)
		(property "Tolerance" "TOL*"
			(at -0.044704 3.05435 90)
			(unlocked yes)
			(layer "Cmts.User")
			(hide yes)
			(effects
				(font
					(size 0.7874 0.5842)
					(thickness 0.1524)
				)
				(justify mirror)
			)
		)
		(property "User Part Number" "PARTNUM*"
			(at -0.02032 4.024884 90)
			(unlocked yes)
			(layer "Cmts.User")
			(hide yes)
			(effects
				(font
					(size 0.7874 0.5842)
					(thickness 0.1524)
				)
				(justify mirror)
			)
		)
		(property "Device Type" "RESISTOR-G155-13300-01,330OHM,A"
			(at -0.008382 1.210564 90)
			(unlocked yes)
			(layer "B.Fab")
			(hide yes)
			(effects
				(font
					(size 0.7874 0.5842)
					(thickness 0.1524)
				)
				(justify mirror)
			)
		)
		(duplicate_pad_numbers_are_jumpers no)
		(fp_line
			(start 1.143 -0.5588)
			(end 1.143 0.5588)
			(stroke
				(width 0.1)
				(type default)
			)
			(layer "B.SilkS")
		)
		(fp_line
			(start -1.143 -0.5588)
			(end 1.143 -0.5588)
			(stroke
				(width 0.1)
				(type default)
			)
			(layer "B.SilkS")
		)
		(fp_line
			(start 1.143 0.5588)
			(end -1.143 0.5588)
			(stroke
				(width 0.1)
				(type default)
			)
			(layer "B.SilkS")
		)
		(fp_line
			(start -1.143 0.5588)
			(end -1.143 -0.5588)
			(stroke
				(width 0.1)
				(type default)
			)
			(layer "B.SilkS")
		)
		(fp_rect
			(start 1.143 -0.5588)
			(end -1.143 0.5588)
			(stroke
				(width 0)
				(type default)
			)
			(fill no)
			(layer "B.CrtYd")
		)
		(fp_line
			(start 0.508 -0.3048)
			(end 0.508 0.3048)
			(stroke
				(width 0.1)
				(type default)
			)
			(layer "B.Fab")
		)
		(fp_line
			(start -0.508 -0.3048)
			(end 0.508 -0.3048)
			(stroke
				(width 0.1)
				(type default)
			)
			(layer "B.Fab")
		)
		(fp_line
			(start 0.508 0.3048)
			(end -0.508 0.3048)
			(stroke
				(width 0.1)
				(type default)
			)
			(layer "B.Fab")
		)
		(fp_line
			(start -0.508 0.3048)
			(end -0.508 -0.3048)
			(stroke
				(width 0.1)
				(type default)
			)
			(layer "B.Fab")
		)
		(pad "1" smd rect
			(at 0.5334 0 270)
			(size 0.7112 0.6096)
			(layers "B.Cu" "B.Mask" "B.Paste")
			(net "XP1R8V_FPGA_PG")
		)
		(pad "2" smd rect
			(at -0.5334 0 270)
			(size 0.7112 0.6096)
			(layers "B.Cu" "B.Mask" "B.Paste")
			(net "UNNAMED_515_CAPACITOR_I128_1")
		)
		(zone
			(layer "B.Cu")
			(hatch none 0.5)
			(connect_pads
				(clearance 0)
			)
			(min_thickness 0.25)
			(keepout
				(tracks allowed)
				(vias not_allowed)
				(pads allowed)
				(copperpour not_allowed)
				(footprints allowed)
			)
			(placement
				(enabled no)
				(sheetname "")
			)
			(fill
				(thermal_gap 0.5)
				(thermal_bridge_width 0.5)
				(island_removal_mode 0)
			)
			(polygon
				(pts
					(xy 146.3802 -19.7612) (xy 146.3802 -19.6088) (xy 146.9898 -19.6088) (xy 146.9898 -19.7612)
				)
			)
		)
	)
	(footprint ""
		(layer "B.Cu")
		(at 115.443 -72.263 180)
		(property "Reference" "C229"
			(at 0.127 -2.45237 0)
			(unlocked yes)
			(layer "B.SilkS")
			(effects
				(font
					(size 0.7874 0.5842)
					(thickness 0.1524)
				)
				(justify mirror)
			)
		)
		(property "Value" "VAL*"
			(at -0.0762 2.067306 180)
			(unlocked yes)
			(layer "B.Fab")
			(hide yes)
			(effects
				(font
					(size 0.7874 0.5842)
					(thickness 0.1524)
				)
				(justify mirror)
			)
		)
		(property "Tolerance" "TOL*"
			(at -0.0762 3.032506 180)
			(unlocked yes)
			(layer "Cmts.User")
			(hide yes)
			(effects
				(font
					(size 0.7874 0.5842)
					(thickness 0.1524)
				)
				(justify mirror)
			)
		)
		(property "User Part Number" "PARTNUM*"
			(at -0.1016 4.023106 180)
			(unlocked yes)
			(layer "Cmts.User")
			(hide yes)
			(effects
				(font
					(size 0.7874 0.5842)
					(thickness 0.1524)
				)
				(justify mirror)
			)
		)
		(property "Device Type" "CAPACITOR-G105-0B104-CK,0.1UF,A"
			(at -0.0508 1.127506 180)
			(unlocked yes)
			(layer "B.Fab")
			(hide yes)
			(effects
				(font
					(size 0.7874 0.5842)
					(thickness 0.1524)
				)
				(justify mirror)
			)
		)
		(duplicate_pad_numbers_are_jumpers no)
		(fp_line
			(start 1.143 0.5588)
			(end -1.143 0.5588)
			(stroke
				(width 0.1)
				(type default)
			)
			(layer "B.SilkS")
		)
		(fp_line
			(start 1.143 -0.5588)
			(end 1.143 0.5588)
			(stroke
				(width 0.1)
				(type default)
			)
			(layer "B.SilkS")
		)
		(fp_line
			(start -1.143 0.5588)
			(end -1.143 -0.5588)
			(stroke
				(width 0.1)
				(type default)
			)
			(layer "B.SilkS")
		)
		(fp_line
			(start -1.143 -0.5588)
			(end 1.143 -0.5588)
			(stroke
				(width 0.1)
				(type default)
			)
			(layer "B.SilkS")
		)
		(fp_rect
			(start 1.143 0.5588)
			(end -1.143 -0.5588)
			(stroke
				(width 0)
				(type default)
			)
			(fill no)
			(layer "B.CrtYd")
		)
		(fp_line
			(start 0.508 0.3048)
			(end -0.508 0.3048)
			(stroke
				(width 0.1)
				(type default)
			)
			(layer "B.Fab")
		)
		(fp_line
			(start 0.508 -0.3048)
			(end 0.508 0.3048)
			(stroke
				(width 0.1)
				(type default)
			)
			(layer "B.Fab")
		)
		(fp_line
			(start -0.508 0.3048)
			(end -0.508 -0.3048)
			(stroke
				(width 0.1)
				(type default)
			)
			(layer "B.Fab")
		)
		(fp_line
			(start -0.508 -0.3048)
			(end 0.508 -0.3048)
			(stroke
				(width 0.1)
				(type default)
			)
			(layer "B.Fab")
		)
		(pad "1" smd rect
			(at 0.5334 0)
			(size 0.7112 0.6096)
			(layers "B.Cu" "B.Mask" "B.Paste")
			(net "XP3R3V_FPGA_EN_R")
		)
		(pad "2" smd rect
			(at -0.5334 0)
			(size 0.7112 0.6096)
			(layers "B.Cu" "B.Mask" "B.Paste")
			(net "SG")
		)
		(zone
			(layer "B.Cu")
			(hatch none 0.5)
			(connect_pads
				(clearance 0)
			)
			(min_thickness 0.25)
			(keepout
				(tracks allowed)
				(vias not_allowed)
				(pads allowed)
				(copperpour not_allowed)
				(footprints allowed)
			)
			(placement
				(enabled no)
				(sheetname "")
			)
			(fill
				(thermal_gap 0.5)
				(thermal_bridge_width 0.5)
				(island_removal_mode 0)
			)
			(polygon
				(pts
					(xy 115.3668 -72.5678) (xy 115.3668 -71.9582) (xy 115.5192 -71.9582) (xy 115.5192 -72.5678)
				)
			)
		)
	)
	(footprint ""
		(layer "B.Cu")
		(at 101.847142 -41.323006 90)
		(property "Reference" "C131"
			(at -0.937006 -42.061892 270)
			(unlocked yes)
			(layer "B.SilkS")
			(effects
				(font
					(size 0.635 0.4064)
					(thickness 0.1524)
				)
				(justify mirror)
			)
		)
		(property "Value" "VAL*"
			(at 0 3.718306 90)
			(unlocked yes)
			(layer "B.Fab")
			(hide yes)
			(effects
				(font
					(size 0.7874 0.5842)
					(thickness 0.127)
				)
				(justify mirror)
			)
		)
		(property "Tolerance" "TOL*"
			(at 0 4.861306 90)
			(unlocked yes)
			(layer "Cmts.User")
			(hide yes)
			(effects
				(font
					(size 0.7874 0.5842)
					(thickness 0.127)
				)
				(justify mirror)
			)
		)
		(property "User Part Number" "PARTNUM*"
			(at 0 2.575306 90)
			(unlocked yes)
			(layer "Cmts.User")
			(hide yes)
			(effects
				(font
					(size 0.7874 0.5842)
					(thickness 0.127)
				)
				(justify mirror)
			)
		)
		(property "Device Type" "CAPACITOR-G105-0F475-BM,4.7UF,A"
			(at 0 1.432306 90)
			(unlocked yes)
			(layer "B.Fab")
			(hide yes)
			(effects
				(font
					(size 0.7874 0.5842)
					(thickness 0.127)
				)
				(justify mirror)
			)
		)
		(duplicate_pad_numbers_are_jumpers no)
		(fp_line
			(start 0.970026 -0.4699)
			(end -0.970026 -0.4699)
			(stroke
				(width 0.1)
				(type default)
			)
			(layer "B.SilkS")
		)
		(fp_line
			(start -0.970026 -0.4699)
			(end -0.970026 0.4699)
			(stroke
				(width 0.1)
				(type default)
			)
			(layer "B.SilkS")
		)
		(fp_line
			(start 0.970026 0.4699)
			(end 0.970026 -0.4699)
			(stroke
				(width 0.1)
				(type default)
			)
			(layer "B.SilkS")
		)
		(fp_line
			(start -0.970026 0.4699)
			(end 0.970026 0.4699)
			(stroke
				(width 0.1)
				(type default)
			)
			(layer "B.SilkS")
		)
		(fp_poly
			(pts
				(xy 0.970026 0.4699) (xy -0.970026 0.4699) (xy -0.970026 -0.4699) (xy 0.970026 -0.4699)
			)
			(stroke
				(width 0)
				(type default)
			)
			(fill no)
			(layer "B.CrtYd")
		)
		(fp_line
			(start 0.508 -0.3048)
			(end -0.508 -0.3048)
			(stroke
				(width 0.1)
				(type default)
			)
			(layer "B.Fab")
		)
		(fp_line
			(start -0.508 -0.3048)
			(end -0.508 0.3048)
			(stroke
				(width 0.1)
				(type default)
			)
			(layer "B.Fab")
		)
		(fp_line
			(start 0.508 0.3048)
			(end 0.508 -0.3048)
			(stroke
				(width 0.1)
				(type default)
			)
			(layer "B.Fab")
		)
		(fp_line
			(start -0.508 0.3048)
			(end 0.508 0.3048)
			(stroke
				(width 0.1)
				(type default)
			)
			(layer "B.Fab")
		)
		(pad "1" smd circle
			(at 0.500126 0 270)
			(size 0.635 0.635)
			(layers "B.Cu" "B.Mask" "B.Paste")
			(net "XP1R0V_FPGA_MGTAVCC")
		)
		(pad "2" smd circle
			(at -0.500126 0 270)
			(size 0.635 0.635)
			(layers "B.Cu" "B.Mask" "B.Paste")
			(net "SG")
		)
	)
	(footprint ""
		(layer "B.Cu")
		(at 139.6492 -87.4014)
		(property "Reference" "C301"
			(at 0.3048 -5.01523 0)
			(unlocked yes)
			(layer "B.SilkS")
			(effects
				(font
					(size 0.7874 0.5842)
					(thickness 0.1524)
				)
				(justify mirror)
			)
		)
		(property "Value" "VAL*"
			(at -0.0762 3.134106 0)
			(unlocked yes)
			(layer "B.Fab")
			(hide yes)
			(effects
				(font
					(size 0.7874 0.5842)
					(thickness 0.1524)
				)
				(justify mirror)
			)
		)
		(property "Tolerance" "TOL*"
			(at -0.0762 4.048506 0)
			(unlocked yes)
			(layer "Cmts.User")
			(hide yes)
			(effects
				(font
					(size 0.7874 0.5842)
					(thickness 0.1524)
				)
				(justify mirror)
			)
		)
		(property "User Part Number" "PARTNUM*"
			(at -0.1016 5.013706 0)
			(unlocked yes)
			(layer "Cmts.User")
			(hide yes)
			(effects
				(font
					(size 0.7874 0.5842)
					(thickness 0.1524)
				)
				(justify mirror)
			)
		)
		(property "Device Type" "CAPACITOR-G107-0F106-EM,10UF,2A"
			(at -0.0508 2.194306 0)
			(unlocked yes)
			(layer "B.Fab")
			(hide yes)
			(effects
				(font
					(size 0.7874 0.5842)
					(thickness 0.1524)
				)
				(justify mirror)
			)
		)
		(duplicate_pad_numbers_are_jumpers no)
		(fp_line
			(start -1.5748 -0.9398)
			(end 1.5748 -0.9398)
			(stroke
				(width 0.1)
				(type default)
			)
			(layer "B.SilkS")
		)
		(fp_line
			(start -1.5748 0.9398)
			(end -1.5748 -0.9398)
			(stroke
				(width 0.1)
				(type default)
			)
			(layer "B.SilkS")
		)
		(fp_line
			(start 1.5748 -0.9398)
			(end 1.5748 0.9398)
			(stroke
				(width 0.1)
				(type default)
			)
			(layer "B.SilkS")
		)
		(fp_line
			(start 1.5748 0.9398)
			(end -1.5748 0.9398)
			(stroke
				(width 0.1)
				(type default)
			)
			(layer "B.SilkS")
		)
		(fp_rect
			(start 1.5748 0.9398)
			(end -1.5748 -0.9398)
			(stroke
				(width 0)
				(type default)
			)
			(fill no)
			(layer "B.CrtYd")
		)
		(fp_line
			(start -1.016 -0.635)
			(end 1.016 -0.635)
			(stroke
				(width 0.1)
				(type default)
			)
			(layer "B.Fab")
		)
		(fp_line
			(start -1.016 0.635)
			(end -1.016 -0.635)
			(stroke
				(width 0.1)
				(type default)
			)
			(layer "B.Fab")
		)
		(fp_line
			(start 1.016 -0.635)
			(end 1.016 0.635)
			(stroke
				(width 0.1)
				(type default)
			)
			(layer "B.Fab")
		)
		(fp_line
			(start 1.016 0.635)
			(end -1.016 0.635)
			(stroke
				(width 0.1)
				(type default)
			)
			(layer "B.Fab")
		)
		(pad "1" smd rect
			(at 0.8382 0 180)
			(size 0.9652 1.3716)
			(layers "B.Cu" "B.Mask" "B.Paste")
			(net "XP12R0V_IN")
		)
		(pad "2" smd rect
			(at -0.8382 0 180)
			(size 0.9652 1.3716)
			(layers "B.Cu" "B.Mask" "B.Paste")
			(net "SG")
		)
		(zone
			(layer "B.Cu")
			(hatch none 0.5)
			(connect_pads
				(clearance 0)
			)
			(min_thickness 0.25)
			(keepout
				(tracks not_allowed)
				(vias allowed)
				(pads allowed)
				(copperpour not_allowed)
				(footprints allowed)
			)
			(placement
				(enabled no)
				(sheetname "")
			)
			(fill
				(thermal_gap 0.5)
				(thermal_bridge_width 0.5)
				(island_removal_mode 0)
			)
			(polygon
				(pts
					(xy 139.8778 -86.7664) (xy 139.8778 -88.0364) (xy 139.4206 -88.0364) (xy 139.4206 -86.7664)
				)
			)
		)
		(zone
			(layer "B.Cu")
			(hatch none 0.5)
			(connect_pads
				(clearance 0)
			)
			(min_thickness 0.25)
			(keepout
				(tracks allowed)
				(vias not_allowed)
				(pads allowed)
				(copperpour not_allowed)
				(footprints allowed)
			)
			(placement
				(enabled no)
				(sheetname "")
			)
			(fill
				(thermal_gap 0.5)
				(thermal_bridge_width 0.5)
				(island_removal_mode 0)
			)
			(polygon
				(pts
					(xy 139.8778 -86.7664) (xy 139.8778 -88.0364) (xy 139.4206 -88.0364) (xy 139.4206 -86.7664)
				)
			)
		)
	)
	(footprint ""
		(layer "B.Cu")
		(at 108.458 -20.447 90)
		(property "Reference" "L14"
			(at 0.635 1.48463 270)
			(unlocked yes)
			(layer "B.SilkS")
			(effects
				(font
					(size 0.7874 0.5842)
					(thickness 0.1524)
				)
				(justify mirror)
			)
		)
		(property "Value" "VAL*"
			(at -0.014732 2.526538 90)
			(unlocked yes)
			(layer "B.Fab")
			(hide yes)
			(effects
				(font
					(size 0.7874 0.5842)
					(thickness 0.000001)
				)
				(justify mirror)
			)
		)
		(property "Tolerance" "TOL*"
			(at -0.014732 3.503676 90)
			(unlocked yes)
			(layer "Cmts.User")
			(hide yes)
			(effects
				(font
					(size 0.7874 0.5842)
					(thickness 0.000001)
				)
				(justify mirror)
			)
		)
		(property "User Part Number" "PARTNUM*"
			(at -0.02794 4.480814 90)
			(unlocked yes)
			(layer "Cmts.User")
			(hide yes)
			(effects
				(font
					(size 0.7874 0.5842)
					(thickness 0.000001)
				)
				(justify mirror)
			)
		)
		(property "Device Type" "FERRITEBEAD-G191-10097-01,600OA"
			(at -0.014732 1.600708 90)
			(unlocked yes)
			(layer "B.Fab")
			(hide yes)
			(effects
				(font
					(size 0.7874 0.5842)
					(thickness 0.000001)
				)
				(justify mirror)
			)
		)
		(duplicate_pad_numbers_are_jumpers no)
		(fp_line
			(start 1.3208 -0.7112)
			(end -1.3208 -0.7112)
			(stroke
				(width 0.1)
				(type default)
			)
			(layer "B.SilkS")
		)
		(fp_line
			(start -1.3208 -0.7112)
			(end -1.3208 0.7112)
			(stroke
				(width 0.1)
				(type default)
			)
			(layer "B.SilkS")
		)
		(fp_line
			(start 1.3208 0.7112)
			(end 1.3208 -0.7112)
			(stroke
				(width 0.1)
				(type default)
			)
			(layer "B.SilkS")
		)
		(fp_line
			(start -1.3208 0.7112)
			(end 1.3208 0.7112)
			(stroke
				(width 0.1)
				(type default)
			)
			(layer "B.SilkS")
		)
		(fp_rect
			(start 1.3208 0.7112)
			(end -1.3208 -0.7112)
			(stroke
				(width 0)
				(type default)
			)
			(fill no)
			(layer "B.CrtYd")
		)
		(fp_line
			(start 0.8128 -0.4572)
			(end -0.8128 -0.4572)
			(stroke
				(width 0.1)
				(type default)
			)
			(layer "B.Fab")
		)
		(fp_line
			(start -0.8128 -0.4572)
			(end -0.8128 0.4572)
			(stroke
				(width 0.1)
				(type default)
			)
			(layer "B.Fab")
		)
		(fp_line
			(start 0.8128 0.4572)
			(end 0.8128 -0.4572)
			(stroke
				(width 0.1)
				(type default)
			)
			(layer "B.Fab")
		)
		(fp_line
			(start -0.8128 0.4572)
			(end 0.8128 0.4572)
			(stroke
				(width 0.1)
				(type default)
			)
			(layer "B.Fab")
		)
		(pad "1" smd rect
			(at 0.6858 0 270)
			(size 0.762 0.8636)
			(layers "B.Cu" "B.Mask" "B.Paste")
			(net "VDD3V3_OSC_200M")
		)
		(pad "2" smd rect
			(at -0.6858 0 270)
			(size 0.762 0.8636)
			(layers "B.Cu" "B.Mask" "B.Paste")
			(net "XP3R3V")
		)
		(zone
			(layer "B.Cu")
			(hatch none 0.5)
			(connect_pads
				(clearance 0)
			)
			(min_thickness 0.25)
			(keepout
				(tracks allowed)
				(vias not_allowed)
				(pads allowed)
				(copperpour not_allowed)
				(footprints allowed)
			)
			(placement
				(enabled no)
				(sheetname "")
			)
			(fill
				(thermal_gap 0.5)
				(thermal_bridge_width 0.5)
				(island_removal_mode 0)
			)
			(polygon
				(pts
					(xy 108.9152 -20.5994) (xy 108.0008 -20.5994) (xy 108.0008 -20.2946) (xy 108.9152 -20.2946)
				)
			)
		)
		(zone
			(layer "B.Cu")
			(hatch none 0.5)
			(connect_pads
				(clearance 0)
			)
			(min_thickness 0.25)
			(keepout
				(tracks not_allowed)
				(vias allowed)
				(pads allowed)
				(copperpour not_allowed)
				(footprints allowed)
			)
			(placement
				(enabled no)
				(sheetname "")
			)
			(fill
				(thermal_gap 0.5)
				(thermal_bridge_width 0.5)
				(island_removal_mode 0)
			)
			(polygon
				(pts
					(xy 108.9152 -20.5994) (xy 108.0008 -20.5994) (xy 108.0008 -20.2946) (xy 108.9152 -20.2946)
				)
			)
		)
	)
	(footprint ""
		(layer "B.Cu")
		(at 46.736 -104.902 180)
		(property "Reference" "R33"
			(at 0.1778 1.61163 0)
			(unlocked yes)
			(layer "B.SilkS")
			(effects
				(font
					(size 0.7874 0.5842)
					(thickness 0.1524)
				)
				(justify mirror)
			)
		)
		(property "Value" "VAL*"
			(at -0.0508 3.159506 180)
			(unlocked yes)
			(layer "B.Fab")
			(hide yes)
			(effects
				(font
					(size 0.7874 0.5842)
					(thickness 0.1524)
				)
				(justify mirror)
			)
		)
		(property "Tolerance" "TOL*"
			(at -0.0508 4.124706 180)
			(unlocked yes)
			(layer "Cmts.User")
			(hide yes)
			(effects
				(font
					(size 0.7874 0.5842)
					(thickness 0.1524)
				)
				(justify mirror)
			)
		)
		(property "User Part Number" "PARTNUM*"
			(at -0.0508 5.089906 180)
			(unlocked yes)
			(layer "Cmts.User")
			(hide yes)
			(effects
				(font
					(size 0.7874 0.5842)
					(thickness 0.1524)
				)
				(justify mirror)
			)
		)
		(property "Device Type" "RESISTOR-G157-12R20-01,2.2OHM,A"
			(at 0 2.194306 180)
			(unlocked yes)
			(layer "B.Fab")
			(hide yes)
			(effects
				(font
					(size 0.7874 0.5842)
					(thickness 0.1524)
				)
				(justify mirror)
			)
		)
		(duplicate_pad_numbers_are_jumpers no)
		(fp_line
			(start 1.5748 0.9398)
			(end -1.5748 0.9398)
			(stroke
				(width 0.1)
				(type default)
			)
			(layer "B.SilkS")
		)
		(fp_line
			(start 1.5748 -0.9398)
			(end 1.5748 0.9398)
			(stroke
				(width 0.1)
				(type default)
			)
			(layer "B.SilkS")
		)
		(fp_line
			(start -1.5748 0.9398)
			(end -1.5748 -0.9398)
			(stroke
				(width 0.1)
				(type default)
			)
			(layer "B.SilkS")
		)
		(fp_line
			(start -1.5748 -0.9398)
			(end 1.5748 -0.9398)
			(stroke
				(width 0.1)
				(type default)
			)
			(layer "B.SilkS")
		)
		(fp_rect
			(start -1.5748 0.9398)
			(end 1.5748 -0.9398)
			(stroke
				(width 0)
				(type default)
			)
			(fill no)
			(layer "B.CrtYd")
		)
		(fp_line
			(start 1.016 0.635)
			(end -1.016 0.635)
			(stroke
				(width 0.1)
				(type default)
			)
			(layer "B.Fab")
		)
		(fp_line
			(start 1.016 -0.635)
			(end 1.016 0.635)
			(stroke
				(width 0.1)
				(type default)
			)
			(layer "B.Fab")
		)
		(fp_line
			(start -1.016 0.635)
			(end -1.016 -0.635)
			(stroke
				(width 0.1)
				(type default)
			)
			(layer "B.Fab")
		)
		(fp_line
			(start -1.016 -0.635)
			(end 1.016 -0.635)
			(stroke
				(width 0.1)
				(type default)
			)
			(layer "B.Fab")
		)
		(pad "1" smd rect
			(at 0.8382 0)
			(size 0.9652 1.3716)
			(layers "B.Cu" "B.Mask" "B.Paste")
			(net "UNNAMED_516_CAPACITOR_I37_2")
		)
		(pad "2" smd rect
			(at -0.8382 0)
			(size 0.9652 1.3716)
			(layers "B.Cu" "B.Mask" "B.Paste")
			(net "SG")
		)
		(zone
			(layer "B.Cu")
			(hatch none 0.5)
			(connect_pads
				(clearance 0)
			)
			(min_thickness 0.25)
			(keepout
				(tracks allowed)
				(vias not_allowed)
				(pads allowed)
				(copperpour not_allowed)
				(footprints allowed)
			)
			(placement
				(enabled no)
				(sheetname "")
			)
			(fill
				(thermal_gap 0.5)
				(thermal_bridge_width 0.5)
				(island_removal_mode 0)
			)
			(polygon
				(pts
					(xy 46.9646 -105.537) (xy 46.5074 -105.537) (xy 46.5074 -104.267) (xy 46.9646 -104.267)
				)
			)
		)
	)
	(footprint ""
		(layer "B.Cu")
		(at 106.847132 -38.323012 90)
		(property "Reference" "C169"
			(at -1.269492 -41.509442 270)
			(unlocked yes)
			(layer "B.SilkS")
			(effects
				(font
					(size 0.635 0.4064)
					(thickness 0.1524)
				)
				(justify mirror)
			)
		)
		(property "Value" "VAL*"
			(at 0 3.718306 90)
			(unlocked yes)
			(layer "B.Fab")
			(hide yes)
			(effects
				(font
					(size 0.7874 0.5842)
					(thickness 0.127)
				)
				(justify mirror)
			)
		)
		(property "Device Type" "CAPACITOR-G105-0B104-CK,0.1UF,A"
			(at 0 1.432306 90)
			(unlocked yes)
			(layer "B.Fab")
			(hide yes)
			(effects
				(font
					(size 0.7874 0.5842)
					(thickness 0.127)
				)
				(justify mirror)
			)
		)
		(property "User Part Number" "PARTNUM*"
			(at 0 2.575306 90)
			(unlocked yes)
			(layer "Cmts.User")
			(hide yes)
			(effects
				(font
					(size 0.7874 0.5842)
					(thickness 0.127)
				)
				(justify mirror)
			)
		)
		(property "Tolerance" "TOL*"
			(at 0 4.861306 90)
			(unlocked yes)
			(layer "Cmts.User")
			(hide yes)
			(effects
				(font
					(size 0.7874 0.5842)
					(thickness 0.127)
				)
				(justify mirror)
			)
		)
		(duplicate_pad_numbers_are_jumpers no)
		(fp_line
			(start 0.970026 -0.4699)
			(end -0.970026 -0.4699)
			(stroke
				(width 0.1)
				(type default)
			)
			(layer "B.SilkS")
		)
		(fp_line
			(start -0.970026 -0.4699)
			(end -0.970026 0.4699)
			(stroke
				(width 0.1)
				(type default)
			)
			(layer "B.SilkS")
		)
		(fp_line
			(start 0.970026 0.4699)
			(end 0.970026 -0.4699)
			(stroke
				(width 0.1)
				(type default)
			)
			(layer "B.SilkS")
		)
		(fp_line
			(start -0.970026 0.4699)
			(end 0.970026 0.4699)
			(stroke
				(width 0.1)
				(type default)
			)
			(layer "B.SilkS")
		)
		(fp_poly
			(pts
				(xy 0.970026 0.4699) (xy -0.970026 0.4699) (xy -0.970026 -0.4699) (xy 0.970026 -0.4699)
			)
			(stroke
				(width 0)
				(type default)
			)
			(fill no)
			(layer "B.CrtYd")
		)
		(fp_line
			(start 0.508 -0.3048)
			(end -0.508 -0.3048)
			(stroke
				(width 0.1)
				(type default)
			)
			(layer "B.Fab")
		)
		(fp_line
			(start -0.508 -0.3048)
			(end -0.508 0.3048)
			(stroke
				(width 0.1)
				(type default)
			)
			(layer "B.Fab")
		)
		(fp_line
			(start 0.508 0.3048)
			(end 0.508 -0.3048)
			(stroke
				(width 0.1)
				(type default)
			)
			(layer "B.Fab")
		)
		(fp_line
			(start -0.508 0.3048)
			(end 0.508 0.3048)
			(stroke
				(width 0.1)
				(type default)
			)
			(layer "B.Fab")
		)
		(pad "1" smd circle
			(at 0.500126 0 270)
			(size 0.635 0.635)
			(layers "B.Cu" "B.Mask" "B.Paste")
			(net "XP1R0V_FPGA_VCCINT")
		)
		(pad "2" smd circle
			(at -0.500126 0 270)
			(size 0.635 0.635)
			(layers "B.Cu" "B.Mask" "B.Paste")
			(net "SG")
		)
	)
	(footprint ""
		(layer "B.Cu")
		(at 152.781 -66.421)
		(property "Reference" "R81"
			(at 0 -1.10363 0)
			(unlocked yes)
			(layer "B.SilkS")
			(effects
				(font
					(size 0.7874 0.5842)
					(thickness 0.1524)
				)
				(justify mirror)
			)
		)
		(property "Value" "VAL*"
			(at -0.02032 2.13233 0)
			(unlocked yes)
			(layer "B.Fab")
			(hide yes)
			(effects
				(font
					(size 0.7874 0.5842)
					(thickness 0.1524)
				)
				(justify mirror)
			)
		)
		(property "Device Type" "RESISTOR-G155-133R0-01,33OHM,1%"
			(at -0.008382 1.210564 0)
			(unlocked yes)
			(layer "B.Fab")
			(hide yes)
			(effects
				(font
					(size 0.7874 0.5842)
					(thickness 0.1524)
				)
				(justify mirror)
			)
		)
		(property "User Part Number" "PARTNUM*"
			(at -0.02032 4.024884 0)
			(unlocked yes)
			(layer "Cmts.User")
			(hide yes)
			(effects
				(font
					(size 0.7874 0.5842)
					(thickness 0.1524)
				)
				(justify mirror)
			)
		)
		(property "Tolerance" "TOL*"
			(at -0.044704 3.05435 0)
			(unlocked yes)
			(layer "Cmts.User")
			(hide yes)
			(effects
				(font
					(size 0.7874 0.5842)
					(thickness 0.1524)
				)
				(justify mirror)
			)
		)
		(duplicate_pad_numbers_are_jumpers no)
		(fp_line
			(start -1.143 -0.5588)
			(end 1.143 -0.5588)
			(stroke
				(width 0.1)
				(type default)
			)
			(layer "B.SilkS")
		)
		(fp_line
			(start -1.143 0.5588)
			(end -1.143 -0.5588)
			(stroke
				(width 0.1)
				(type default)
			)
			(layer "B.SilkS")
		)
		(fp_line
			(start 1.143 -0.5588)
			(end 1.143 0.5588)
			(stroke
				(width 0.1)
				(type default)
			)
			(layer "B.SilkS")
		)
		(fp_line
			(start 1.143 0.5588)
			(end -1.143 0.5588)
			(stroke
				(width 0.1)
				(type default)
			)
			(layer "B.SilkS")
		)
		(fp_rect
			(start 1.143 0.5588)
			(end -1.143 -0.5588)
			(stroke
				(width 0)
				(type default)
			)
			(fill no)
			(layer "B.CrtYd")
		)
		(fp_line
			(start -0.508 -0.3048)
			(end 0.508 -0.3048)
			(stroke
				(width 0.1)
				(type default)
			)
			(layer "B.Fab")
		)
		(fp_line
			(start -0.508 0.3048)
			(end -0.508 -0.3048)
			(stroke
				(width 0.1)
				(type default)
			)
			(layer "B.Fab")
		)
		(fp_line
			(start 0.508 -0.3048)
			(end 0.508 0.3048)
			(stroke
				(width 0.1)
				(type default)
			)
			(layer "B.Fab")
		)
		(fp_line
			(start 0.508 0.3048)
			(end -0.508 0.3048)
			(stroke
				(width 0.1)
				(type default)
			)
			(layer "B.Fab")
		)
		(pad "1" smd rect
			(at 0.5334 0 180)
			(size 0.7112 0.6096)
			(layers "B.Cu" "B.Mask" "B.Paste")
			(net "R_MAC_UART_RX_FPGA_TX")
		)
		(pad "2" smd rect
			(at -0.5334 0 180)
			(size 0.7112 0.6096)
			(layers "B.Cu" "B.Mask" "B.Paste")
			(net "DBG_UART_MAC_RX")
		)
		(zone
			(layer "B.Cu")
			(hatch none 0.5)
			(connect_pads
				(clearance 0)
			)
			(min_thickness 0.25)
			(keepout
				(tracks allowed)
				(vias not_allowed)
				(pads allowed)
				(copperpour not_allowed)
				(footprints allowed)
			)
			(placement
				(enabled no)
				(sheetname "")
			)
			(fill
				(thermal_gap 0.5)
				(thermal_bridge_width 0.5)
				(island_removal_mode 0)
			)
			(polygon
				(pts
					(xy 152.8572 -66.1162) (xy 152.8572 -66.7258) (xy 152.7048 -66.7258) (xy 152.7048 -66.1162)
				)
			)
		)
	)
	(footprint ""
		(layer "B.Cu")
		(at 87.884 -34.163 90)
		(property "Reference" "C143"
			(at -3.429 -0.03937 270)
			(unlocked yes)
			(layer "B.SilkS")
			(effects
				(font
					(size 0.7874 0.5842)
					(thickness 0.1524)
				)
				(justify mirror)
			)
		)
		(property "Value" "VAL*"
			(at -0.0762 3.134106 90)
			(unlocked yes)
			(layer "B.Fab")
			(hide yes)
			(effects
				(font
					(size 0.7874 0.5842)
					(thickness 0.1524)
				)
				(justify mirror)
			)
		)
		(property "Tolerance" "TOL*"
			(at -0.0762 4.048506 90)
			(unlocked yes)
			(layer "Cmts.User")
			(hide yes)
			(effects
				(font
					(size 0.7874 0.5842)
					(thickness 0.1524)
				)
				(justify mirror)
			)
		)
		(property "User Part Number" "PARTNUM*"
			(at -0.1016 5.013706 90)
			(unlocked yes)
			(layer "Cmts.User")
			(hide yes)
			(effects
				(font
					(size 0.7874 0.5842)
					(thickness 0.1524)
				)
				(justify mirror)
			)
		)
		(property "Device Type" "CAPACITOR-G107-0F476-AM,47UF,2A"
			(at -0.0508 2.194306 90)
			(unlocked yes)
			(layer "B.Fab")
			(hide yes)
			(effects
				(font
					(size 0.7874 0.5842)
					(thickness 0.1524)
				)
				(justify mirror)
			)
		)
		(duplicate_pad_numbers_are_jumpers no)
		(fp_line
			(start 1.5748 -0.9398)
			(end 1.5748 0.9398)
			(stroke
				(width 0.1)
				(type default)
			)
			(layer "B.SilkS")
		)
		(fp_line
			(start -1.5748 -0.9398)
			(end 1.5748 -0.9398)
			(stroke
				(width 0.1)
				(type default)
			)
			(layer "B.SilkS")
		)
		(fp_line
			(start 1.5748 0.9398)
			(end -1.5748 0.9398)
			(stroke
				(width 0.1)
				(type default)
			)
			(layer "B.SilkS")
		)
		(fp_line
			(start -1.5748 0.9398)
			(end -1.5748 -0.9398)
			(stroke
				(width 0.1)
				(type default)
			)
			(layer "B.SilkS")
		)
		(fp_rect
			(start 1.5748 -0.9398)
			(end -1.5748 0.9398)
			(stroke
				(width 0)
				(type default)
			)
			(fill no)
			(layer "B.CrtYd")
		)
		(fp_line
			(start 1.016 -0.635)
			(end 1.016 0.635)
			(stroke
				(width 0.1)
				(type default)
			)
			(layer "B.Fab")
		)
		(fp_line
			(start -1.016 -0.635)
			(end 1.016 -0.635)
			(stroke
				(width 0.1)
				(type default)
			)
			(layer "B.Fab")
		)
		(fp_line
			(start 1.016 0.635)
			(end -1.016 0.635)
			(stroke
				(width 0.1)
				(type default)
			)
			(layer "B.Fab")
		)
		(fp_line
			(start -1.016 0.635)
			(end -1.016 -0.635)
			(stroke
				(width 0.1)
				(type default)
			)
			(layer "B.Fab")
		)
		(pad "1" smd rect
			(at 0.8382 0 270)
			(size 0.9652 1.3716)
			(layers "B.Cu" "B.Mask" "B.Paste")
			(net "XP1R2V_FPGA")
		)
		(pad "2" smd rect
			(at -0.8382 0 270)
			(size 0.9652 1.3716)
			(layers "B.Cu" "B.Mask" "B.Paste")
			(net "SG")
		)
		(zone
			(layer "B.Cu")
			(hatch none 0.5)
			(connect_pads
				(clearance 0)
			)
			(min_thickness 0.25)
			(keepout
				(tracks allowed)
				(vias not_allowed)
				(pads allowed)
				(copperpour not_allowed)
				(footprints allowed)
			)
			(placement
				(enabled no)
				(sheetname "")
			)
			(fill
				(thermal_gap 0.5)
				(thermal_bridge_width 0.5)
				(island_removal_mode 0)
			)
			(polygon
				(pts
					(xy 87.249 -34.3916) (xy 87.249 -33.9344) (xy 88.519 -33.9344) (xy 88.519 -34.3916)
				)
			)
		)
	)
	(footprint ""
		(layer "B.Cu")
		(at 115.062 -61.976 90)
		(property "Reference" "R215"
			(at 3.429 0.08763 270)
			(unlocked yes)
			(layer "B.SilkS")
			(effects
				(font
					(size 0.7874 0.5842)
					(thickness 0.1524)
				)
				(justify mirror)
			)
		)
		(property "Value" "VAL*"
			(at -0.02032 2.13233 90)
			(unlocked yes)
			(layer "B.Fab")
			(hide yes)
			(effects
				(font
					(size 0.7874 0.5842)
					(thickness 0.1524)
				)
				(justify mirror)
			)
		)
		(property "Device Type" "RESISTOR-G155-11002-01,10KOHM,A"
			(at -0.008382 1.210564 90)
			(unlocked yes)
			(layer "B.Fab")
			(hide yes)
			(effects
				(font
					(size 0.7874 0.5842)
					(thickness 0.1524)
				)
				(justify mirror)
			)
		)
		(property "User Part Number" "PARTNUM*"
			(at -0.02032 4.024884 90)
			(unlocked yes)
			(layer "Cmts.User")
			(hide yes)
			(effects
				(font
					(size 0.7874 0.5842)
					(thickness 0.1524)
				)
				(justify mirror)
			)
		)
		(property "Tolerance" "TOL*"
			(at -0.044704 3.05435 90)
			(unlocked yes)
			(layer "Cmts.User")
			(hide yes)
			(effects
				(font
					(size 0.7874 0.5842)
					(thickness 0.1524)
				)
				(justify mirror)
			)
		)
		(duplicate_pad_numbers_are_jumpers no)
		(fp_line
			(start 1.143 -0.5588)
			(end 1.143 0.5588)
			(stroke
				(width 0.1)
				(type default)
			)
			(layer "B.SilkS")
		)
		(fp_line
			(start -1.143 -0.5588)
			(end 1.143 -0.5588)
			(stroke
				(width 0.1)
				(type default)
			)
			(layer "B.SilkS")
		)
		(fp_line
			(start 1.143 0.5588)
			(end -1.143 0.5588)
			(stroke
				(width 0.1)
				(type default)
			)
			(layer "B.SilkS")
		)
		(fp_line
			(start -1.143 0.5588)
			(end -1.143 -0.5588)
			(stroke
				(width 0.1)
				(type default)
			)
			(layer "B.SilkS")
		)
		(fp_rect
			(start -1.143 0.5588)
			(end 1.143 -0.5588)
			(stroke
				(width 0)
				(type default)
			)
			(fill no)
			(layer "B.CrtYd")
		)
		(fp_line
			(start 0.508 -0.3048)
			(end 0.508 0.3048)
			(stroke
				(width 0.1)
				(type default)
			)
			(layer "B.Fab")
		)
		(fp_line
			(start -0.508 -0.3048)
			(end 0.508 -0.3048)
			(stroke
				(width 0.1)
				(type default)
			)
			(layer "B.Fab")
		)
		(fp_line
			(start 0.508 0.3048)
			(end -0.508 0.3048)
			(stroke
				(width 0.1)
				(type default)
			)
			(layer "B.Fab")
		)
		(fp_line
			(start -0.508 0.3048)
			(end -0.508 -0.3048)
			(stroke
				(width 0.1)
				(type default)
			)
			(layer "B.Fab")
		)
		(pad "1" smd rect
			(at 0.5334 0 270)
			(size 0.7112 0.6096)
			(layers "B.Cu" "B.Mask" "B.Paste")
			(net "XP3R3V_FPGA")
		)
		(pad "2" smd rect
			(at -0.5334 0 270)
			(size 0.7112 0.6096)
			(layers "B.Cu" "B.Mask" "B.Paste")
			(net "FPGA_BRD_REV1")
		)
		(zone
			(layer "B.Cu")
			(hatch none 0.5)
			(connect_pads
				(clearance 0)
			)
			(min_thickness 0.25)
			(keepout
				(tracks allowed)
				(vias not_allowed)
				(pads allowed)
				(copperpour not_allowed)
				(footprints allowed)
			)
			(placement
				(enabled no)
				(sheetname "")
			)
			(fill
				(thermal_gap 0.5)
				(thermal_bridge_width 0.5)
				(island_removal_mode 0)
			)
			(polygon
				(pts
					(xy 115.3668 -61.8998) (xy 115.3668 -62.0522) (xy 114.7572 -62.0522) (xy 114.7572 -61.8998)
				)
			)
		)
	)
	(footprint ""
		(layer "B.Cu")
		(at 101.092 -87.63 -90)
		(property "Reference" "C123"
			(at 0.127 -1.23063 270)
			(unlocked yes)
			(layer "B.SilkS")
			(effects
				(font
					(size 0.7874 0.5842)
					(thickness 0.1524)
				)
				(justify mirror)
			)
		)
		(property "Value" "VAL*"
			(at -0.0762 2.067306 270)
			(unlocked yes)
			(layer "B.Fab")
			(hide yes)
			(effects
				(font
					(size 0.7874 0.5842)
					(thickness 0.1524)
				)
				(justify mirror)
			)
		)
		(property "Tolerance" "TOL*"
			(at -0.0762 3.032506 270)
			(unlocked yes)
			(layer "Cmts.User")
			(hide yes)
			(effects
				(font
					(size 0.7874 0.5842)
					(thickness 0.1524)
				)
				(justify mirror)
			)
		)
		(property "User Part Number" "PARTNUM*"
			(at -0.1016 4.023106 270)
			(unlocked yes)
			(layer "Cmts.User")
			(hide yes)
			(effects
				(font
					(size 0.7874 0.5842)
					(thickness 0.1524)
				)
				(justify mirror)
			)
		)
		(property "Device Type" "CAPACITOR-G105-0B104-EK,0.1UF,A"
			(at -0.0508 1.127506 270)
			(unlocked yes)
			(layer "B.Fab")
			(hide yes)
			(effects
				(font
					(size 0.7874 0.5842)
					(thickness 0.1524)
				)
				(justify mirror)
			)
		)
		(duplicate_pad_numbers_are_jumpers no)
		(fp_line
			(start -1.143 0.5588)
			(end -1.143 -0.5588)
			(stroke
				(width 0.1)
				(type default)
			)
			(layer "B.SilkS")
		)
		(fp_line
			(start 1.143 0.5588)
			(end -1.143 0.5588)
			(stroke
				(width 0.1)
				(type default)
			)
			(layer "B.SilkS")
		)
		(fp_line
			(start -1.143 -0.5588)
			(end 1.143 -0.5588)
			(stroke
				(width 0.1)
				(type default)
			)
			(layer "B.SilkS")
		)
		(fp_line
			(start 1.143 -0.5588)
			(end 1.143 0.5588)
			(stroke
				(width 0.1)
				(type default)
			)
			(layer "B.SilkS")
		)
		(fp_poly
			(pts
				(xy 1.143 0.5588) (xy -1.143 0.5588) (xy -1.143 -0.5588) (xy 1.143 -0.5588)
			)
			(stroke
				(width 0)
				(type default)
			)
			(fill no)
			(layer "B.CrtYd")
		)
		(fp_line
			(start -0.508 0.3048)
			(end -0.508 -0.3048)
			(stroke
				(width 0.1)
				(type default)
			)
			(layer "B.Fab")
		)
		(fp_line
			(start 0.508 0.3048)
			(end -0.508 0.3048)
			(stroke
				(width 0.1)
				(type default)
			)
			(layer "B.Fab")
		)
		(fp_line
			(start -0.508 -0.3048)
			(end 0.508 -0.3048)
			(stroke
				(width 0.1)
				(type default)
			)
			(layer "B.Fab")
		)
		(fp_line
			(start 0.508 -0.3048)
			(end 0.508 0.3048)
			(stroke
				(width 0.1)
				(type default)
			)
			(layer "B.Fab")
		)
		(pad "1" smd rect
			(at 0.5334 0 90)
			(size 0.7112 0.6096)
			(layers "B.Cu" "B.Mask" "B.Paste")
			(net "XP3R3V_FPGA")
		)
		(pad "2" smd rect
			(at -0.5334 0 90)
			(size 0.7112 0.6096)
			(layers "B.Cu" "B.Mask" "B.Paste")
			(net "SG")
		)
		(zone
			(layer "B.Cu")
			(hatch none 0.5)
			(connect_pads
				(clearance 0)
			)
			(min_thickness 0.25)
			(keepout
				(tracks not_allowed)
				(vias allowed)
				(pads allowed)
				(copperpour not_allowed)
				(footprints allowed)
			)
			(placement
				(enabled no)
				(sheetname "")
			)
			(fill
				(thermal_gap 0.5)
				(thermal_bridge_width 0.5)
				(island_removal_mode 0)
			)
			(polygon
				(pts
					(xy 100.7872 -87.5538) (xy 101.3968 -87.5538) (xy 101.3968 -87.7062) (xy 100.7872 -87.7062)
				)
			)
		)
		(zone
			(layer "B.Cu")
			(hatch none 0.5)
			(connect_pads
				(clearance 0)
			)
			(min_thickness 0.25)
			(keepout
				(tracks allowed)
				(vias not_allowed)
				(pads allowed)
				(copperpour not_allowed)
				(footprints allowed)
			)
			(placement
				(enabled no)
				(sheetname "")
			)
			(fill
				(thermal_gap 0.5)
				(thermal_bridge_width 0.5)
				(island_removal_mode 0)
			)
			(polygon
				(pts
					(xy 100.7872 -87.5538) (xy 101.3968 -87.5538) (xy 101.3968 -87.7062) (xy 100.7872 -87.7062)
				)
			)
		)
	)
	(footprint ""
		(layer "B.Cu")
		(at 77.3938 -82.804 180)
		(property "Reference" "R62"
			(at 2.9718 -0.29337 0)
			(unlocked yes)
			(layer "B.SilkS")
			(effects
				(font
					(size 0.7874 0.5842)
					(thickness 0.1524)
				)
				(justify mirror)
			)
		)
		(property "Value" "VAL*"
			(at -0.02032 2.13233 180)
			(unlocked yes)
			(layer "B.Fab")
			(hide yes)
			(effects
				(font
					(size 0.7874 0.5842)
					(thickness 0.1524)
				)
				(justify mirror)
			)
		)
		(property "Tolerance" "TOL*"
			(at -0.044704 3.05435 180)
			(unlocked yes)
			(layer "Cmts.User")
			(hide yes)
			(effects
				(font
					(size 0.7874 0.5842)
					(thickness 0.1524)
				)
				(justify mirror)
			)
		)
		(property "User Part Number" "PARTNUM*"
			(at -0.02032 4.024884 180)
			(unlocked yes)
			(layer "Cmts.User")
			(hide yes)
			(effects
				(font
					(size 0.7874 0.5842)
					(thickness 0.1524)
				)
				(justify mirror)
			)
		)
		(property "Device Type" "RESISTOR-G155-100R0-J0,0OHM,-"
			(at -0.008382 1.210564 180)
			(unlocked yes)
			(layer "B.Fab")
			(hide yes)
			(effects
				(font
					(size 0.7874 0.5842)
					(thickness 0.1524)
				)
				(justify mirror)
			)
		)
		(duplicate_pad_numbers_are_jumpers no)
		(fp_line
			(start 1.143 0.5588)
			(end -1.143 0.5588)
			(stroke
				(width 0.1)
				(type default)
			)
			(layer "B.SilkS")
		)
		(fp_line
			(start 1.143 -0.5588)
			(end 1.143 0.5588)
			(stroke
				(width 0.1)
				(type default)
			)
			(layer "B.SilkS")
		)
		(fp_line
			(start -1.143 0.5588)
			(end -1.143 -0.5588)
			(stroke
				(width 0.1)
				(type default)
			)
			(layer "B.SilkS")
		)
		(fp_line
			(start -1.143 -0.5588)
			(end 1.143 -0.5588)
			(stroke
				(width 0.1)
				(type default)
			)
			(layer "B.SilkS")
		)
		(fp_poly
			(pts
				(xy 1.143 0.5588) (xy -1.143 0.5588) (xy -1.143 -0.5588) (xy 1.143 -0.5588)
			)
			(stroke
				(width 0)
				(type default)
			)
			(fill no)
			(layer "B.CrtYd")
		)
		(fp_line
			(start 0.508 0.3048)
			(end -0.508 0.3048)
			(stroke
				(width 0.1)
				(type default)
			)
			(layer "B.Fab")
		)
		(fp_line
			(start 0.508 -0.3048)
			(end 0.508 0.3048)
			(stroke
				(width 0.1)
				(type default)
			)
			(layer "B.Fab")
		)
		(fp_line
			(start -0.508 0.3048)
			(end -0.508 -0.3048)
			(stroke
				(width 0.1)
				(type default)
			)
			(layer "B.Fab")
		)
		(fp_line
			(start -0.508 -0.3048)
			(end 0.508 -0.3048)
			(stroke
				(width 0.1)
				(type default)
			)
			(layer "B.Fab")
		)
		(pad "1" smd rect
			(at 0.5334 0)
			(size 0.7112 0.6096)
			(layers "B.Cu" "B.Mask" "B.Paste")
			(net "VDD_PCA9546A")
		)
		(pad "2" smd rect
			(at -0.5334 0)
			(size 0.7112 0.6096)
			(layers "B.Cu" "B.Mask" "B.Paste")
			(net "XP3R3V_FPGA")
		)
		(zone
			(layer "B.Cu")
			(hatch none 0.5)
			(connect_pads
				(clearance 0)
			)
			(min_thickness 0.25)
			(keepout
				(tracks allowed)
				(vias not_allowed)
				(pads allowed)
				(copperpour not_allowed)
				(footprints allowed)
			)
			(placement
				(enabled no)
				(sheetname "")
			)
			(fill
				(thermal_gap 0.5)
				(thermal_bridge_width 0.5)
				(island_removal_mode 0)
			)
			(polygon
				(pts
					(xy 77.3176 -83.1088) (xy 77.3176 -82.4992) (xy 77.47 -82.4992) (xy 77.47 -83.1088)
				)
			)
		)
		(zone
			(layer "B.Cu")
			(hatch none 0.5)
			(connect_pads
				(clearance 0)
			)
			(min_thickness 0.25)
			(keepout
				(tracks not_allowed)
				(vias allowed)
				(pads allowed)
				(copperpour not_allowed)
				(footprints allowed)
			)
			(placement
				(enabled no)
				(sheetname "")
			)
			(fill
				(thermal_gap 0.5)
				(thermal_bridge_width 0.5)
				(island_removal_mode 0)
			)
			(polygon
				(pts
					(xy 77.3176 -83.1088) (xy 77.3176 -82.4992) (xy 77.47 -82.4992) (xy 77.47 -83.1088)
				)
			)
		)
	)
	(footprint ""
		(layer "B.Cu")
		(at 34.925 -90.932 90)
		(property "Reference" "C91"
			(at 3.048 -0.29337 270)
			(unlocked yes)
			(layer "B.SilkS")
			(effects
				(font
					(size 0.7874 0.5842)
					(thickness 0.1524)
				)
				(justify mirror)
			)
		)
		(property "Value" "VAL*"
			(at -0.02032 2.13233 90)
			(unlocked yes)
			(layer "B.Fab")
			(hide yes)
			(effects
				(font
					(size 0.7874 0.5842)
					(thickness 0.1524)
				)
				(justify mirror)
			)
		)
		(property "Tolerance" "TOL*"
			(at -0.044704 3.05435 90)
			(unlocked yes)
			(layer "Cmts.User")
			(hide yes)
			(effects
				(font
					(size 0.7874 0.5842)
					(thickness 0.1524)
				)
				(justify mirror)
			)
		)
		(property "User Part Number" "PARTNUM*"
			(at -0.02032 4.024884 90)
			(unlocked yes)
			(layer "Cmts.User")
			(hide yes)
			(effects
				(font
					(size 0.7874 0.5842)
					(thickness 0.1524)
				)
				(justify mirror)
			)
		)
		(property "Device Type" "CAPACITOR-G105-0F475-BM,4.7UF,A"
			(at -0.008382 1.210564 90)
			(unlocked yes)
			(layer "B.Fab")
			(hide yes)
			(effects
				(font
					(size 0.7874 0.5842)
					(thickness 0.1524)
				)
				(justify mirror)
			)
		)
		(duplicate_pad_numbers_are_jumpers no)
		(fp_line
			(start 1.143 -0.5588)
			(end 1.143 0.5588)
			(stroke
				(width 0.1)
				(type default)
			)
			(layer "B.SilkS")
		)
		(fp_line
			(start -1.143 -0.5588)
			(end 1.143 -0.5588)
			(stroke
				(width 0.1)
				(type default)
			)
			(layer "B.SilkS")
		)
		(fp_line
			(start 1.143 0.5588)
			(end -1.143 0.5588)
			(stroke
				(width 0.1)
				(type default)
			)
			(layer "B.SilkS")
		)
		(fp_line
			(start -1.143 0.5588)
			(end -1.143 -0.5588)
			(stroke
				(width 0.1)
				(type default)
			)
			(layer "B.SilkS")
		)
		(fp_poly
			(pts
				(xy 1.143 0.5588) (xy -1.143 0.5588) (xy -1.143 -0.5588) (xy 1.143 -0.5588)
			)
			(stroke
				(width 0)
				(type default)
			)
			(fill no)
			(layer "B.CrtYd")
		)
		(fp_line
			(start 0.508 -0.3048)
			(end 0.508 0.3048)
			(stroke
				(width 0.1)
				(type default)
			)
			(layer "B.Fab")
		)
		(fp_line
			(start -0.508 -0.3048)
			(end 0.508 -0.3048)
			(stroke
				(width 0.1)
				(type default)
			)
			(layer "B.Fab")
		)
		(fp_line
			(start 0.508 0.3048)
			(end -0.508 0.3048)
			(stroke
				(width 0.1)
				(type default)
			)
			(layer "B.Fab")
		)
		(fp_line
			(start -0.508 0.3048)
			(end -0.508 -0.3048)
			(stroke
				(width 0.1)
				(type default)
			)
			(layer "B.Fab")
		)
		(pad "1" smd rect
			(at 0.5334 0 270)
			(size 0.7112 0.6096)
			(layers "B.Cu" "B.Mask" "B.Paste")
			(net "XP3R3V_FT4232")
		)
		(pad "2" smd rect
			(at -0.5334 0 270)
			(size 0.7112 0.6096)
			(layers "B.Cu" "B.Mask" "B.Paste")
			(net "SG")
		)
		(zone
			(layer "B.Cu")
			(hatch none 0.5)
			(connect_pads
				(clearance 0)
			)
			(min_thickness 0.25)
			(keepout
				(tracks allowed)
				(vias not_allowed)
				(pads allowed)
				(copperpour not_allowed)
				(footprints allowed)
			)
			(placement
				(enabled no)
				(sheetname "")
			)
			(fill
				(thermal_gap 0.5)
				(thermal_bridge_width 0.5)
				(island_removal_mode 0)
			)
			(polygon
				(pts
					(xy 35.2298 -91.0082) (xy 34.6202 -91.0082) (xy 34.6202 -90.8558) (xy 35.2298 -90.8558)
				)
			)
		)
		(zone
			(layer "B.Cu")
			(hatch none 0.5)
			(connect_pads
				(clearance 0)
			)
			(min_thickness 0.25)
			(keepout
				(tracks not_allowed)
				(vias allowed)
				(pads allowed)
				(copperpour not_allowed)
				(footprints allowed)
			)
			(placement
				(enabled no)
				(sheetname "")
			)
			(fill
				(thermal_gap 0.5)
				(thermal_bridge_width 0.5)
				(island_removal_mode 0)
			)
			(polygon
				(pts
					(xy 35.2298 -91.0082) (xy 34.6202 -91.0082) (xy 34.6202 -90.8558) (xy 35.2298 -90.8558)
				)
			)
		)
	)
	(footprint ""
		(layer "B.Cu")
		(at 105.847134 -50.323242 -90)
		(property "Reference" "C119"
			(at 0.412242 -0.928116 270)
			(unlocked yes)
			(layer "B.SilkS")
			(effects
				(font
					(size 0.635 0.4064)
					(thickness 0.1524)
				)
				(justify mirror)
			)
		)
		(property "Value" "VAL*"
			(at 0 3.718306 270)
			(unlocked yes)
			(layer "B.Fab")
			(hide yes)
			(effects
				(font
					(size 0.7874 0.5842)
					(thickness 0.127)
				)
				(justify mirror)
			)
		)
		(property "Device Type" "CAPACITOR-G105-0B104-CK,0.1UF,A"
			(at 0 1.432306 270)
			(unlocked yes)
			(layer "B.Fab")
			(hide yes)
			(effects
				(font
					(size 0.7874 0.5842)
					(thickness 0.127)
				)
				(justify mirror)
			)
		)
		(property "User Part Number" "PARTNUM*"
			(at 0 2.575306 270)
			(unlocked yes)
			(layer "Cmts.User")
			(hide yes)
			(effects
				(font
					(size 0.7874 0.5842)
					(thickness 0.127)
				)
				(justify mirror)
			)
		)
		(property "Tolerance" "TOL*"
			(at 0 4.861306 270)
			(unlocked yes)
			(layer "Cmts.User")
			(hide yes)
			(effects
				(font
					(size 0.7874 0.5842)
					(thickness 0.127)
				)
				(justify mirror)
			)
		)
		(duplicate_pad_numbers_are_jumpers no)
		(fp_line
			(start -0.970026 0.4699)
			(end 0.970026 0.4699)
			(stroke
				(width 0.1)
				(type default)
			)
			(layer "B.SilkS")
		)
		(fp_line
			(start 0.970026 0.4699)
			(end 0.970026 -0.4699)
			(stroke
				(width 0.1)
				(type default)
			)
			(layer "B.SilkS")
		)
		(fp_line
			(start -0.970026 -0.4699)
			(end -0.970026 0.4699)
			(stroke
				(width 0.1)
				(type default)
			)
			(layer "B.SilkS")
		)
		(fp_line
			(start 0.970026 -0.4699)
			(end -0.970026 -0.4699)
			(stroke
				(width 0.1)
				(type default)
			)
			(layer "B.SilkS")
		)
		(fp_poly
			(pts
				(xy 0.970026 0.4699) (xy -0.970026 0.4699) (xy -0.970026 -0.4699) (xy 0.970026 -0.4699)
			)
			(stroke
				(width 0)
				(type default)
			)
			(fill no)
			(layer "B.CrtYd")
		)
		(fp_line
			(start -0.508 0.3048)
			(end 0.508 0.3048)
			(stroke
				(width 0.1)
				(type default)
			)
			(layer "B.Fab")
		)
		(fp_line
			(start 0.508 0.3048)
			(end 0.508 -0.3048)
			(stroke
				(width 0.1)
				(type default)
			)
			(layer "B.Fab")
		)
		(fp_line
			(start -0.508 -0.3048)
			(end -0.508 0.3048)
			(stroke
				(width 0.1)
				(type default)
			)
			(layer "B.Fab")
		)
		(fp_line
			(start 0.508 -0.3048)
			(end -0.508 -0.3048)
			(stroke
				(width 0.1)
				(type default)
			)
			(layer "B.Fab")
		)
		(pad "1" smd circle
			(at 0.500126 0 90)
			(size 0.635 0.635)
			(layers "B.Cu" "B.Mask" "B.Paste")
			(net "XP3R3V_FPGA")
		)
		(pad "2" smd circle
			(at -0.500126 0 90)
			(size 0.635 0.635)
			(layers "B.Cu" "B.Mask" "B.Paste")
			(net "SG")
		)
	)
	(footprint ""
		(layer "B.Cu")
		(at 72.40397 -15.367 -90)
		(property "Reference" "C34"
			(at 2.286 -0.08128 270)
			(unlocked yes)
			(layer "B.SilkS")
			(effects
				(font
					(size 0.635 0.4064)
					(thickness 0.1524)
				)
				(justify mirror)
			)
		)
		(property "Value" "VAL*"
			(at -0.0762 2.067306 270)
			(unlocked yes)
			(layer "B.Fab")
			(hide yes)
			(effects
				(font
					(size 0.7874 0.5842)
					(thickness 0.1524)
				)
				(justify mirror)
			)
		)
		(property "Tolerance" "TOL*"
			(at -0.0762 3.032506 270)
			(unlocked yes)
			(layer "Cmts.User")
			(hide yes)
			(effects
				(font
					(size 0.7874 0.5842)
					(thickness 0.1524)
				)
				(justify mirror)
			)
		)
		(property "User Part Number" "PARTNUM*"
			(at -0.1016 4.023106 270)
			(unlocked yes)
			(layer "Cmts.User")
			(hide yes)
			(effects
				(font
					(size 0.7874 0.5842)
					(thickness 0.1524)
				)
				(justify mirror)
			)
		)
		(property "Device Type" "CAPACITOR-G105-0B104-CK,0.1UF,A"
			(at -0.0508 1.127506 270)
			(unlocked yes)
			(layer "B.Fab")
			(hide yes)
			(effects
				(font
					(size 0.7874 0.5842)
					(thickness 0.1524)
				)
				(justify mirror)
			)
		)
		(duplicate_pad_numbers_are_jumpers no)
		(fp_line
			(start -1.143 0.5588)
			(end -1.143 -0.5588)
			(stroke
				(width 0.1)
				(type default)
			)
			(layer "B.SilkS")
		)
		(fp_line
			(start 1.143 0.5588)
			(end -1.143 0.5588)
			(stroke
				(width 0.1)
				(type default)
			)
			(layer "B.SilkS")
		)
		(fp_line
			(start -1.143 -0.5588)
			(end 1.143 -0.5588)
			(stroke
				(width 0.1)
				(type default)
			)
			(layer "B.SilkS")
		)
		(fp_line
			(start 1.143 -0.5588)
			(end 1.143 0.5588)
			(stroke
				(width 0.1)
				(type default)
			)
			(layer "B.SilkS")
		)
		(fp_rect
			(start 1.143 0.5588)
			(end -1.143 -0.5588)
			(stroke
				(width 0)
				(type default)
			)
			(fill no)
			(layer "B.CrtYd")
		)
		(fp_line
			(start -0.508 0.3048)
			(end -0.508 -0.3048)
			(stroke
				(width 0.1)
				(type default)
			)
			(layer "B.Fab")
		)
		(fp_line
			(start 0.508 0.3048)
			(end -0.508 0.3048)
			(stroke
				(width 0.1)
				(type default)
			)
			(layer "B.Fab")
		)
		(fp_line
			(start -0.508 -0.3048)
			(end 0.508 -0.3048)
			(stroke
				(width 0.1)
				(type default)
			)
			(layer "B.Fab")
		)
		(fp_line
			(start 0.508 -0.3048)
			(end 0.508 0.3048)
			(stroke
				(width 0.1)
				(type default)
			)
			(layer "B.Fab")
		)
		(pad "1" smd rect
			(at 0.5334 0 90)
			(size 0.7112 0.6096)
			(layers "B.Cu" "B.Mask" "B.Paste")
			(net "C_CPU_RX_PCIE_MGT2_TXN")
		)
		(pad "2" smd rect
			(at -0.5334 0 90)
			(size 0.7112 0.6096)
			(layers "B.Cu" "B.Mask" "B.Paste")
			(net "CPU_RX_PCIE_MGT2_TXN")
		)
		(zone
			(layer "B.Cu")
			(hatch none 0.5)
			(connect_pads
				(clearance 0)
			)
			(min_thickness 0.25)
			(keepout
				(tracks allowed)
				(vias not_allowed)
				(pads allowed)
				(copperpour not_allowed)
				(footprints allowed)
			)
			(placement
				(enabled no)
				(sheetname "")
			)
			(fill
				(thermal_gap 0.5)
				(thermal_bridge_width 0.5)
				(island_removal_mode 0)
			)
			(polygon
				(pts
					(xy 72.09917 -15.2908) (xy 72.70877 -15.2908) (xy 72.70877 -15.4432) (xy 72.09917 -15.4432)
				)
			)
		)
	)
	(footprint ""
		(layer "B.Cu")
		(at 104.6226 -44.45)
		(property "Reference" "C113"
			(at -43.307 1.63195 0)
			(unlocked yes)
			(layer "B.SilkS")
			(effects
				(font
					(size 0.635 0.4064)
					(thickness 0.1524)
				)
				(justify mirror)
			)
		)
		(property "Value" "VAL*"
			(at -0.0762 2.067306 0)
			(unlocked yes)
			(layer "B.Fab")
			(hide yes)
			(effects
				(font
					(size 0.7874 0.5842)
					(thickness 0.1524)
				)
				(justify mirror)
			)
		)
		(property "Device Type" "CAPACITOR-G105-0B104-CK,0.1UF,A"
			(at -0.0508 1.127506 0)
			(unlocked yes)
			(layer "B.Fab")
			(hide yes)
			(effects
				(font
					(size 0.7874 0.5842)
					(thickness 0.1524)
				)
				(justify mirror)
			)
		)
		(property "User Part Number" "PARTNUM*"
			(at -0.1016 4.023106 0)
			(unlocked yes)
			(layer "Cmts.User")
			(hide yes)
			(effects
				(font
					(size 0.7874 0.5842)
					(thickness 0.1524)
				)
				(justify mirror)
			)
		)
		(property "Tolerance" "TOL*"
			(at -0.0762 3.032506 0)
			(unlocked yes)
			(layer "Cmts.User")
			(hide yes)
			(effects
				(font
					(size 0.7874 0.5842)
					(thickness 0.1524)
				)
				(justify mirror)
			)
		)
		(duplicate_pad_numbers_are_jumpers no)
		(fp_line
			(start -1.143 -0.5588)
			(end 1.143 -0.5588)
			(stroke
				(width 0.1)
				(type default)
			)
			(layer "B.SilkS")
		)
		(fp_line
			(start -1.143 0.5588)
			(end -1.143 -0.5588)
			(stroke
				(width 0.1)
				(type default)
			)
			(layer "B.SilkS")
		)
		(fp_line
			(start 1.143 -0.5588)
			(end 1.143 0.5588)
			(stroke
				(width 0.1)
				(type default)
			)
			(layer "B.SilkS")
		)
		(fp_line
			(start 1.143 0.5588)
			(end -1.143 0.5588)
			(stroke
				(width 0.1)
				(type default)
			)
			(layer "B.SilkS")
		)
		(fp_poly
			(pts
				(xy 1.143 0.5588) (xy -1.143 0.5588) (xy -1.143 -0.5588) (xy 1.143 -0.5588)
			)
			(stroke
				(width 0)
				(type default)
			)
			(fill no)
			(layer "B.CrtYd")
		)
		(fp_line
			(start -0.508 -0.3048)
			(end 0.508 -0.3048)
			(stroke
				(width 0.1)
				(type default)
			)
			(layer "B.Fab")
		)
		(fp_line
			(start -0.508 0.3048)
			(end -0.508 -0.3048)
			(stroke
				(width 0.1)
				(type default)
			)
			(layer "B.Fab")
		)
		(fp_line
			(start 0.508 -0.3048)
			(end 0.508 0.3048)
			(stroke
				(width 0.1)
				(type default)
			)
			(layer "B.Fab")
		)
		(fp_line
			(start 0.508 0.3048)
			(end -0.508 0.3048)
			(stroke
				(width 0.1)
				(type default)
			)
			(layer "B.Fab")
		)
		(pad "1" smd rect
			(at 0.5334 0 180)
			(size 0.7112 0.6096)
			(layers "B.Cu" "B.Mask" "B.Paste")
			(net "XP1R8V_FPGA_VCCAUX")
		)
		(pad "2" smd rect
			(at -0.5334 0 180)
			(size 0.7112 0.6096)
			(layers "B.Cu" "B.Mask" "B.Paste")
			(net "SG")
		)
		(zone
			(layer "B.Cu")
			(hatch none 0.5)
			(connect_pads
				(clearance 0)
			)
			(min_thickness 0.25)
			(keepout
				(tracks not_allowed)
				(vias allowed)
				(pads allowed)
				(copperpour not_allowed)
				(footprints allowed)
			)
			(placement
				(enabled no)
				(sheetname "")
			)
			(fill
				(thermal_gap 0.5)
				(thermal_bridge_width 0.5)
				(island_removal_mode 0)
			)
			(polygon
				(pts
					(xy 104.6988 -44.1452) (xy 104.6988 -44.7548) (xy 104.5464 -44.7548) (xy 104.5464 -44.1452)
				)
			)
		)
		(zone
			(layer "B.Cu")
			(hatch none 0.5)
			(connect_pads
				(clearance 0)
			)
			(min_thickness 0.25)
			(keepout
				(tracks allowed)
				(vias not_allowed)
				(pads allowed)
				(copperpour not_allowed)
				(footprints allowed)
			)
			(placement
				(enabled no)
				(sheetname "")
			)
			(fill
				(thermal_gap 0.5)
				(thermal_bridge_width 0.5)
				(island_removal_mode 0)
			)
			(polygon
				(pts
					(xy 104.6988 -44.1452) (xy 104.6988 -44.7548) (xy 104.5464 -44.7548) (xy 104.5464 -44.1452)
				)
			)
		)
	)
	(footprint ""
		(layer "B.Cu")
		(at 92.583 -56.642 180)
		(property "Reference" "C158"
			(at 1.397 1.48463 0)
			(unlocked yes)
			(layer "B.SilkS")
			(effects
				(font
					(size 0.7874 0.5842)
					(thickness 0.1524)
				)
				(justify mirror)
			)
		)
		(property "Value" "VAL*"
			(at -0.0762 3.134106 180)
			(unlocked yes)
			(layer "B.Fab")
			(hide yes)
			(effects
				(font
					(size 0.7874 0.5842)
					(thickness 0.1524)
				)
				(justify mirror)
			)
		)
		(property "Device Type" "CAPACITOR-G107-0F226-CM,22UF,2A"
			(at -0.0508 2.194306 180)
			(unlocked yes)
			(layer "B.Fab")
			(hide yes)
			(effects
				(font
					(size 0.7874 0.5842)
					(thickness 0.1524)
				)
				(justify mirror)
			)
		)
		(property "User Part Number" "PARTNUM*"
			(at -0.1016 5.013706 180)
			(unlocked yes)
			(layer "Cmts.User")
			(hide yes)
			(effects
				(font
					(size 0.7874 0.5842)
					(thickness 0.1524)
				)
				(justify mirror)
			)
		)
		(property "Tolerance" "TOL*"
			(at -0.0762 4.048506 180)
			(unlocked yes)
			(layer "Cmts.User")
			(hide yes)
			(effects
				(font
					(size 0.7874 0.5842)
					(thickness 0.1524)
				)
				(justify mirror)
			)
		)
		(duplicate_pad_numbers_are_jumpers no)
		(fp_line
			(start 1.5748 0.9398)
			(end -1.5748 0.9398)
			(stroke
				(width 0.1)
				(type default)
			)
			(layer "B.SilkS")
		)
		(fp_line
			(start 1.5748 -0.9398)
			(end 1.5748 0.9398)
			(stroke
				(width 0.1)
				(type default)
			)
			(layer "B.SilkS")
		)
		(fp_line
			(start -1.5748 0.9398)
			(end -1.5748 -0.9398)
			(stroke
				(width 0.1)
				(type default)
			)
			(layer "B.SilkS")
		)
		(fp_line
			(start -1.5748 -0.9398)
			(end 1.5748 -0.9398)
			(stroke
				(width 0.1)
				(type default)
			)
			(layer "B.SilkS")
		)
		(fp_rect
			(start -1.5748 -0.9398)
			(end 1.5748 0.9398)
			(stroke
				(width 0)
				(type default)
			)
			(fill no)
			(layer "B.CrtYd")
		)
		(fp_line
			(start 1.016 0.635)
			(end -1.016 0.635)
			(stroke
				(width 0.1)
				(type default)
			)
			(layer "B.Fab")
		)
		(fp_line
			(start 1.016 -0.635)
			(end 1.016 0.635)
			(stroke
				(width 0.1)
				(type default)
			)
			(layer "B.Fab")
		)
		(fp_line
			(start -1.016 0.635)
			(end -1.016 -0.635)
			(stroke
				(width 0.1)
				(type default)
			)
			(layer "B.Fab")
		)
		(fp_line
			(start -1.016 -0.635)
			(end 1.016 -0.635)
			(stroke
				(width 0.1)
				(type default)
			)
			(layer "B.Fab")
		)
		(pad "1" smd rect
			(at 0.8382 0)
			(size 0.9652 1.3716)
			(layers "B.Cu" "B.Mask" "B.Paste")
			(net "XP1R8V_FPGA")
		)
		(pad "2" smd rect
			(at -0.8382 0)
			(size 0.9652 1.3716)
			(layers "B.Cu" "B.Mask" "B.Paste")
			(net "SG")
		)
		(zone
			(layer "B.Cu")
			(hatch none 0.5)
			(connect_pads
				(clearance 0)
			)
			(min_thickness 0.25)
			(keepout
				(tracks allowed)
				(vias not_allowed)
				(pads allowed)
				(copperpour not_allowed)
				(footprints allowed)
			)
			(placement
				(enabled no)
				(sheetname "")
			)
			(fill
				(thermal_gap 0.5)
				(thermal_bridge_width 0.5)
				(island_removal_mode 0)
			)
			(polygon
				(pts
					(xy 92.8116 -56.007) (xy 92.8116 -57.277) (xy 92.3544 -57.277) (xy 92.3544 -56.007)
				)
			)
		)
	)
	(footprint ""
		(layer "B.Cu")
		(at 158.877 -50.513996 -90)
		(property "Reference" "R102"
			(at 7.874 -1.35763 270)
			(unlocked yes)
			(layer "B.SilkS")
			(effects
				(font
					(size 0.7874 0.5842)
					(thickness 0.1524)
				)
				(justify mirror)
			)
		)
		(property "Value" "VAL*"
			(at -0.02032 2.13233 270)
			(unlocked yes)
			(layer "B.Fab")
			(hide yes)
			(effects
				(font
					(size 0.7874 0.5842)
					(thickness 0.1524)
				)
				(justify mirror)
			)
		)
		(property "Device Type" "RESISTOR-G155-11001-01,1KOHM,1%"
			(at -0.008382 1.210564 270)
			(unlocked yes)
			(layer "B.Fab")
			(hide yes)
			(effects
				(font
					(size 0.7874 0.5842)
					(thickness 0.1524)
				)
				(justify mirror)
			)
		)
		(property "User Part Number" "PARTNUM*"
			(at -0.02032 4.024884 270)
			(unlocked yes)
			(layer "Cmts.User")
			(hide yes)
			(effects
				(font
					(size 0.7874 0.5842)
					(thickness 0.1524)
				)
				(justify mirror)
			)
		)
		(property "Tolerance" "TOL*"
			(at -0.044704 3.05435 270)
			(unlocked yes)
			(layer "Cmts.User")
			(hide yes)
			(effects
				(font
					(size 0.7874 0.5842)
					(thickness 0.1524)
				)
				(justify mirror)
			)
		)
		(duplicate_pad_numbers_are_jumpers no)
		(fp_line
			(start -1.143 0.5588)
			(end -1.143 -0.5588)
			(stroke
				(width 0.1)
				(type default)
			)
			(layer "B.SilkS")
		)
		(fp_line
			(start 1.143 0.5588)
			(end -1.143 0.5588)
			(stroke
				(width 0.1)
				(type default)
			)
			(layer "B.SilkS")
		)
		(fp_line
			(start -1.143 -0.5588)
			(end 1.143 -0.5588)
			(stroke
				(width 0.1)
				(type default)
			)
			(layer "B.SilkS")
		)
		(fp_line
			(start 1.143 -0.5588)
			(end 1.143 0.5588)
			(stroke
				(width 0.1)
				(type default)
			)
			(layer "B.SilkS")
		)
		(fp_rect
			(start -1.143 -0.5588)
			(end 1.143 0.5588)
			(stroke
				(width 0)
				(type default)
			)
			(fill no)
			(layer "B.CrtYd")
		)
		(fp_line
			(start -0.508 0.3048)
			(end -0.508 -0.3048)
			(stroke
				(width 0.1)
				(type default)
			)
			(layer "B.Fab")
		)
		(fp_line
			(start 0.508 0.3048)
			(end -0.508 0.3048)
			(stroke
				(width 0.1)
				(type default)
			)
			(layer "B.Fab")
		)
		(fp_line
			(start -0.508 -0.3048)
			(end 0.508 -0.3048)
			(stroke
				(width 0.1)
				(type default)
			)
			(layer "B.Fab")
		)
		(fp_line
			(start 0.508 -0.3048)
			(end 0.508 0.3048)
			(stroke
				(width 0.1)
				(type default)
			)
			(layer "B.Fab")
		)
		(pad "1" smd rect
			(at 0.5334 0 90)
			(size 0.7112 0.6096)
			(layers "B.Cu" "B.Mask" "B.Paste")
			(net "XP5R0V_USB_CONN_DET")
		)
		(pad "2" smd rect
			(at -0.5334 0 90)
			(size 0.7112 0.6096)
			(layers "B.Cu" "B.Mask" "B.Paste")
			(net "UNNAMED_527_RESISTOR_I201_2")
		)
		(zone
			(layer "B.Cu")
			(hatch none 0.5)
			(connect_pads
				(clearance 0)
			)
			(min_thickness 0.25)
			(keepout
				(tracks allowed)
				(vias not_allowed)
				(pads allowed)
				(copperpour not_allowed)
				(footprints allowed)
			)
			(placement
				(enabled no)
				(sheetname "")
			)
			(fill
				(thermal_gap 0.5)
				(thermal_bridge_width 0.5)
				(island_removal_mode 0)
			)
			(polygon
				(pts
					(xy 159.1818 -50.590196) (xy 158.5722 -50.590196) (xy 158.5722 -50.437796) (xy 159.1818 -50.437796)
				)
			)
		)
	)
	(footprint ""
		(layer "B.Cu")
		(at 140.335 -65.913)
		(property "Reference" "R28"
			(at 1.73863 0.381 270)
			(unlocked yes)
			(layer "B.SilkS")
			(effects
				(font
					(size 0.7874 0.5842)
					(thickness 0.1524)
				)
				(justify mirror)
			)
		)
		(property "Value" "VAL*"
			(at -0.02032 2.13233 0)
			(unlocked yes)
			(layer "B.Fab")
			(hide yes)
			(effects
				(font
					(size 0.7874 0.5842)
					(thickness 0.1524)
				)
				(justify mirror)
			)
		)
		(property "Tolerance" "TOL*"
			(at -0.044704 3.05435 0)
			(unlocked yes)
			(layer "Cmts.User")
			(hide yes)
			(effects
				(font
					(size 0.7874 0.5842)
					(thickness 0.1524)
				)
				(justify mirror)
			)
		)
		(property "User Part Number" "PARTNUM*"
			(at -0.02032 4.024884 0)
			(unlocked yes)
			(layer "Cmts.User")
			(hide yes)
			(effects
				(font
					(size 0.7874 0.5842)
					(thickness 0.1524)
				)
				(justify mirror)
			)
		)
		(property "Device Type" "RESISTOR-G155-100R0-J0,0OHM,-"
			(at -0.008382 1.210564 0)
			(unlocked yes)
			(layer "B.Fab")
			(hide yes)
			(effects
				(font
					(size 0.7874 0.5842)
					(thickness 0.1524)
				)
				(justify mirror)
			)
		)
		(duplicate_pad_numbers_are_jumpers no)
		(fp_line
			(start -1.143 -0.5588)
			(end 1.143 -0.5588)
			(stroke
				(width 0.1)
				(type default)
			)
			(layer "B.SilkS")
		)
		(fp_line
			(start -1.143 0.5588)
			(end -1.143 -0.5588)
			(stroke
				(width 0.1)
				(type default)
			)
			(layer "B.SilkS")
		)
		(fp_line
			(start 1.143 -0.5588)
			(end 1.143 0.5588)
			(stroke
				(width 0.1)
				(type default)
			)
			(layer "B.SilkS")
		)
		(fp_line
			(start 1.143 0.5588)
			(end -1.143 0.5588)
			(stroke
				(width 0.1)
				(type default)
			)
			(layer "B.SilkS")
		)
		(fp_rect
			(start 1.143 0.5588)
			(end -1.143 -0.5588)
			(stroke
				(width 0)
				(type default)
			)
			(fill no)
			(layer "B.CrtYd")
		)
		(fp_line
			(start -0.508 -0.3048)
			(end 0.508 -0.3048)
			(stroke
				(width 0.1)
				(type default)
			)
			(layer "B.Fab")
		)
		(fp_line
			(start -0.508 0.3048)
			(end -0.508 -0.3048)
			(stroke
				(width 0.1)
				(type default)
			)
			(layer "B.Fab")
		)
		(fp_line
			(start 0.508 -0.3048)
			(end 0.508 0.3048)
			(stroke
				(width 0.1)
				(type default)
			)
			(layer "B.Fab")
		)
		(fp_line
			(start 0.508 0.3048)
			(end -0.508 0.3048)
			(stroke
				(width 0.1)
				(type default)
			)
			(layer "B.Fab")
		)
		(pad "1" smd rect
			(at 0.5334 0 180)
			(size 0.7112 0.6096)
			(layers "B.Cu" "B.Mask" "B.Paste")
			(net "PCIE_CONN_TCK")
		)
		(pad "2" smd rect
			(at -0.5334 0 180)
			(size 0.7112 0.6096)
			(layers "B.Cu" "B.Mask" "B.Paste")
			(net "FPGA_TCK")
		)
		(zone
			(layer "B.Cu")
			(hatch none 0.5)
			(connect_pads
				(clearance 0)
			)
			(min_thickness 0.25)
			(keepout
				(tracks allowed)
				(vias not_allowed)
				(pads allowed)
				(copperpour not_allowed)
				(footprints allowed)
			)
			(placement
				(enabled no)
				(sheetname "")
			)
			(fill
				(thermal_gap 0.5)
				(thermal_bridge_width 0.5)
				(island_removal_mode 0)
			)
			(polygon
				(pts
					(xy 140.4112 -65.6082) (xy 140.4112 -66.2178) (xy 140.2588 -66.2178) (xy 140.2588 -65.6082)
				)
			)
		)
	)
	(footprint ""
		(layer "B.Cu")
		(at 109.3724 -46.1264 90)
		(property "Reference" "C115"
			(at -1.6764 -42.98315 270)
			(unlocked yes)
			(layer "B.SilkS")
			(effects
				(font
					(size 0.635 0.4064)
					(thickness 0.1524)
				)
				(justify mirror)
			)
		)
		(property "Value" "VAL*"
			(at -0.0762 2.067306 90)
			(unlocked yes)
			(layer "B.Fab")
			(hide yes)
			(effects
				(font
					(size 0.7874 0.5842)
					(thickness 0.1524)
				)
				(justify mirror)
			)
		)
		(property "Device Type" "CAPACITOR-G105-0B104-CK,0.1UF,A"
			(at -0.0508 1.127506 90)
			(unlocked yes)
			(layer "B.Fab")
			(hide yes)
			(effects
				(font
					(size 0.7874 0.5842)
					(thickness 0.1524)
				)
				(justify mirror)
			)
		)
		(property "User Part Number" "PARTNUM*"
			(at -0.1016 4.023106 90)
			(unlocked yes)
			(layer "Cmts.User")
			(hide yes)
			(effects
				(font
					(size 0.7874 0.5842)
					(thickness 0.1524)
				)
				(justify mirror)
			)
		)
		(property "Tolerance" "TOL*"
			(at -0.0762 3.032506 90)
			(unlocked yes)
			(layer "Cmts.User")
			(hide yes)
			(effects
				(font
					(size 0.7874 0.5842)
					(thickness 0.1524)
				)
				(justify mirror)
			)
		)
		(duplicate_pad_numbers_are_jumpers no)
		(fp_line
			(start 1.143 -0.5588)
			(end 1.143 0.5588)
			(stroke
				(width 0.1)
				(type default)
			)
			(layer "B.SilkS")
		)
		(fp_line
			(start -1.143 -0.5588)
			(end 1.143 -0.5588)
			(stroke
				(width 0.1)
				(type default)
			)
			(layer "B.SilkS")
		)
		(fp_line
			(start 1.143 0.5588)
			(end -1.143 0.5588)
			(stroke
				(width 0.1)
				(type default)
			)
			(layer "B.SilkS")
		)
		(fp_line
			(start -1.143 0.5588)
			(end -1.143 -0.5588)
			(stroke
				(width 0.1)
				(type default)
			)
			(layer "B.SilkS")
		)
		(fp_poly
			(pts
				(xy 1.143 0.5588) (xy -1.143 0.5588) (xy -1.143 -0.5588) (xy 1.143 -0.5588)
			)
			(stroke
				(width 0)
				(type default)
			)
			(fill no)
			(layer "B.CrtYd")
		)
		(fp_line
			(start 0.508 -0.3048)
			(end 0.508 0.3048)
			(stroke
				(width 0.1)
				(type default)
			)
			(layer "B.Fab")
		)
		(fp_line
			(start -0.508 -0.3048)
			(end 0.508 -0.3048)
			(stroke
				(width 0.1)
				(type default)
			)
			(layer "B.Fab")
		)
		(fp_line
			(start 0.508 0.3048)
			(end -0.508 0.3048)
			(stroke
				(width 0.1)
				(type default)
			)
			(layer "B.Fab")
		)
		(fp_line
			(start -0.508 0.3048)
			(end -0.508 -0.3048)
			(stroke
				(width 0.1)
				(type default)
			)
			(layer "B.Fab")
		)
		(pad "1" smd rect
			(at 0.5334 0 270)
			(size 0.7112 0.6096)
			(layers "B.Cu" "B.Mask" "B.Paste")
			(net "XP3R3V_FPGA")
		)
		(pad "2" smd rect
			(at -0.5334 0 270)
			(size 0.7112 0.6096)
			(layers "B.Cu" "B.Mask" "B.Paste")
			(net "SG")
		)
		(zone
			(layer "B.Cu")
			(hatch none 0.5)
			(connect_pads
				(clearance 0)
			)
			(min_thickness 0.25)
			(keepout
				(tracks not_allowed)
				(vias allowed)
				(pads allowed)
				(copperpour not_allowed)
				(footprints allowed)
			)
			(placement
				(enabled no)
				(sheetname "")
			)
			(fill
				(thermal_gap 0.5)
				(thermal_bridge_width 0.5)
				(island_removal_mode 0)
			)
			(polygon
				(pts
					(xy 109.6772 -46.2026) (xy 109.0676 -46.2026) (xy 109.0676 -46.0502) (xy 109.6772 -46.0502)
				)
			)
		)
		(zone
			(layer "B.Cu")
			(hatch none 0.5)
			(connect_pads
				(clearance 0)
			)
			(min_thickness 0.25)
			(keepout
				(tracks allowed)
				(vias not_allowed)
				(pads allowed)
				(copperpour not_allowed)
				(footprints allowed)
			)
			(placement
				(enabled no)
				(sheetname "")
			)
			(fill
				(thermal_gap 0.5)
				(thermal_bridge_width 0.5)
				(island_removal_mode 0)
			)
			(polygon
				(pts
					(xy 109.6772 -46.2026) (xy 109.0676 -46.2026) (xy 109.0676 -46.0502) (xy 109.6772 -46.0502)
				)
			)
		)
	)
	(footprint ""
		(layer "B.Cu")
		(at 30.34538 -17.99844)
		(property "Reference" "R1"
			(at 0.13462 -1.13919 0)
			(unlocked yes)
			(layer "B.SilkS")
			(effects
				(font
					(size 0.7874 0.5842)
					(thickness 0.1524)
				)
				(justify mirror)
			)
		)
		(property "Value" "VAL*"
			(at -0.02032 2.13233 0)
			(unlocked yes)
			(layer "B.Fab")
			(hide yes)
			(effects
				(font
					(size 0.7874 0.5842)
					(thickness 0.1524)
				)
				(justify mirror)
			)
		)
		(property "Device Type" "RESISTOR-G155-13300-01,330OHM,A"
			(at -0.008382 1.210564 0)
			(unlocked yes)
			(layer "B.Fab")
			(hide yes)
			(effects
				(font
					(size 0.7874 0.5842)
					(thickness 0.1524)
				)
				(justify mirror)
			)
		)
		(property "User Part Number" "PARTNUM*"
			(at -0.02032 4.024884 0)
			(unlocked yes)
			(layer "Cmts.User")
			(hide yes)
			(effects
				(font
					(size 0.7874 0.5842)
					(thickness 0.1524)
				)
				(justify mirror)
			)
		)
		(property "Tolerance" "TOL*"
			(at -0.044704 3.05435 0)
			(unlocked yes)
			(layer "Cmts.User")
			(hide yes)
			(effects
				(font
					(size 0.7874 0.5842)
					(thickness 0.1524)
				)
				(justify mirror)
			)
		)
		(duplicate_pad_numbers_are_jumpers no)
		(fp_line
			(start -1.143 -0.5588)
			(end 1.143 -0.5588)
			(stroke
				(width 0.1)
				(type default)
			)
			(layer "B.SilkS")
		)
		(fp_line
			(start -1.143 0.5588)
			(end -1.143 -0.5588)
			(stroke
				(width 0.1)
				(type default)
			)
			(layer "B.SilkS")
		)
		(fp_line
			(start 1.143 -0.5588)
			(end 1.143 0.5588)
			(stroke
				(width 0.1)
				(type default)
			)
			(layer "B.SilkS")
		)
		(fp_line
			(start 1.143 0.5588)
			(end -1.143 0.5588)
			(stroke
				(width 0.1)
				(type default)
			)
			(layer "B.SilkS")
		)
		(fp_rect
			(start 1.143 0.5588)
			(end -1.143 -0.5588)
			(stroke
				(width 0)
				(type default)
			)
			(fill no)
			(layer "B.CrtYd")
		)
		(fp_line
			(start -0.508 -0.3048)
			(end 0.508 -0.3048)
			(stroke
				(width 0.1)
				(type default)
			)
			(layer "B.Fab")
		)
		(fp_line
			(start -0.508 0.3048)
			(end -0.508 -0.3048)
			(stroke
				(width 0.1)
				(type default)
			)
			(layer "B.Fab")
		)
		(fp_line
			(start 0.508 -0.3048)
			(end 0.508 0.3048)
			(stroke
				(width 0.1)
				(type default)
			)
			(layer "B.Fab")
		)
		(fp_line
			(start 0.508 0.3048)
			(end -0.508 0.3048)
			(stroke
				(width 0.1)
				(type default)
			)
			(layer "B.Fab")
		)
		(pad "1" smd rect
			(at 0.5334 0 180)
			(size 0.7112 0.6096)
			(layers "B.Cu" "B.Mask" "B.Paste")
			(net "FPGA_OUT_SN_EEPROM_WP")
		)
		(pad "2" smd rect
			(at -0.5334 0 180)
			(size 0.7112 0.6096)
			(layers "B.Cu" "B.Mask" "B.Paste")
			(net "SN_EEPROM_WP")
		)
		(zone
			(layer "B.Cu")
			(hatch none 0.5)
			(connect_pads
				(clearance 0)
			)
			(min_thickness 0.25)
			(keepout
				(tracks allowed)
				(vias not_allowed)
				(pads allowed)
				(copperpour not_allowed)
				(footprints allowed)
			)
			(placement
				(enabled no)
				(sheetname "")
			)
			(fill
				(thermal_gap 0.5)
				(thermal_bridge_width 0.5)
				(island_removal_mode 0)
			)
			(polygon
				(pts
					(xy 30.42158 -17.69364) (xy 30.42158 -18.30324) (xy 30.26918 -18.30324) (xy 30.26918 -17.69364)
				)
			)
		)
	)
	(footprint ""
		(layer "B.Cu")
		(at 144.145 -104.267 90)
		(property "Reference" "R180"
			(at -1.143 0.98425 270)
			(unlocked yes)
			(layer "B.SilkS")
			(effects
				(font
					(size 0.635 0.4064)
					(thickness 0.1524)
				)
				(justify mirror)
			)
		)
		(property "Value" "VAL*"
			(at -0.02032 2.13233 90)
			(unlocked yes)
			(layer "B.Fab")
			(hide yes)
			(effects
				(font
					(size 0.7874 0.5842)
					(thickness 0.1524)
				)
				(justify mirror)
			)
		)
		(property "Tolerance" "TOL*"
			(at -0.044704 3.05435 90)
			(unlocked yes)
			(layer "Cmts.User")
			(hide yes)
			(effects
				(font
					(size 0.7874 0.5842)
					(thickness 0.1524)
				)
				(justify mirror)
			)
		)
		(property "User Part Number" "PARTNUM*"
			(at -0.02032 4.024884 90)
			(unlocked yes)
			(layer "Cmts.User")
			(hide yes)
			(effects
				(font
					(size 0.7874 0.5842)
					(thickness 0.1524)
				)
				(justify mirror)
			)
		)
		(property "Device Type" "RESISTOR-G155-11001-01,1KOHM,1%"
			(at -0.008382 1.210564 90)
			(unlocked yes)
			(layer "B.Fab")
			(hide yes)
			(effects
				(font
					(size 0.7874 0.5842)
					(thickness 0.1524)
				)
				(justify mirror)
			)
		)
		(duplicate_pad_numbers_are_jumpers no)
		(fp_line
			(start 1.143 -0.5588)
			(end 1.143 0.5588)
			(stroke
				(width 0.1)
				(type default)
			)
			(layer "B.SilkS")
		)
		(fp_line
			(start -1.143 -0.5588)
			(end 1.143 -0.5588)
			(stroke
				(width 0.1)
				(type default)
			)
			(layer "B.SilkS")
		)
		(fp_line
			(start 1.143 0.5588)
			(end -1.143 0.5588)
			(stroke
				(width 0.1)
				(type default)
			)
			(layer "B.SilkS")
		)
		(fp_line
			(start -1.143 0.5588)
			(end -1.143 -0.5588)
			(stroke
				(width 0.1)
				(type default)
			)
			(layer "B.SilkS")
		)
		(fp_rect
			(start -1.143 -0.5588)
			(end 1.143 0.5588)
			(stroke
				(width 0)
				(type default)
			)
			(fill no)
			(layer "B.CrtYd")
		)
		(fp_line
			(start 0.508 -0.3048)
			(end 0.508 0.3048)
			(stroke
				(width 0.1)
				(type default)
			)
			(layer "B.Fab")
		)
		(fp_line
			(start -0.508 -0.3048)
			(end 0.508 -0.3048)
			(stroke
				(width 0.1)
				(type default)
			)
			(layer "B.Fab")
		)
		(fp_line
			(start 0.508 0.3048)
			(end -0.508 0.3048)
			(stroke
				(width 0.1)
				(type default)
			)
			(layer "B.Fab")
		)
		(fp_line
			(start -0.508 0.3048)
			(end -0.508 -0.3048)
			(stroke
				(width 0.1)
				(type default)
			)
			(layer "B.Fab")
		)
		(pad "1" smd rect
			(at 0.5334 0 270)
			(size 0.7112 0.6096)
			(layers "B.Cu" "B.Mask" "B.Paste")
			(net "UNNAMED_14_OPTICAL_I142_A")
		)
		(pad "2" smd rect
			(at -0.5334 0 270)
			(size 0.7112 0.6096)
			(layers "B.Cu" "B.Mask" "B.Paste")
			(net "XP5R0V")
		)
		(zone
			(layer "B.Cu")
			(hatch none 0.5)
			(connect_pads
				(clearance 0)
			)
			(min_thickness 0.25)
			(keepout
				(tracks allowed)
				(vias not_allowed)
				(pads allowed)
				(copperpour not_allowed)
				(footprints allowed)
			)
			(placement
				(enabled no)
				(sheetname "")
			)
			(fill
				(thermal_gap 0.5)
				(thermal_bridge_width 0.5)
				(island_removal_mode 0)
			)
			(polygon
				(pts
					(xy 143.8402 -104.1908) (xy 144.4498 -104.1908) (xy 144.4498 -104.3432) (xy 143.8402 -104.3432)
				)
			)
		)
	)
	(footprint ""
		(layer "B.Cu")
		(at 143.256 -55.118 -90)
		(property "Reference" "SP3"
			(at 1.81737 -0.254 0)
			(unlocked yes)
			(layer "B.SilkS")
			(effects
				(font
					(size 0.7874 0.5842)
					(thickness 0.1524)
				)
				(justify mirror)
			)
		)
		(property "Value" ""
			(at 0 0 90)
			(layer "B.Fab")
			(effects
				(font
					(size 1.27 1.27)
				)
				(justify mirror)
			)
		)
		(duplicate_pad_numbers_are_jumpers no)
		(fp_rect
			(start 0.1778 0.3048)
			(end -0.1778 -0.3048)
			(stroke
				(width 0)
				(type default)
			)
			(fill yes)
			(layer "B.Paste")
		)
		(fp_rect
			(start 0.2286 0.3556)
			(end -0.2286 -0.3556)
			(stroke
				(width 0)
				(type default)
			)
			(fill no)
			(layer "B.CrtYd")
		)
		(fp_line
			(start -0.1397 0.2413)
			(end 0.1397 0.2413)
			(stroke
				(width 0.1)
				(type default)
			)
			(layer "B.Fab")
		)
		(fp_line
			(start 0.1397 0.2413)
			(end 0.1397 -0.2413)
			(stroke
				(width 0.1)
				(type default)
			)
			(layer "B.Fab")
		)
		(fp_line
			(start -0.1397 -0.2413)
			(end -0.1397 0.2413)
			(stroke
				(width 0.1)
				(type default)
			)
			(layer "B.Fab")
		)
		(fp_line
			(start 0.1397 -0.2413)
			(end -0.1397 -0.2413)
			(stroke
				(width 0.1)
				(type default)
			)
			(layer "B.Fab")
		)
		(pad "1" smd rect
			(at 0.1143 0 90)
			(size 0.127 0.6096)
			(layers "B.Cu" "B.Mask" "B.Paste")
			(net "SG")
		)
		(pad "2" smd rect
			(at -0.1143 0 90)
			(size 0.127 0.6096)
			(layers "B.Cu" "B.Mask" "B.Paste")
			(net "XP1R0V_AGND")
		)
	)
	(footprint ""
		(layer "B.Cu")
		(at 14.6558 -17.1704 90)
		(property "Reference" "R379"
			(at 2.2606 -0.08255 270)
			(unlocked yes)
			(layer "B.SilkS")
			(effects
				(font
					(size 0.635 0.4064)
					(thickness 0.1524)
				)
				(justify mirror)
			)
		)
		(property "Value" "VAL*"
			(at -0.02032 2.13233 90)
			(unlocked yes)
			(layer "B.Fab")
			(hide yes)
			(effects
				(font
					(size 0.7874 0.5842)
					(thickness 0.1524)
				)
				(justify mirror)
			)
		)
		(property "Tolerance" "TOL*"
			(at -0.044704 3.05435 90)
			(unlocked yes)
			(layer "Cmts.User")
			(hide yes)
			(effects
				(font
					(size 0.7874 0.5842)
					(thickness 0.1524)
				)
				(justify mirror)
			)
		)
		(property "User Part Number" "PARTNUM*"
			(at -0.02032 4.024884 90)
			(unlocked yes)
			(layer "Cmts.User")
			(hide yes)
			(effects
				(font
					(size 0.7874 0.5842)
					(thickness 0.1524)
				)
				(justify mirror)
			)
		)
		(property "Device Type" "RESISTOR-G155-14701-01,4.7KOHMA"
			(at -0.008382 1.210564 90)
			(unlocked yes)
			(layer "B.Fab")
			(hide yes)
			(effects
				(font
					(size 0.7874 0.5842)
					(thickness 0.1524)
				)
				(justify mirror)
			)
		)
		(duplicate_pad_numbers_are_jumpers no)
		(fp_line
			(start 1.143 -0.5588)
			(end 1.143 0.5588)
			(stroke
				(width 0.1)
				(type default)
			)
			(layer "B.SilkS")
		)
		(fp_line
			(start -1.143 -0.5588)
			(end 1.143 -0.5588)
			(stroke
				(width 0.1)
				(type default)
			)
			(layer "B.SilkS")
		)
		(fp_line
			(start 1.143 0.5588)
			(end -1.143 0.5588)
			(stroke
				(width 0.1)
				(type default)
			)
			(layer "B.SilkS")
		)
		(fp_line
			(start -1.143 0.5588)
			(end -1.143 -0.5588)
			(stroke
				(width 0.1)
				(type default)
			)
			(layer "B.SilkS")
		)
		(fp_rect
			(start -1.143 0.5588)
			(end 1.143 -0.5588)
			(stroke
				(width 0)
				(type default)
			)
			(fill no)
			(layer "B.CrtYd")
		)
		(fp_line
			(start 0.508 -0.3048)
			(end 0.508 0.3048)
			(stroke
				(width 0.1)
				(type default)
			)
			(layer "B.Fab")
		)
		(fp_line
			(start -0.508 -0.3048)
			(end 0.508 -0.3048)
			(stroke
				(width 0.1)
				(type default)
			)
			(layer "B.Fab")
		)
		(fp_line
			(start 0.508 0.3048)
			(end -0.508 0.3048)
			(stroke
				(width 0.1)
				(type default)
			)
			(layer "B.Fab")
		)
		(fp_line
			(start -0.508 0.3048)
			(end -0.508 -0.3048)
			(stroke
				(width 0.1)
				(type default)
			)
			(layer "B.Fab")
		)
		(pad "1" smd rect
			(at 0.5334 0 270)
			(size 0.7112 0.6096)
			(layers "B.Cu" "B.Mask" "B.Paste")
			(net "XP3R3V_FPGA")
		)
		(pad "2" smd rect
			(at -0.5334 0 270)
			(size 0.7112 0.6096)
			(layers "B.Cu" "B.Mask" "B.Paste")
			(net "SMA4_SIG_IN_BF_EN_N")
		)
		(zone
			(layer "B.Cu")
			(hatch none 0.5)
			(connect_pads
				(clearance 0)
			)
			(min_thickness 0.25)
			(keepout
				(tracks allowed)
				(vias not_allowed)
				(pads allowed)
				(copperpour not_allowed)
				(footprints allowed)
			)
			(placement
				(enabled no)
				(sheetname "")
			)
			(fill
				(thermal_gap 0.5)
				(thermal_bridge_width 0.5)
				(island_removal_mode 0)
			)
			(polygon
				(pts
					(xy 14.9606 -17.0942) (xy 14.9606 -17.2466) (xy 14.351 -17.2466) (xy 14.351 -17.0942)
				)
			)
		)
		(zone
			(layer "B.Cu")
			(hatch none 0.5)
			(connect_pads
				(clearance 0)
			)
			(min_thickness 0.25)
			(keepout
				(tracks not_allowed)
				(vias allowed)
				(pads allowed)
				(copperpour not_allowed)
				(footprints allowed)
			)
			(placement
				(enabled no)
				(sheetname "")
			)
			(fill
				(thermal_gap 0.5)
				(thermal_bridge_width 0.5)
				(island_removal_mode 0)
			)
			(polygon
				(pts
					(xy 14.9606 -17.0942) (xy 14.9606 -17.2466) (xy 14.351 -17.2466) (xy 14.351 -17.0942)
				)
			)
		)
	)
	(footprint ""
		(layer "B.Cu")
		(at 98.044 -95.4532)
		(property "Reference" "R451"
			(at 2.667 0.11557 0)
			(unlocked yes)
			(layer "B.SilkS")
			(effects
				(font
					(size 0.7874 0.5842)
					(thickness 0.1524)
				)
				(justify mirror)
			)
		)
		(property "Value" "VAL*"
			(at -0.02032 2.13233 0)
			(unlocked yes)
			(layer "B.Fab")
			(hide yes)
			(effects
				(font
					(size 0.7874 0.5842)
					(thickness 0.1524)
				)
				(justify mirror)
			)
		)
		(property "Tolerance" "TOL*"
			(at -0.044704 3.05435 0)
			(unlocked yes)
			(layer "Cmts.User")
			(hide yes)
			(effects
				(font
					(size 0.7874 0.5842)
					(thickness 0.1524)
				)
				(justify mirror)
			)
		)
		(property "User Part Number" "PARTNUM*"
			(at -0.02032 4.024884 0)
			(unlocked yes)
			(layer "Cmts.User")
			(hide yes)
			(effects
				(font
					(size 0.7874 0.5842)
					(thickness 0.1524)
				)
				(justify mirror)
			)
		)
		(property "Device Type" "RESISTOR-G155-11001-01,1KOHM,1%"
			(at -0.008382 1.210564 0)
			(unlocked yes)
			(layer "B.Fab")
			(hide yes)
			(effects
				(font
					(size 0.7874 0.5842)
					(thickness 0.1524)
				)
				(justify mirror)
			)
		)
		(duplicate_pad_numbers_are_jumpers no)
		(fp_line
			(start -1.143 -0.5588)
			(end 1.143 -0.5588)
			(stroke
				(width 0.1)
				(type default)
			)
			(layer "B.SilkS")
		)
		(fp_line
			(start -1.143 0.5588)
			(end -1.143 -0.5588)
			(stroke
				(width 0.1)
				(type default)
			)
			(layer "B.SilkS")
		)
		(fp_line
			(start 1.143 -0.5588)
			(end 1.143 0.5588)
			(stroke
				(width 0.1)
				(type default)
			)
			(layer "B.SilkS")
		)
		(fp_line
			(start 1.143 0.5588)
			(end -1.143 0.5588)
			(stroke
				(width 0.1)
				(type default)
			)
			(layer "B.SilkS")
		)
		(fp_poly
			(pts
				(xy 1.143 0.5588) (xy -1.143 0.5588) (xy -1.143 -0.5588) (xy 1.143 -0.5588)
			)
			(stroke
				(width 0)
				(type default)
			)
			(fill no)
			(layer "B.CrtYd")
		)
		(fp_line
			(start -0.508 -0.3048)
			(end 0.508 -0.3048)
			(stroke
				(width 0.1)
				(type default)
			)
			(layer "B.Fab")
		)
		(fp_line
			(start -0.508 0.3048)
			(end -0.508 -0.3048)
			(stroke
				(width 0.1)
				(type default)
			)
			(layer "B.Fab")
		)
		(fp_line
			(start 0.508 -0.3048)
			(end 0.508 0.3048)
			(stroke
				(width 0.1)
				(type default)
			)
			(layer "B.Fab")
		)
		(fp_line
			(start 0.508 0.3048)
			(end -0.508 0.3048)
			(stroke
				(width 0.1)
				(type default)
			)
			(layer "B.Fab")
		)
		(pad "1" smd rect
			(at 0.5334 0 180)
			(size 0.7112 0.6096)
			(layers "B.Cu" "B.Mask" "B.Paste")
			(net "MUX1_SEL")
		)
		(pad "2" smd rect
			(at -0.5334 0 180)
			(size 0.7112 0.6096)
			(layers "B.Cu" "B.Mask" "B.Paste")
			(net "SG")
		)
		(zone
			(layer "B.Cu")
			(hatch none 0.5)
			(connect_pads
				(clearance 0)
			)
			(min_thickness 0.25)
			(keepout
				(tracks not_allowed)
				(vias allowed)
				(pads allowed)
				(copperpour not_allowed)
				(footprints allowed)
			)
			(placement
				(enabled no)
				(sheetname "")
			)
			(fill
				(thermal_gap 0.5)
				(thermal_bridge_width 0.5)
				(island_removal_mode 0)
			)
			(polygon
				(pts
					(xy 98.1202 -95.1484) (xy 98.1202 -95.758) (xy 97.9678 -95.758) (xy 97.9678 -95.1484)
				)
			)
		)
		(zone
			(layer "B.Cu")
			(hatch none 0.5)
			(connect_pads
				(clearance 0)
			)
			(min_thickness 0.25)
			(keepout
				(tracks allowed)
				(vias not_allowed)
				(pads allowed)
				(copperpour not_allowed)
				(footprints allowed)
			)
			(placement
				(enabled no)
				(sheetname "")
			)
			(fill
				(thermal_gap 0.5)
				(thermal_bridge_width 0.5)
				(island_removal_mode 0)
			)
			(polygon
				(pts
					(xy 98.1202 -95.1484) (xy 98.1202 -95.758) (xy 97.9678 -95.758) (xy 97.9678 -95.1484)
				)
			)
		)
	)
	(footprint ""
		(layer "B.Cu")
		(at 54.737 -16.129 -90)
		(property "Reference" "C289"
			(at -4.064 -0.72263 270)
			(unlocked yes)
			(layer "B.SilkS")
			(effects
				(font
					(size 0.7874 0.5842)
					(thickness 0.1524)
				)
				(justify mirror)
			)
		)
		(property "Value" "VAL*"
			(at -0.0762 2.067306 270)
			(unlocked yes)
			(layer "B.Fab")
			(hide yes)
			(effects
				(font
					(size 0.7874 0.5842)
					(thickness 0.1524)
				)
				(justify mirror)
			)
		)
		(property "Device Type" "CAPACITOR-G105-0C106-BM,10UF,2A"
			(at -0.0508 1.127506 270)
			(unlocked yes)
			(layer "B.Fab")
			(hide yes)
			(effects
				(font
					(size 0.7874 0.5842)
					(thickness 0.1524)
				)
				(justify mirror)
			)
		)
		(property "User Part Number" "PARTNUM*"
			(at -0.1016 4.023106 270)
			(unlocked yes)
			(layer "Cmts.User")
			(hide yes)
			(effects
				(font
					(size 0.7874 0.5842)
					(thickness 0.1524)
				)
				(justify mirror)
			)
		)
		(property "Tolerance" "TOL*"
			(at -0.0762 3.032506 270)
			(unlocked yes)
			(layer "Cmts.User")
			(hide yes)
			(effects
				(font
					(size 0.7874 0.5842)
					(thickness 0.1524)
				)
				(justify mirror)
			)
		)
		(duplicate_pad_numbers_are_jumpers no)
		(fp_line
			(start -1.143 0.5588)
			(end -1.143 -0.5588)
			(stroke
				(width 0.1)
				(type default)
			)
			(layer "B.SilkS")
		)
		(fp_line
			(start 1.143 0.5588)
			(end -1.143 0.5588)
			(stroke
				(width 0.1)
				(type default)
			)
			(layer "B.SilkS")
		)
		(fp_line
			(start -1.143 -0.5588)
			(end 1.143 -0.5588)
			(stroke
				(width 0.1)
				(type default)
			)
			(layer "B.SilkS")
		)
		(fp_line
			(start 1.143 -0.5588)
			(end 1.143 0.5588)
			(stroke
				(width 0.1)
				(type default)
			)
			(layer "B.SilkS")
		)
		(fp_poly
			(pts
				(xy 1.143 0.5588) (xy -1.143 0.5588) (xy -1.143 -0.5588) (xy 1.143 -0.5588)
			)
			(stroke
				(width 0)
				(type default)
			)
			(fill no)
			(layer "B.CrtYd")
		)
		(fp_line
			(start -0.508 0.3048)
			(end -0.508 -0.3048)
			(stroke
				(width 0.1)
				(type default)
			)
			(layer "B.Fab")
		)
		(fp_line
			(start 0.508 0.3048)
			(end -0.508 0.3048)
			(stroke
				(width 0.1)
				(type default)
			)
			(layer "B.Fab")
		)
		(fp_line
			(start -0.508 -0.3048)
			(end 0.508 -0.3048)
			(stroke
				(width 0.1)
				(type default)
			)
			(layer "B.Fab")
		)
		(fp_line
			(start 0.508 -0.3048)
			(end 0.508 0.3048)
			(stroke
				(width 0.1)
				(type default)
			)
			(layer "B.Fab")
		)
		(pad "1" smd rect
			(at 0.5334 0 90)
			(size 0.7112 0.6096)
			(layers "B.Cu" "B.Mask" "B.Paste")
			(net "XP3R3V_PCIE")
		)
		(pad "2" smd rect
			(at -0.5334 0 90)
			(size 0.7112 0.6096)
			(layers "B.Cu" "B.Mask" "B.Paste")
			(net "SG")
		)
		(zone
			(layer "B.Cu")
			(hatch none 0.5)
			(connect_pads
				(clearance 0)
			)
			(min_thickness 0.25)
			(keepout
				(tracks not_allowed)
				(vias allowed)
				(pads allowed)
				(copperpour not_allowed)
				(footprints allowed)
			)
			(placement
				(enabled no)
				(sheetname "")
			)
			(fill
				(thermal_gap 0.5)
				(thermal_bridge_width 0.5)
				(island_removal_mode 0)
			)
			(polygon
				(pts
					(xy 54.4322 -16.0528) (xy 55.0418 -16.0528) (xy 55.0418 -16.2052) (xy 54.4322 -16.2052)
				)
			)
		)
		(zone
			(layer "B.Cu")
			(hatch none 0.5)
			(connect_pads
				(clearance 0)
			)
			(min_thickness 0.25)
			(keepout
				(tracks allowed)
				(vias not_allowed)
				(pads allowed)
				(copperpour not_allowed)
				(footprints allowed)
			)
			(placement
				(enabled no)
				(sheetname "")
			)
			(fill
				(thermal_gap 0.5)
				(thermal_bridge_width 0.5)
				(island_removal_mode 0)
			)
			(polygon
				(pts
					(xy 54.4322 -16.0528) (xy 55.0418 -16.0528) (xy 55.0418 -16.2052) (xy 54.4322 -16.2052)
				)
			)
		)
	)
	(footprint ""
		(layer "B.Cu")
		(at 102.5398 -64.2874 90)
		(property "Reference" "R293"
			(at 3.5306 -0.09017 270)
			(unlocked yes)
			(layer "B.SilkS")
			(effects
				(font
					(size 0.7874 0.5842)
					(thickness 0.1524)
				)
				(justify mirror)
			)
		)
		(property "Value" "VAL*"
			(at -0.02032 2.13233 90)
			(unlocked yes)
			(layer "B.Fab")
			(hide yes)
			(effects
				(font
					(size 0.7874 0.5842)
					(thickness 0.1524)
				)
				(justify mirror)
			)
		)
		(property "Tolerance" "TOL*"
			(at -0.044704 3.05435 90)
			(unlocked yes)
			(layer "Cmts.User")
			(hide yes)
			(effects
				(font
					(size 0.7874 0.5842)
					(thickness 0.1524)
				)
				(justify mirror)
			)
		)
		(property "User Part Number" "PARTNUM*"
			(at -0.02032 4.024884 90)
			(unlocked yes)
			(layer "Cmts.User")
			(hide yes)
			(effects
				(font
					(size 0.7874 0.5842)
					(thickness 0.1524)
				)
				(justify mirror)
			)
		)
		(property "Device Type" "RESISTOR-G155-14701-01,4.7KOHMA"
			(at -0.008382 1.210564 90)
			(unlocked yes)
			(layer "B.Fab")
			(hide yes)
			(effects
				(font
					(size 0.7874 0.5842)
					(thickness 0.1524)
				)
				(justify mirror)
			)
		)
		(duplicate_pad_numbers_are_jumpers no)
		(fp_line
			(start 1.143 -0.5588)
			(end 1.143 0.5588)
			(stroke
				(width 0.1)
				(type default)
			)
			(layer "B.SilkS")
		)
		(fp_line
			(start -1.143 -0.5588)
			(end 1.143 -0.5588)
			(stroke
				(width 0.1)
				(type default)
			)
			(layer "B.SilkS")
		)
		(fp_line
			(start 1.143 0.5588)
			(end -1.143 0.5588)
			(stroke
				(width 0.1)
				(type default)
			)
			(layer "B.SilkS")
		)
		(fp_line
			(start -1.143 0.5588)
			(end -1.143 -0.5588)
			(stroke
				(width 0.1)
				(type default)
			)
			(layer "B.SilkS")
		)
		(fp_rect
			(start -1.143 0.5588)
			(end 1.143 -0.5588)
			(stroke
				(width 0)
				(type default)
			)
			(fill no)
			(layer "B.CrtYd")
		)
		(fp_line
			(start 0.508 -0.3048)
			(end 0.508 0.3048)
			(stroke
				(width 0.1)
				(type default)
			)
			(layer "B.Fab")
		)
		(fp_line
			(start -0.508 -0.3048)
			(end 0.508 -0.3048)
			(stroke
				(width 0.1)
				(type default)
			)
			(layer "B.Fab")
		)
		(fp_line
			(start 0.508 0.3048)
			(end -0.508 0.3048)
			(stroke
				(width 0.1)
				(type default)
			)
			(layer "B.Fab")
		)
		(fp_line
			(start -0.508 0.3048)
			(end -0.508 -0.3048)
			(stroke
				(width 0.1)
				(type default)
			)
			(layer "B.Fab")
		)
		(pad "1" smd rect
			(at 0.5334 0 270)
			(size 0.7112 0.6096)
			(layers "B.Cu" "B.Mask" "B.Paste")
			(net "SG")
		)
		(pad "2" smd rect
			(at -0.5334 0 270)
			(size 0.7112 0.6096)
			(layers "B.Cu" "B.Mask" "B.Paste")
			(net "FPGA_IO_4")
		)
		(zone
			(layer "B.Cu")
			(hatch none 0.5)
			(connect_pads
				(clearance 0)
			)
			(min_thickness 0.25)
			(keepout
				(tracks allowed)
				(vias not_allowed)
				(pads allowed)
				(copperpour not_allowed)
				(footprints allowed)
			)
			(placement
				(enabled no)
				(sheetname "")
			)
			(fill
				(thermal_gap 0.5)
				(thermal_bridge_width 0.5)
				(island_removal_mode 0)
			)
			(polygon
				(pts
					(xy 102.8446 -64.2112) (xy 102.8446 -64.3636) (xy 102.235 -64.3636) (xy 102.235 -64.2112)
				)
			)
		)
	)
	(footprint ""
		(layer "B.Cu")
		(at 126.619 -89.535 -90)
		(property "Reference" "R109"
			(at -2.794 0.03937 270)
			(unlocked yes)
			(layer "B.SilkS")
			(effects
				(font
					(size 0.7874 0.5842)
					(thickness 0.1524)
				)
				(justify mirror)
			)
		)
		(property "Value" "VAL*"
			(at -0.02032 2.13233 270)
			(unlocked yes)
			(layer "B.Fab")
			(hide yes)
			(effects
				(font
					(size 0.7874 0.5842)
					(thickness 0.1524)
				)
				(justify mirror)
			)
		)
		(property "Tolerance" "TOL*"
			(at -0.044704 3.05435 270)
			(unlocked yes)
			(layer "Cmts.User")
			(hide yes)
			(effects
				(font
					(size 0.7874 0.5842)
					(thickness 0.1524)
				)
				(justify mirror)
			)
		)
		(property "User Part Number" "PARTNUM*"
			(at -0.02032 4.024884 270)
			(unlocked yes)
			(layer "Cmts.User")
			(hide yes)
			(effects
				(font
					(size 0.7874 0.5842)
					(thickness 0.1524)
				)
				(justify mirror)
			)
		)
		(property "Device Type" "RESISTOR-G155-133R0-01,33OHM,1%"
			(at -0.008382 1.210564 270)
			(unlocked yes)
			(layer "B.Fab")
			(hide yes)
			(effects
				(font
					(size 0.7874 0.5842)
					(thickness 0.1524)
				)
				(justify mirror)
			)
		)
		(duplicate_pad_numbers_are_jumpers no)
		(fp_line
			(start -1.143 0.5588)
			(end -1.143 -0.5588)
			(stroke
				(width 0.1)
				(type default)
			)
			(layer "B.SilkS")
		)
		(fp_line
			(start 1.143 0.5588)
			(end -1.143 0.5588)
			(stroke
				(width 0.1)
				(type default)
			)
			(layer "B.SilkS")
		)
		(fp_line
			(start -1.143 -0.5588)
			(end 1.143 -0.5588)
			(stroke
				(width 0.1)
				(type default)
			)
			(layer "B.SilkS")
		)
		(fp_line
			(start 1.143 -0.5588)
			(end 1.143 0.5588)
			(stroke
				(width 0.1)
				(type default)
			)
			(layer "B.SilkS")
		)
		(fp_rect
			(start 1.143 0.5588)
			(end -1.143 -0.5588)
			(stroke
				(width 0)
				(type default)
			)
			(fill no)
			(layer "B.CrtYd")
		)
		(fp_line
			(start -0.508 0.3048)
			(end -0.508 -0.3048)
			(stroke
				(width 0.1)
				(type default)
			)
			(layer "B.Fab")
		)
		(fp_line
			(start 0.508 0.3048)
			(end -0.508 0.3048)
			(stroke
				(width 0.1)
				(type default)
			)
			(layer "B.Fab")
		)
		(fp_line
			(start -0.508 -0.3048)
			(end 0.508 -0.3048)
			(stroke
				(width 0.1)
				(type default)
			)
			(layer "B.Fab")
		)
		(fp_line
			(start 0.508 -0.3048)
			(end 0.508 0.3048)
			(stroke
				(width 0.1)
				(type default)
			)
			(layer "B.Fab")
		)
		(pad "1" smd rect
			(at 0.5334 0 90)
			(size 0.7112 0.6096)
			(layers "B.Cu" "B.Mask" "B.Paste")
			(net "UART_GPS_TX_FPGA_RX")
		)
		(pad "2" smd rect
			(at -0.5334 0 90)
			(size 0.7112 0.6096)
			(layers "B.Cu" "B.Mask" "B.Paste")
			(net "GPS_UART_TXD")
		)
		(zone
			(layer "B.Cu")
			(hatch none 0.5)
			(connect_pads
				(clearance 0)
			)
			(min_thickness 0.25)
			(keepout
				(tracks allowed)
				(vias not_allowed)
				(pads allowed)
				(copperpour not_allowed)
				(footprints allowed)
			)
			(placement
				(enabled no)
				(sheetname "")
			)
			(fill
				(thermal_gap 0.5)
				(thermal_bridge_width 0.5)
				(island_removal_mode 0)
			)
			(polygon
				(pts
					(xy 126.3142 -89.4588) (xy 126.9238 -89.4588) (xy 126.9238 -89.6112) (xy 126.3142 -89.6112)
				)
			)
		)
	)
	(footprint ""
		(layer "B.Cu")
		(at 119.761 -24.511 180)
		(property "Reference" "R482"
			(at 0 1.23063 0)
			(unlocked yes)
			(layer "B.SilkS")
			(effects
				(font
					(size 0.7874 0.5842)
					(thickness 0.1524)
				)
				(justify mirror)
			)
		)
		(property "Value" "VAL*"
			(at -0.02032 2.13233 180)
			(unlocked yes)
			(layer "B.Fab")
			(hide yes)
			(effects
				(font
					(size 0.7874 0.5842)
					(thickness 0.1524)
				)
				(justify mirror)
			)
		)
		(property "Tolerance" "TOL*"
			(at -0.044704 3.05435 180)
			(unlocked yes)
			(layer "Cmts.User")
			(hide yes)
			(effects
				(font
					(size 0.7874 0.5842)
					(thickness 0.1524)
				)
				(justify mirror)
			)
		)
		(property "User Part Number" "PARTNUM*"
			(at -0.02032 4.024884 180)
			(unlocked yes)
			(layer "Cmts.User")
			(hide yes)
			(effects
				(font
					(size 0.7874 0.5842)
					(thickness 0.1524)
				)
				(justify mirror)
			)
		)
		(property "Device Type" "RESISTOR-G155-14701-01,4.7KOHMA"
			(at -0.008382 1.210564 180)
			(unlocked yes)
			(layer "B.Fab")
			(hide yes)
			(effects
				(font
					(size 0.7874 0.5842)
					(thickness 0.1524)
				)
				(justify mirror)
			)
		)
		(duplicate_pad_numbers_are_jumpers no)
		(fp_line
			(start 1.143 0.5588)
			(end -1.143 0.5588)
			(stroke
				(width 0.1)
				(type default)
			)
			(layer "B.SilkS")
		)
		(fp_line
			(start 1.143 -0.5588)
			(end 1.143 0.5588)
			(stroke
				(width 0.1)
				(type default)
			)
			(layer "B.SilkS")
		)
		(fp_line
			(start -1.143 0.5588)
			(end -1.143 -0.5588)
			(stroke
				(width 0.1)
				(type default)
			)
			(layer "B.SilkS")
		)
		(fp_line
			(start -1.143 -0.5588)
			(end 1.143 -0.5588)
			(stroke
				(width 0.1)
				(type default)
			)
			(layer "B.SilkS")
		)
		(fp_poly
			(pts
				(xy 1.143 0.5588) (xy -1.143 0.5588) (xy -1.143 -0.5588) (xy 1.143 -0.5588)
			)
			(stroke
				(width 0)
				(type default)
			)
			(fill no)
			(layer "B.CrtYd")
		)
		(fp_line
			(start 0.508 0.3048)
			(end -0.508 0.3048)
			(stroke
				(width 0.1)
				(type default)
			)
			(layer "B.Fab")
		)
		(fp_line
			(start 0.508 -0.3048)
			(end 0.508 0.3048)
			(stroke
				(width 0.1)
				(type default)
			)
			(layer "B.Fab")
		)
		(fp_line
			(start -0.508 0.3048)
			(end -0.508 -0.3048)
			(stroke
				(width 0.1)
				(type default)
			)
			(layer "B.Fab")
		)
		(fp_line
			(start -0.508 -0.3048)
			(end 0.508 -0.3048)
			(stroke
				(width 0.1)
				(type default)
			)
			(layer "B.Fab")
		)
		(pad "1" smd rect
			(at 0.5334 0)
			(size 0.7112 0.6096)
			(layers "B.Cu" "B.Mask" "B.Paste")
			(net "XP3R3V_FPGA")
		)
		(pad "2" smd rect
			(at -0.5334 0)
			(size 0.7112 0.6096)
			(layers "B.Cu" "B.Mask" "B.Paste")
			(net "MUX3_SEL")
		)
		(zone
			(layer "B.Cu")
			(hatch none 0.5)
			(connect_pads
				(clearance 0)
			)
			(min_thickness 0.25)
			(keepout
				(tracks allowed)
				(vias not_allowed)
				(pads allowed)
				(copperpour not_allowed)
				(footprints allowed)
			)
			(placement
				(enabled no)
				(sheetname "")
			)
			(fill
				(thermal_gap 0.5)
				(thermal_bridge_width 0.5)
				(island_removal_mode 0)
			)
			(polygon
				(pts
					(xy 119.6848 -24.8158) (xy 119.6848 -24.2062) (xy 119.8372 -24.2062) (xy 119.8372 -24.8158)
				)
			)
		)
		(zone
			(layer "B.Cu")
			(hatch none 0.5)
			(connect_pads
				(clearance 0)
			)
			(min_thickness 0.25)
			(keepout
				(tracks not_allowed)
				(vias allowed)
				(pads allowed)
				(copperpour not_allowed)
				(footprints allowed)
			)
			(placement
				(enabled no)
				(sheetname "")
			)
			(fill
				(thermal_gap 0.5)
				(thermal_bridge_width 0.5)
				(island_removal_mode 0)
			)
			(polygon
				(pts
					(xy 119.6848 -24.8158) (xy 119.6848 -24.2062) (xy 119.8372 -24.2062) (xy 119.8372 -24.8158)
				)
			)
		)
	)
	(footprint ""
		(layer "B.Cu")
		(at 53.975 -88.9)
		(property "Reference" "R447"
			(at 0.127 -4.40563 0)
			(unlocked yes)
			(layer "B.SilkS")
			(effects
				(font
					(size 0.7874 0.5842)
					(thickness 0.1524)
				)
				(justify mirror)
			)
		)
		(property "Value" "VAL*"
			(at -0.02032 2.13233 0)
			(unlocked yes)
			(layer "B.Fab")
			(hide yes)
			(effects
				(font
					(size 0.7874 0.5842)
					(thickness 0.1524)
				)
				(justify mirror)
			)
		)
		(property "Tolerance" "TOL*"
			(at -0.044704 3.05435 0)
			(unlocked yes)
			(layer "Cmts.User")
			(hide yes)
			(effects
				(font
					(size 0.7874 0.5842)
					(thickness 0.1524)
				)
				(justify mirror)
			)
		)
		(property "User Part Number" "PARTNUM*"
			(at -0.02032 4.024884 0)
			(unlocked yes)
			(layer "Cmts.User")
			(hide yes)
			(effects
				(font
					(size 0.7874 0.5842)
					(thickness 0.1524)
				)
				(justify mirror)
			)
		)
		(property "Device Type" "RESISTOR-G155-11002-01,10KOHM,A"
			(at -0.008382 1.210564 0)
			(unlocked yes)
			(layer "B.Fab")
			(hide yes)
			(effects
				(font
					(size 0.7874 0.5842)
					(thickness 0.1524)
				)
				(justify mirror)
			)
		)
		(duplicate_pad_numbers_are_jumpers no)
		(fp_line
			(start -1.143 -0.5588)
			(end 1.143 -0.5588)
			(stroke
				(width 0.1)
				(type default)
			)
			(layer "B.SilkS")
		)
		(fp_line
			(start -1.143 0.5588)
			(end -1.143 -0.5588)
			(stroke
				(width 0.1)
				(type default)
			)
			(layer "B.SilkS")
		)
		(fp_line
			(start 1.143 -0.5588)
			(end 1.143 0.5588)
			(stroke
				(width 0.1)
				(type default)
			)
			(layer "B.SilkS")
		)
		(fp_line
			(start 1.143 0.5588)
			(end -1.143 0.5588)
			(stroke
				(width 0.1)
				(type default)
			)
			(layer "B.SilkS")
		)
		(fp_poly
			(pts
				(xy 1.143 0.5588) (xy -1.143 0.5588) (xy -1.143 -0.5588) (xy 1.143 -0.5588)
			)
			(stroke
				(width 0)
				(type default)
			)
			(fill no)
			(layer "B.CrtYd")
		)
		(fp_line
			(start -0.508 -0.3048)
			(end 0.508 -0.3048)
			(stroke
				(width 0.1)
				(type default)
			)
			(layer "B.Fab")
		)
		(fp_line
			(start -0.508 0.3048)
			(end -0.508 -0.3048)
			(stroke
				(width 0.1)
				(type default)
			)
			(layer "B.Fab")
		)
		(fp_line
			(start 0.508 -0.3048)
			(end 0.508 0.3048)
			(stroke
				(width 0.1)
				(type default)
			)
			(layer "B.Fab")
		)
		(fp_line
			(start 0.508 0.3048)
			(end -0.508 0.3048)
			(stroke
				(width 0.1)
				(type default)
			)
			(layer "B.Fab")
		)
		(pad "1" smd rect
			(at 0.5334 0 180)
			(size 0.7112 0.6096)
			(layers "B.Cu" "B.Mask" "B.Paste")
			(net "XP3R3V_FT4232")
		)
		(pad "2" smd rect
			(at -0.5334 0 180)
			(size 0.7112 0.6096)
			(layers "B.Cu" "B.Mask" "B.Paste")
			(net "FTDI_EE_CLK")
		)
		(zone
			(layer "B.Cu")
			(hatch none 0.5)
			(connect_pads
				(clearance 0)
			)
			(min_thickness 0.25)
			(keepout
				(tracks allowed)
				(vias not_allowed)
				(pads allowed)
				(copperpour not_allowed)
				(footprints allowed)
			)
			(placement
				(enabled no)
				(sheetname "")
			)
			(fill
				(thermal_gap 0.5)
				(thermal_bridge_width 0.5)
				(island_removal_mode 0)
			)
			(polygon
				(pts
					(xy 54.0512 -88.5952) (xy 54.0512 -89.2048) (xy 53.8988 -89.2048) (xy 53.8988 -88.5952)
				)
			)
		)
		(zone
			(layer "B.Cu")
			(hatch none 0.5)
			(connect_pads
				(clearance 0)
			)
			(min_thickness 0.25)
			(keepout
				(tracks not_allowed)
				(vias allowed)
				(pads allowed)
				(copperpour not_allowed)
				(footprints allowed)
			)
			(placement
				(enabled no)
				(sheetname "")
			)
			(fill
				(thermal_gap 0.5)
				(thermal_bridge_width 0.5)
				(island_removal_mode 0)
			)
			(polygon
				(pts
					(xy 54.0512 -88.5952) (xy 54.0512 -89.2048) (xy 53.8988 -89.2048) (xy 53.8988 -88.5952)
				)
			)
		)
	)
	(footprint ""
		(layer "B.Cu")
		(at 114.847116 -46.32325 -90)
		(property "Reference" "C107"
			(at 2.00025 43.123866 270)
			(unlocked yes)
			(layer "B.SilkS")
			(effects
				(font
					(size 0.635 0.4064)
					(thickness 0.1524)
				)
				(justify mirror)
			)
		)
		(property "Value" "VAL*"
			(at 0 3.718306 270)
			(unlocked yes)
			(layer "B.Fab")
			(hide yes)
			(effects
				(font
					(size 0.7874 0.5842)
					(thickness 0.127)
				)
				(justify mirror)
			)
		)
		(property "Device Type" "CAPACITOR-G105-0B104-CK,0.1UF,A"
			(at 0 1.432306 270)
			(unlocked yes)
			(layer "B.Fab")
			(hide yes)
			(effects
				(font
					(size 0.7874 0.5842)
					(thickness 0.127)
				)
				(justify mirror)
			)
		)
		(property "User Part Number" "PARTNUM*"
			(at 0 2.575306 270)
			(unlocked yes)
			(layer "Cmts.User")
			(hide yes)
			(effects
				(font
					(size 0.7874 0.5842)
					(thickness 0.127)
				)
				(justify mirror)
			)
		)
		(property "Tolerance" "TOL*"
			(at 0 4.861306 270)
			(unlocked yes)
			(layer "Cmts.User")
			(hide yes)
			(effects
				(font
					(size 0.7874 0.5842)
					(thickness 0.127)
				)
				(justify mirror)
			)
		)
		(duplicate_pad_numbers_are_jumpers no)
		(fp_line
			(start -0.970026 0.4699)
			(end 0.970026 0.4699)
			(stroke
				(width 0.1)
				(type default)
			)
			(layer "B.SilkS")
		)
		(fp_line
			(start 0.970026 0.4699)
			(end 0.970026 -0.4699)
			(stroke
				(width 0.1)
				(type default)
			)
			(layer "B.SilkS")
		)
		(fp_line
			(start -0.970026 -0.4699)
			(end -0.970026 0.4699)
			(stroke
				(width 0.1)
				(type default)
			)
			(layer "B.SilkS")
		)
		(fp_line
			(start 0.970026 -0.4699)
			(end -0.970026 -0.4699)
			(stroke
				(width 0.1)
				(type default)
			)
			(layer "B.SilkS")
		)
		(fp_poly
			(pts
				(xy 0.970026 0.4699) (xy -0.970026 0.4699) (xy -0.970026 -0.4699) (xy 0.970026 -0.4699)
			)
			(stroke
				(width 0)
				(type default)
			)
			(fill no)
			(layer "B.CrtYd")
		)
		(fp_line
			(start -0.508 0.3048)
			(end 0.508 0.3048)
			(stroke
				(width 0.1)
				(type default)
			)
			(layer "B.Fab")
		)
		(fp_line
			(start 0.508 0.3048)
			(end 0.508 -0.3048)
			(stroke
				(width 0.1)
				(type default)
			)
			(layer "B.Fab")
		)
		(fp_line
			(start -0.508 -0.3048)
			(end -0.508 0.3048)
			(stroke
				(width 0.1)
				(type default)
			)
			(layer "B.Fab")
		)
		(fp_line
			(start 0.508 -0.3048)
			(end -0.508 -0.3048)
			(stroke
				(width 0.1)
				(type default)
			)
			(layer "B.Fab")
		)
		(pad "1" smd circle
			(at 0.500126 0 90)
			(size 0.635 0.635)
			(layers "B.Cu" "B.Mask" "B.Paste")
			(net "XP3R3V_FPGA")
		)
		(pad "2" smd circle
			(at -0.500126 0 90)
			(size 0.635 0.635)
			(layers "B.Cu" "B.Mask" "B.Paste")
			(net "SG")
		)
	)
	(footprint ""
		(layer "B.Cu")
		(at 89.027 -45.974 90)
		(property "Reference" "C67"
			(at -0.381 -1.56337 270)
			(unlocked yes)
			(layer "B.SilkS")
			(effects
				(font
					(size 0.7874 0.5842)
					(thickness 0.1524)
				)
				(justify mirror)
			)
		)
		(property "Value" "VAL*"
			(at -0.0762 2.067306 90)
			(unlocked yes)
			(layer "B.Fab")
			(hide yes)
			(effects
				(font
					(size 0.7874 0.5842)
					(thickness 0.1524)
				)
				(justify mirror)
			)
		)
		(property "Device Type" "CAPACITOR-G105-0B104-CK,0.1UF,A"
			(at -0.0508 1.127506 90)
			(unlocked yes)
			(layer "B.Fab")
			(hide yes)
			(effects
				(font
					(size 0.7874 0.5842)
					(thickness 0.1524)
				)
				(justify mirror)
			)
		)
		(property "User Part Number" "PARTNUM*"
			(at -0.1016 4.023106 90)
			(unlocked yes)
			(layer "Cmts.User")
			(hide yes)
			(effects
				(font
					(size 0.7874 0.5842)
					(thickness 0.1524)
				)
				(justify mirror)
			)
		)
		(property "Tolerance" "TOL*"
			(at -0.0762 3.032506 90)
			(unlocked yes)
			(layer "Cmts.User")
			(hide yes)
			(effects
				(font
					(size 0.7874 0.5842)
					(thickness 0.1524)
				)
				(justify mirror)
			)
		)
		(duplicate_pad_numbers_are_jumpers no)
		(fp_line
			(start 1.143 -0.5588)
			(end 1.143 0.5588)
			(stroke
				(width 0.1)
				(type default)
			)
			(layer "B.SilkS")
		)
		(fp_line
			(start -1.143 -0.5588)
			(end 1.143 -0.5588)
			(stroke
				(width 0.1)
				(type default)
			)
			(layer "B.SilkS")
		)
		(fp_line
			(start 1.143 0.5588)
			(end -1.143 0.5588)
			(stroke
				(width 0.1)
				(type default)
			)
			(layer "B.SilkS")
		)
		(fp_line
			(start -1.143 0.5588)
			(end -1.143 -0.5588)
			(stroke
				(width 0.1)
				(type default)
			)
			(layer "B.SilkS")
		)
		(fp_rect
			(start -1.143 0.5588)
			(end 1.143 -0.5588)
			(stroke
				(width 0)
				(type default)
			)
			(fill no)
			(layer "B.CrtYd")
		)
		(fp_line
			(start 0.508 -0.3048)
			(end 0.508 0.3048)
			(stroke
				(width 0.1)
				(type default)
			)
			(layer "B.Fab")
		)
		(fp_line
			(start -0.508 -0.3048)
			(end 0.508 -0.3048)
			(stroke
				(width 0.1)
				(type default)
			)
			(layer "B.Fab")
		)
		(fp_line
			(start 0.508 0.3048)
			(end -0.508 0.3048)
			(stroke
				(width 0.1)
				(type default)
			)
			(layer "B.Fab")
		)
		(fp_line
			(start -0.508 0.3048)
			(end -0.508 -0.3048)
			(stroke
				(width 0.1)
				(type default)
			)
			(layer "B.Fab")
		)
		(pad "1" smd rect
			(at 0.5334 0 270)
			(size 0.7112 0.6096)
			(layers "B.Cu" "B.Mask" "B.Paste")
			(net "XP3R3V_FPGA")
		)
		(pad "2" smd rect
			(at -0.5334 0 270)
			(size 0.7112 0.6096)
			(layers "B.Cu" "B.Mask" "B.Paste")
			(net "SG")
		)
		(zone
			(layer "B.Cu")
			(hatch none 0.5)
			(connect_pads
				(clearance 0)
			)
			(min_thickness 0.25)
			(keepout
				(tracks allowed)
				(vias not_allowed)
				(pads allowed)
				(copperpour not_allowed)
				(footprints allowed)
			)
			(placement
				(enabled no)
				(sheetname "")
			)
			(fill
				(thermal_gap 0.5)
				(thermal_bridge_width 0.5)
				(island_removal_mode 0)
			)
			(polygon
				(pts
					(xy 89.3318 -45.8978) (xy 89.3318 -46.0502) (xy 88.7222 -46.0502) (xy 88.7222 -45.8978)
				)
			)
		)
	)
	(footprint ""
		(layer "B.Cu")
		(at 61.976 -59.817)
		(property "Reference" "C68"
			(at -2.54 0.03937 0)
			(unlocked yes)
			(layer "B.SilkS")
			(effects
				(font
					(size 0.7874 0.5842)
					(thickness 0.1524)
				)
				(justify mirror)
			)
		)
		(property "Value" "VAL*"
			(at -0.0762 2.067306 0)
			(unlocked yes)
			(layer "B.Fab")
			(hide yes)
			(effects
				(font
					(size 0.7874 0.5842)
					(thickness 0.1524)
				)
				(justify mirror)
			)
		)
		(property "Device Type" "CAPACITOR-G105-0B104-EK,0.1UF,A"
			(at -0.0508 1.127506 0)
			(unlocked yes)
			(layer "B.Fab")
			(hide yes)
			(effects
				(font
					(size 0.7874 0.5842)
					(thickness 0.1524)
				)
				(justify mirror)
			)
		)
		(property "User Part Number" "PARTNUM*"
			(at -0.1016 4.023106 0)
			(unlocked yes)
			(layer "Cmts.User")
			(hide yes)
			(effects
				(font
					(size 0.7874 0.5842)
					(thickness 0.1524)
				)
				(justify mirror)
			)
		)
		(property "Tolerance" "TOL*"
			(at -0.0762 3.032506 0)
			(unlocked yes)
			(layer "Cmts.User")
			(hide yes)
			(effects
				(font
					(size 0.7874 0.5842)
					(thickness 0.1524)
				)
				(justify mirror)
			)
		)
		(duplicate_pad_numbers_are_jumpers no)
		(fp_line
			(start -1.143 -0.5588)
			(end 1.143 -0.5588)
			(stroke
				(width 0.1)
				(type default)
			)
			(layer "B.SilkS")
		)
		(fp_line
			(start -1.143 0.5588)
			(end -1.143 -0.5588)
			(stroke
				(width 0.1)
				(type default)
			)
			(layer "B.SilkS")
		)
		(fp_line
			(start 1.143 -0.5588)
			(end 1.143 0.5588)
			(stroke
				(width 0.1)
				(type default)
			)
			(layer "B.SilkS")
		)
		(fp_line
			(start 1.143 0.5588)
			(end -1.143 0.5588)
			(stroke
				(width 0.1)
				(type default)
			)
			(layer "B.SilkS")
		)
		(fp_rect
			(start -1.143 -0.5588)
			(end 1.143 0.5588)
			(stroke
				(width 0)
				(type default)
			)
			(fill no)
			(layer "B.CrtYd")
		)
		(fp_line
			(start -0.508 -0.3048)
			(end 0.508 -0.3048)
			(stroke
				(width 0.1)
				(type default)
			)
			(layer "B.Fab")
		)
		(fp_line
			(start -0.508 0.3048)
			(end -0.508 -0.3048)
			(stroke
				(width 0.1)
				(type default)
			)
			(layer "B.Fab")
		)
		(fp_line
			(start 0.508 -0.3048)
			(end 0.508 0.3048)
			(stroke
				(width 0.1)
				(type default)
			)
			(layer "B.Fab")
		)
		(fp_line
			(start 0.508 0.3048)
			(end -0.508 0.3048)
			(stroke
				(width 0.1)
				(type default)
			)
			(layer "B.Fab")
		)
		(pad "1" smd rect
			(at 0.5334 0 180)
			(size 0.7112 0.6096)
			(layers "B.Cu" "B.Mask" "B.Paste")
			(net "XP3R3V_FPGA")
		)
		(pad "2" smd rect
			(at -0.5334 0 180)
			(size 0.7112 0.6096)
			(layers "B.Cu" "B.Mask" "B.Paste")
			(net "SG")
		)
		(zone
			(layer "B.Cu")
			(hatch none 0.5)
			(connect_pads
				(clearance 0)
			)
			(min_thickness 0.25)
			(keepout
				(tracks allowed)
				(vias not_allowed)
				(pads allowed)
				(copperpour not_allowed)
				(footprints allowed)
			)
			(placement
				(enabled no)
				(sheetname "")
			)
			(fill
				(thermal_gap 0.5)
				(thermal_bridge_width 0.5)
				(island_removal_mode 0)
			)
			(polygon
				(pts
					(xy 61.8998 -60.1218) (xy 61.8998 -59.5122) (xy 62.0522 -59.5122) (xy 62.0522 -60.1218)
				)
			)
		)
		(zone
			(layer "B.Cu")
			(hatch none 0.5)
			(connect_pads
				(clearance 0)
			)
			(min_thickness 0.25)
			(keepout
				(tracks not_allowed)
				(vias allowed)
				(pads allowed)
				(copperpour not_allowed)
				(footprints allowed)
			)
			(placement
				(enabled no)
				(sheetname "")
			)
			(fill
				(thermal_gap 0.5)
				(thermal_bridge_width 0.5)
				(island_removal_mode 0)
			)
			(polygon
				(pts
					(xy 61.8998 -60.1218) (xy 61.8998 -59.5122) (xy 62.0522 -59.5122) (xy 62.0522 -60.1218)
				)
			)
		)
	)
	(footprint ""
		(layer "B.Cu")
		(at 77.3938 -83.947)
		(property "Reference" "R154"
			(at -1.1938 -2.37363 0)
			(unlocked yes)
			(layer "B.SilkS")
			(effects
				(font
					(size 0.7874 0.5842)
					(thickness 0.1524)
				)
				(justify mirror)
			)
		)
		(property "Value" "VAL*"
			(at -0.02032 2.13233 0)
			(unlocked yes)
			(layer "B.Fab")
			(hide yes)
			(effects
				(font
					(size 0.7874 0.5842)
					(thickness 0.1524)
				)
				(justify mirror)
			)
		)
		(property "Tolerance" "TOL*"
			(at -0.044704 3.05435 0)
			(unlocked yes)
			(layer "Cmts.User")
			(hide yes)
			(effects
				(font
					(size 0.7874 0.5842)
					(thickness 0.1524)
				)
				(justify mirror)
			)
		)
		(property "User Part Number" "PARTNUM*"
			(at -0.02032 4.024884 0)
			(unlocked yes)
			(layer "Cmts.User")
			(hide yes)
			(effects
				(font
					(size 0.7874 0.5842)
					(thickness 0.1524)
				)
				(justify mirror)
			)
		)
		(property "Device Type" "RESISTOR-G155-14701-01,4.7KOHMA"
			(at -0.008382 1.210564 0)
			(unlocked yes)
			(layer "B.Fab")
			(hide yes)
			(effects
				(font
					(size 0.7874 0.5842)
					(thickness 0.1524)
				)
				(justify mirror)
			)
		)
		(duplicate_pad_numbers_are_jumpers no)
		(fp_line
			(start -1.143 -0.5588)
			(end 1.143 -0.5588)
			(stroke
				(width 0.1)
				(type default)
			)
			(layer "B.SilkS")
		)
		(fp_line
			(start -1.143 0.5588)
			(end -1.143 -0.5588)
			(stroke
				(width 0.1)
				(type default)
			)
			(layer "B.SilkS")
		)
		(fp_line
			(start 1.143 -0.5588)
			(end 1.143 0.5588)
			(stroke
				(width 0.1)
				(type default)
			)
			(layer "B.SilkS")
		)
		(fp_line
			(start 1.143 0.5588)
			(end -1.143 0.5588)
			(stroke
				(width 0.1)
				(type default)
			)
			(layer "B.SilkS")
		)
		(fp_rect
			(start 1.143 -0.5588)
			(end -1.143 0.5588)
			(stroke
				(width 0)
				(type default)
			)
			(fill no)
			(layer "B.CrtYd")
		)
		(fp_line
			(start -0.508 -0.3048)
			(end 0.508 -0.3048)
			(stroke
				(width 0.1)
				(type default)
			)
			(layer "B.Fab")
		)
		(fp_line
			(start -0.508 0.3048)
			(end -0.508 -0.3048)
			(stroke
				(width 0.1)
				(type default)
			)
			(layer "B.Fab")
		)
		(fp_line
			(start 0.508 -0.3048)
			(end 0.508 0.3048)
			(stroke
				(width 0.1)
				(type default)
			)
			(layer "B.Fab")
		)
		(fp_line
			(start 0.508 0.3048)
			(end -0.508 0.3048)
			(stroke
				(width 0.1)
				(type default)
			)
			(layer "B.Fab")
		)
		(pad "1" smd rect
			(at 0.5334 0 180)
			(size 0.7112 0.6096)
			(layers "B.Cu" "B.Mask" "B.Paste")
			(net "SG")
		)
		(pad "2" smd rect
			(at -0.5334 0 180)
			(size 0.7112 0.6096)
			(layers "B.Cu" "B.Mask" "B.Paste")
			(net "UNNAMED_5_PCA9546APWTSSOP16_I_2")
		)
		(zone
			(layer "B.Cu")
			(hatch none 0.5)
			(connect_pads
				(clearance 0)
			)
			(min_thickness 0.25)
			(keepout
				(tracks allowed)
				(vias not_allowed)
				(pads allowed)
				(copperpour not_allowed)
				(footprints allowed)
			)
			(placement
				(enabled no)
				(sheetname "")
			)
			(fill
				(thermal_gap 0.5)
				(thermal_bridge_width 0.5)
				(island_removal_mode 0)
			)
			(polygon
				(pts
					(xy 77.47 -84.2518) (xy 77.3176 -84.2518) (xy 77.3176 -83.6422) (xy 77.47 -83.6422)
				)
			)
		)
	)
	(footprint ""
		(layer "B.Cu")
		(at 139.6492 -85.4456)
		(property "Reference" "C297"
			(at 0.4318 -5.82803 0)
			(unlocked yes)
			(layer "B.SilkS")
			(effects
				(font
					(size 0.7874 0.5842)
					(thickness 0.1524)
				)
				(justify mirror)
			)
		)
		(property "Value" "VAL*"
			(at -0.0762 3.134106 0)
			(unlocked yes)
			(layer "B.Fab")
			(hide yes)
			(effects
				(font
					(size 0.7874 0.5842)
					(thickness 0.1524)
				)
				(justify mirror)
			)
		)
		(property "Device Type" "CAPACITOR-G107-0F106-EM,10UF,2A"
			(at -0.0508 2.194306 0)
			(unlocked yes)
			(layer "B.Fab")
			(hide yes)
			(effects
				(font
					(size 0.7874 0.5842)
					(thickness 0.1524)
				)
				(justify mirror)
			)
		)
		(property "User Part Number" "PARTNUM*"
			(at -0.1016 5.013706 0)
			(unlocked yes)
			(layer "Cmts.User")
			(hide yes)
			(effects
				(font
					(size 0.7874 0.5842)
					(thickness 0.1524)
				)
				(justify mirror)
			)
		)
		(property "Tolerance" "TOL*"
			(at -0.0762 4.048506 0)
			(unlocked yes)
			(layer "Cmts.User")
			(hide yes)
			(effects
				(font
					(size 0.7874 0.5842)
					(thickness 0.1524)
				)
				(justify mirror)
			)
		)
		(duplicate_pad_numbers_are_jumpers no)
		(fp_line
			(start -1.5748 -0.9398)
			(end 1.5748 -0.9398)
			(stroke
				(width 0.1)
				(type default)
			)
			(layer "B.SilkS")
		)
		(fp_line
			(start -1.5748 0.9398)
			(end -1.5748 -0.9398)
			(stroke
				(width 0.1)
				(type default)
			)
			(layer "B.SilkS")
		)
		(fp_line
			(start 1.5748 -0.9398)
			(end 1.5748 0.9398)
			(stroke
				(width 0.1)
				(type default)
			)
			(layer "B.SilkS")
		)
		(fp_line
			(start 1.5748 0.9398)
			(end -1.5748 0.9398)
			(stroke
				(width 0.1)
				(type default)
			)
			(layer "B.SilkS")
		)
		(fp_rect
			(start 1.5748 -0.9398)
			(end -1.5748 0.9398)
			(stroke
				(width 0)
				(type default)
			)
			(fill no)
			(layer "B.CrtYd")
		)
		(fp_line
			(start -1.016 -0.635)
			(end 1.016 -0.635)
			(stroke
				(width 0.1)
				(type default)
			)
			(layer "B.Fab")
		)
		(fp_line
			(start -1.016 0.635)
			(end -1.016 -0.635)
			(stroke
				(width 0.1)
				(type default)
			)
			(layer "B.Fab")
		)
		(fp_line
			(start 1.016 -0.635)
			(end 1.016 0.635)
			(stroke
				(width 0.1)
				(type default)
			)
			(layer "B.Fab")
		)
		(fp_line
			(start 1.016 0.635)
			(end -1.016 0.635)
			(stroke
				(width 0.1)
				(type default)
			)
			(layer "B.Fab")
		)
		(pad "1" smd rect
			(at 0.8382 0 180)
			(size 0.9652 1.3716)
			(layers "B.Cu" "B.Mask" "B.Paste")
			(net "XP12R0V_IN")
		)
		(pad "2" smd rect
			(at -0.8382 0 180)
			(size 0.9652 1.3716)
			(layers "B.Cu" "B.Mask" "B.Paste")
			(net "SG")
		)
		(zone
			(layer "B.Cu")
			(hatch none 0.5)
			(connect_pads
				(clearance 0)
			)
			(min_thickness 0.25)
			(keepout
				(tracks not_allowed)
				(vias allowed)
				(pads allowed)
				(copperpour not_allowed)
				(footprints allowed)
			)
			(placement
				(enabled no)
				(sheetname "")
			)
			(fill
				(thermal_gap 0.5)
				(thermal_bridge_width 0.5)
				(island_removal_mode 0)
			)
			(polygon
				(pts
					(xy 139.8778 -86.0806) (xy 139.4206 -86.0806) (xy 139.4206 -84.8106) (xy 139.8778 -84.8106)
				)
			)
		)
		(zone
			(layer "B.Cu")
			(hatch none 0.5)
			(connect_pads
				(clearance 0)
			)
			(min_thickness 0.25)
			(keepout
				(tracks allowed)
				(vias not_allowed)
				(pads allowed)
				(copperpour not_allowed)
				(footprints allowed)
			)
			(placement
				(enabled no)
				(sheetname "")
			)
			(fill
				(thermal_gap 0.5)
				(thermal_bridge_width 0.5)
				(island_removal_mode 0)
			)
			(polygon
				(pts
					(xy 139.8778 -86.0806) (xy 139.4206 -86.0806) (xy 139.4206 -84.8106) (xy 139.8778 -84.8106)
				)
			)
		)
	)
	(footprint ""
		(layer "B.Cu")
		(at 111.847122 -42.323004 90)
		(property "Reference" "C201"
			(at -1.141984 -42.018712 270)
			(unlocked yes)
			(layer "B.SilkS")
			(effects
				(font
					(size 0.635 0.4064)
					(thickness 0.1524)
				)
				(justify mirror)
			)
		)
		(property "Value" "VAL*"
			(at 0 3.718306 90)
			(unlocked yes)
			(layer "B.Fab")
			(hide yes)
			(effects
				(font
					(size 0.7874 0.5842)
					(thickness 0.127)
				)
				(justify mirror)
			)
		)
		(property "Device Type" "CAPACITOR-G105-0B104-CK,0.1UF,A"
			(at 0 1.432306 90)
			(unlocked yes)
			(layer "B.Fab")
			(hide yes)
			(effects
				(font
					(size 0.7874 0.5842)
					(thickness 0.127)
				)
				(justify mirror)
			)
		)
		(property "User Part Number" "PARTNUM*"
			(at 0 2.575306 90)
			(unlocked yes)
			(layer "Cmts.User")
			(hide yes)
			(effects
				(font
					(size 0.7874 0.5842)
					(thickness 0.127)
				)
				(justify mirror)
			)
		)
		(property "Tolerance" "TOL*"
			(at 0 4.861306 90)
			(unlocked yes)
			(layer "Cmts.User")
			(hide yes)
			(effects
				(font
					(size 0.7874 0.5842)
					(thickness 0.127)
				)
				(justify mirror)
			)
		)
		(duplicate_pad_numbers_are_jumpers no)
		(fp_line
			(start 0.970026 -0.4699)
			(end -0.970026 -0.4699)
			(stroke
				(width 0.1)
				(type default)
			)
			(layer "B.SilkS")
		)
		(fp_line
			(start -0.970026 -0.4699)
			(end -0.970026 0.4699)
			(stroke
				(width 0.1)
				(type default)
			)
			(layer "B.SilkS")
		)
		(fp_line
			(start 0.970026 0.4699)
			(end 0.970026 -0.4699)
			(stroke
				(width 0.1)
				(type default)
			)
			(layer "B.SilkS")
		)
		(fp_line
			(start -0.970026 0.4699)
			(end 0.970026 0.4699)
			(stroke
				(width 0.1)
				(type default)
			)
			(layer "B.SilkS")
		)
		(fp_poly
			(pts
				(xy 0.970026 0.4699) (xy -0.970026 0.4699) (xy -0.970026 -0.4699) (xy 0.970026 -0.4699)
			)
			(stroke
				(width 0)
				(type default)
			)
			(fill no)
			(layer "B.CrtYd")
		)
		(fp_line
			(start 0.508 -0.3048)
			(end -0.508 -0.3048)
			(stroke
				(width 0.1)
				(type default)
			)
			(layer "B.Fab")
		)
		(fp_line
			(start -0.508 -0.3048)
			(end -0.508 0.3048)
			(stroke
				(width 0.1)
				(type default)
			)
			(layer "B.Fab")
		)
		(fp_line
			(start 0.508 0.3048)
			(end 0.508 -0.3048)
			(stroke
				(width 0.1)
				(type default)
			)
			(layer "B.Fab")
		)
		(fp_line
			(start -0.508 0.3048)
			(end 0.508 0.3048)
			(stroke
				(width 0.1)
				(type default)
			)
			(layer "B.Fab")
		)
		(pad "1" smd circle
			(at 0.500126 0 270)
			(size 0.635 0.635)
			(layers "B.Cu" "B.Mask" "B.Paste")
			(net "XP1R0V_FPGA_VCCINT")
		)
		(pad "2" smd circle
			(at -0.500126 0 270)
			(size 0.635 0.635)
			(layers "B.Cu" "B.Mask" "B.Paste")
			(net "SG")
		)
	)
	(footprint ""
		(layer "B.Cu")
		(at 113.347246 -42.82313 180)
		(property "Reference" "C138"
			(at 41.909746 -1.24968 0)
			(unlocked yes)
			(layer "B.SilkS")
			(effects
				(font
					(size 0.635 0.4064)
					(thickness 0.1524)
				)
				(justify mirror)
			)
		)
		(property "Value" "VAL*"
			(at 0 3.718306 180)
			(unlocked yes)
			(layer "B.Fab")
			(hide yes)
			(effects
				(font
					(size 0.7874 0.5842)
					(thickness 0.127)
				)
				(justify mirror)
			)
		)
		(property "Tolerance" "TOL*"
			(at 0 4.861306 180)
			(unlocked yes)
			(layer "Cmts.User")
			(hide yes)
			(effects
				(font
					(size 0.7874 0.5842)
					(thickness 0.127)
				)
				(justify mirror)
			)
		)
		(property "User Part Number" "PARTNUM*"
			(at 0 2.575306 180)
			(unlocked yes)
			(layer "Cmts.User")
			(hide yes)
			(effects
				(font
					(size 0.7874 0.5842)
					(thickness 0.127)
				)
				(justify mirror)
			)
		)
		(property "Device Type" "CAPACITOR-G105-0F475-BM,4.7UF,A"
			(at 0 1.432306 180)
			(unlocked yes)
			(layer "B.Fab")
			(hide yes)
			(effects
				(font
					(size 0.7874 0.5842)
					(thickness 0.127)
				)
				(justify mirror)
			)
		)
		(duplicate_pad_numbers_are_jumpers no)
		(fp_line
			(start 0.970026 0.4699)
			(end 0.970026 -0.4699)
			(stroke
				(width 0.1)
				(type default)
			)
			(layer "B.SilkS")
		)
		(fp_line
			(start 0.970026 -0.4699)
			(end -0.970026 -0.4699)
			(stroke
				(width 0.1)
				(type default)
			)
			(layer "B.SilkS")
		)
		(fp_line
			(start -0.970026 0.4699)
			(end 0.970026 0.4699)
			(stroke
				(width 0.1)
				(type default)
			)
			(layer "B.SilkS")
		)
		(fp_line
			(start -0.970026 -0.4699)
			(end -0.970026 0.4699)
			(stroke
				(width 0.1)
				(type default)
			)
			(layer "B.SilkS")
		)
		(fp_poly
			(pts
				(xy 0.970026 0.4699) (xy -0.970026 0.4699) (xy -0.970026 -0.4699) (xy 0.970026 -0.4699)
			)
			(stroke
				(width 0)
				(type default)
			)
			(fill no)
			(layer "B.CrtYd")
		)
		(fp_line
			(start 0.508 0.3048)
			(end 0.508 -0.3048)
			(stroke
				(width 0.1)
				(type default)
			)
			(layer "B.Fab")
		)
		(fp_line
			(start 0.508 -0.3048)
			(end -0.508 -0.3048)
			(stroke
				(width 0.1)
				(type default)
			)
			(layer "B.Fab")
		)
		(fp_line
			(start -0.508 0.3048)
			(end 0.508 0.3048)
			(stroke
				(width 0.1)
				(type default)
			)
			(layer "B.Fab")
		)
		(fp_line
			(start -0.508 -0.3048)
			(end -0.508 0.3048)
			(stroke
				(width 0.1)
				(type default)
			)
			(layer "B.Fab")
		)
		(pad "1" smd circle
			(at 0.500126 0)
			(size 0.635 0.635)
			(layers "B.Cu" "B.Mask" "B.Paste")
			(net "XP1R8V_FPGA_VCCAUX")
		)
		(pad "2" smd circle
			(at -0.500126 0)
			(size 0.635 0.635)
			(layers "B.Cu" "B.Mask" "B.Paste")
			(net "SG")
		)
	)
	(footprint ""
		(layer "B.Cu")
		(at 13.462 -37.211 90)
		(property "Reference" "R492"
			(at -1.524 1.73863 270)
			(unlocked yes)
			(layer "B.SilkS")
			(effects
				(font
					(size 0.7874 0.5842)
					(thickness 0.1524)
				)
				(justify mirror)
			)
		)
		(property "Value" "VAL*"
			(at -0.02032 2.13233 90)
			(unlocked yes)
			(layer "B.Fab")
			(hide yes)
			(effects
				(font
					(size 0.7874 0.5842)
					(thickness 0.1524)
				)
				(justify mirror)
			)
		)
		(property "Tolerance" "TOL*"
			(at -0.044704 3.05435 90)
			(unlocked yes)
			(layer "Cmts.User")
			(hide yes)
			(effects
				(font
					(size 0.7874 0.5842)
					(thickness 0.1524)
				)
				(justify mirror)
			)
		)
		(property "User Part Number" "PARTNUM*"
			(at -0.02032 4.024884 90)
			(unlocked yes)
			(layer "Cmts.User")
			(hide yes)
			(effects
				(font
					(size 0.7874 0.5842)
					(thickness 0.1524)
				)
				(justify mirror)
			)
		)
		(property "Device Type" "RESISTOR-G155-100R0-J0,0OHM,-"
			(at -0.008382 1.210564 90)
			(unlocked yes)
			(layer "B.Fab")
			(hide yes)
			(effects
				(font
					(size 0.7874 0.5842)
					(thickness 0.1524)
				)
				(justify mirror)
			)
		)
		(duplicate_pad_numbers_are_jumpers no)
		(fp_line
			(start 1.143 -0.5588)
			(end 1.143 0.5588)
			(stroke
				(width 0.1)
				(type default)
			)
			(layer "B.SilkS")
		)
		(fp_line
			(start -1.143 -0.5588)
			(end 1.143 -0.5588)
			(stroke
				(width 0.1)
				(type default)
			)
			(layer "B.SilkS")
		)
		(fp_line
			(start 1.143 0.5588)
			(end -1.143 0.5588)
			(stroke
				(width 0.1)
				(type default)
			)
			(layer "B.SilkS")
		)
		(fp_line
			(start -1.143 0.5588)
			(end -1.143 -0.5588)
			(stroke
				(width 0.1)
				(type default)
			)
			(layer "B.SilkS")
		)
		(fp_poly
			(pts
				(xy 1.143 0.5588) (xy -1.143 0.5588) (xy -1.143 -0.5588) (xy 1.143 -0.5588)
			)
			(stroke
				(width 0)
				(type default)
			)
			(fill no)
			(layer "B.CrtYd")
		)
		(fp_line
			(start 0.508 -0.3048)
			(end 0.508 0.3048)
			(stroke
				(width 0.1)
				(type default)
			)
			(layer "B.Fab")
		)
		(fp_line
			(start -0.508 -0.3048)
			(end 0.508 -0.3048)
			(stroke
				(width 0.1)
				(type default)
			)
			(layer "B.Fab")
		)
		(fp_line
			(start 0.508 0.3048)
			(end -0.508 0.3048)
			(stroke
				(width 0.1)
				(type default)
			)
			(layer "B.Fab")
		)
		(fp_line
			(start -0.508 0.3048)
			(end -0.508 -0.3048)
			(stroke
				(width 0.1)
				(type default)
			)
			(layer "B.Fab")
		)
		(pad "1" smd rect
			(at 0.5334 0 270)
			(size 0.7112 0.6096)
			(layers "B.Cu" "B.Mask" "B.Paste")
			(net "UNNAMED_12_CAPACITOR_I318_2")
		)
		(pad "2" smd rect
			(at -0.5334 0 270)
			(size 0.7112 0.6096)
			(layers "B.Cu" "B.Mask" "B.Paste")
			(net "UNNAMED_12_74HCT2G125DPTSSOP8_I")
		)
		(zone
			(layer "B.Cu")
			(hatch none 0.5)
			(connect_pads
				(clearance 0)
			)
			(min_thickness 0.25)
			(keepout
				(tracks allowed)
				(vias not_allowed)
				(pads allowed)
				(copperpour not_allowed)
				(footprints allowed)
			)
			(placement
				(enabled no)
				(sheetname "")
			)
			(fill
				(thermal_gap 0.5)
				(thermal_bridge_width 0.5)
				(island_removal_mode 0)
			)
			(polygon
				(pts
					(xy 13.7668 -37.2872) (xy 13.1572 -37.2872) (xy 13.1572 -37.1348) (xy 13.7668 -37.1348)
				)
			)
		)
		(zone
			(layer "B.Cu")
			(hatch none 0.5)
			(connect_pads
				(clearance 0)
			)
			(min_thickness 0.25)
			(keepout
				(tracks not_allowed)
				(vias allowed)
				(pads allowed)
				(copperpour not_allowed)
				(footprints allowed)
			)
			(placement
				(enabled no)
				(sheetname "")
			)
			(fill
				(thermal_gap 0.5)
				(thermal_bridge_width 0.5)
				(island_removal_mode 0)
			)
			(polygon
				(pts
					(xy 13.7668 -37.2872) (xy 13.1572 -37.2872) (xy 13.1572 -37.1348) (xy 13.7668 -37.1348)
				)
			)
		)
	)
	(footprint ""
		(layer "B.Cu")
		(at 107.188 -44.45)
		(property "Reference" "C219"
			(at -43.307 1.63195 0)
			(unlocked yes)
			(layer "B.SilkS")
			(effects
				(font
					(size 0.635 0.4064)
					(thickness 0.1524)
				)
				(justify mirror)
			)
		)
		(property "Value" "VAL*"
			(at -0.0762 2.067306 0)
			(unlocked yes)
			(layer "B.Fab")
			(hide yes)
			(effects
				(font
					(size 0.7874 0.5842)
					(thickness 0.1524)
				)
				(justify mirror)
			)
		)
		(property "Device Type" "CAPACITOR-G105-0B104-CK,0.1UF,A"
			(at -0.0508 1.127506 0)
			(unlocked yes)
			(layer "B.Fab")
			(hide yes)
			(effects
				(font
					(size 0.7874 0.5842)
					(thickness 0.1524)
				)
				(justify mirror)
			)
		)
		(property "User Part Number" "PARTNUM*"
			(at -0.1016 4.023106 0)
			(unlocked yes)
			(layer "Cmts.User")
			(hide yes)
			(effects
				(font
					(size 0.7874 0.5842)
					(thickness 0.1524)
				)
				(justify mirror)
			)
		)
		(property "Tolerance" "TOL*"
			(at -0.0762 3.032506 0)
			(unlocked yes)
			(layer "Cmts.User")
			(hide yes)
			(effects
				(font
					(size 0.7874 0.5842)
					(thickness 0.1524)
				)
				(justify mirror)
			)
		)
		(duplicate_pad_numbers_are_jumpers no)
		(fp_line
			(start -1.143 -0.5588)
			(end 1.143 -0.5588)
			(stroke
				(width 0.1)
				(type default)
			)
			(layer "B.SilkS")
		)
		(fp_line
			(start -1.143 0.5588)
			(end -1.143 -0.5588)
			(stroke
				(width 0.1)
				(type default)
			)
			(layer "B.SilkS")
		)
		(fp_line
			(start 1.143 -0.5588)
			(end 1.143 0.5588)
			(stroke
				(width 0.1)
				(type default)
			)
			(layer "B.SilkS")
		)
		(fp_line
			(start 1.143 0.5588)
			(end -1.143 0.5588)
			(stroke
				(width 0.1)
				(type default)
			)
			(layer "B.SilkS")
		)
		(fp_rect
			(start -1.143 0.5588)
			(end 1.143 -0.5588)
			(stroke
				(width 0)
				(type default)
			)
			(fill no)
			(layer "B.CrtYd")
		)
		(fp_line
			(start -0.508 -0.3048)
			(end 0.508 -0.3048)
			(stroke
				(width 0.1)
				(type default)
			)
			(layer "B.Fab")
		)
		(fp_line
			(start -0.508 0.3048)
			(end -0.508 -0.3048)
			(stroke
				(width 0.1)
				(type default)
			)
			(layer "B.Fab")
		)
		(fp_line
			(start 0.508 -0.3048)
			(end 0.508 0.3048)
			(stroke
				(width 0.1)
				(type default)
			)
			(layer "B.Fab")
		)
		(fp_line
			(start 0.508 0.3048)
			(end -0.508 0.3048)
			(stroke
				(width 0.1)
				(type default)
			)
			(layer "B.Fab")
		)
		(pad "1" smd rect
			(at 0.5334 0 180)
			(size 0.7112 0.6096)
			(layers "B.Cu" "B.Mask" "B.Paste")
			(net "XP1R8V_FPGA_VCCAUX")
		)
		(pad "2" smd rect
			(at -0.5334 0 180)
			(size 0.7112 0.6096)
			(layers "B.Cu" "B.Mask" "B.Paste")
			(net "SG")
		)
		(zone
			(layer "B.Cu")
			(hatch none 0.5)
			(connect_pads
				(clearance 0)
			)
			(min_thickness 0.25)
			(keepout
				(tracks allowed)
				(vias not_allowed)
				(pads allowed)
				(copperpour not_allowed)
				(footprints allowed)
			)
			(placement
				(enabled no)
				(sheetname "")
			)
			(fill
				(thermal_gap 0.5)
				(thermal_bridge_width 0.5)
				(island_removal_mode 0)
			)
			(polygon
				(pts
					(xy 107.1118 -44.1452) (xy 107.2642 -44.1452) (xy 107.2642 -44.7548) (xy 107.1118 -44.7548)
				)
			)
		)
	)
	(gr_poly
		(pts
			(xy 1.269492 -70.485) (xy 0.763016 -70.485) (xy 0.763016 -80.137) (xy 1.269492 -80.137)
		)
		(stroke
			(width 0)
			(type solid)
		)
		(fill yes)
		(layer "F.Cu")
		(net "SG")
	)
	(gr_poly
		(pts
			(xy 166.88689 -23.4188) (xy 166.380668 -23.4188) (xy 166.380668 -48.641) (xy 166.88689 -48.641)
		)
		(stroke
			(width 0)
			(type solid)
		)
		(fill yes)
		(layer "F.Cu")
		(net "SG")
	)
	(gr_poly
		(pts
			(xy 166.882826 -110.188502) (xy 166.882826 -99.70008) (xy 157.619954 -99.70008) (xy 157.619954 -110.149894)
			(xy 157.619954 -110.37824) (xy 166.693088 -110.37824)
		)
		(stroke
			(width 0)
			(type solid)
		)
		(fill yes)
		(layer "F.Cu")
		(net "SG")
	)
	(gr_poly
		(pts
			(xy 12.7 -110.149894) (xy 12.7 -89.7001) (xy 0.999998 -89.7001) (xy 0.765302 -89.7001) (xy 0.765302 -110.148878)
			(xy 1.002538 -110.386114) (xy 12.7 -110.386114)
		)
		(stroke
			(width 0)
			(type solid)
		)
		(fill yes)
		(layer "F.Cu")
		(net "SG")
	)
	(gr_poly
		(pts
			(xy 166.874952 -13.730986) (xy 166.668958 -13.524992) (xy 157.607 -13.524992) (xy 157.607 -13.750036)
			(xy 157.619954 -13.750036) (xy 157.619954 -22.899878) (xy 166.874952 -22.899878)
		)
		(stroke
			(width 0)
			(type solid)
		)
		(fill yes)
		(layer "F.Cu")
		(net "SG")
	)
	(gr_poly
		(pts
			(xy 14.234922 -13.412978) (xy 14.234922 -5.50164) (xy 14.002004 -5.268722) (xy 1.813052 -5.268722)
			(xy 0.972058 -5.268722) (xy 0.770382 -5.470398) (xy 0.770382 -13.412978) (xy 0.770382 -13.59662)
			(xy 8.866886 -13.59662) (xy 14.234922 -13.59662)
		)
		(stroke
			(width 0)
			(type solid)
		)
		(fill yes)
		(layer "F.Cu")
		(net "SG")
	)
	(gr_poly
		(pts
			(xy 47.879 -9.652) (xy 48.387 -9.144) (xy 48.387 -8.255) (xy 47.879 -7.747) (xy 47.879 -7.239) (xy 47.752 -7.112)
			(xy 46.482 -7.112) (xy 46.3296 -7.2644) (xy 46.3296 -9.7028) (xy 46.5582 -9.9314) (xy 47.5996 -9.9314)
		)
		(stroke
			(width 0)
			(type solid)
		)
		(fill yes)
		(layer "F.Cu")
		(net "XP12R0V_PCIE")
	)
	(gr_poly
		(pts
			(arc
				(start 32.278574 -14.019276)
				(mid 32.316248 -14.002554)
				(end 32.32912 -13.963396)
			)
			(xy 32.32912 -13.58773) (xy 32.25419 -13.5128) (xy 16.229076 -13.5128) (xy 16.221202 -13.520674)
			(arc
				(start 16.221202 -13.750544)
				(mid 16.208877 -13.851978)
				(end 16.1798 -13.949934)
			)
			(arc
				(start 16.1798 -13.949934)
				(mid 16.185182 -13.997171)
				(end 16.227298 -14.019276)
			)
		)
		(stroke
			(width 0)
			(type solid)
		)
		(fill yes)
		(layer "F.Cu")
		(net "SG")
	)
	(gr_poly
		(pts
			(xy 152.019 -53.7845) (xy 152.146 -53.6575) (xy 153.035 -53.6575) (xy 153.035 -52.7685) (xy 151.003 -52.7685)
			(xy 149.352 -51.1175) (xy 149.352 -50.3555) (xy 148.463 -49.4665) (xy 148.336 -49.3395) (xy 148.336 -48.7045)
			(xy 148.209 -48.5775) (xy 147.955 -48.5775) (xy 147.193 -49.3395) (xy 147.193 -49.7205) (xy 147.32 -49.8475)
			(xy 147.447 -49.9745) (xy 147.447 -50.9905) (xy 150.114 -53.6575) (xy 151.257 -54.8005) (xy 151.257 -55.0545)
			(xy 152.019 -55.0545)
		)
		(stroke
			(width 0)
			(type solid)
		)
		(fill yes)
		(layer "F.Cu")
		(net "SG")
	)
	(gr_poly
		(pts
			(arc
				(start 1.203198 -89.238582)
				(mid 1.24873 -89.231194)
				(end 1.269492 -89.190068)
			)
			(xy 1.269492 -85.344) (xy 0.763016 -85.344)
			(arc
				(start 0.763016 -89.190068)
				(mid 0.783885 -89.231114)
				(end 0.82931 -89.238328)
			)
			(arc
				(start 0.82931 -89.238328)
				(mid 0.921393 -89.216484)
				(end 1.015746 -89.209118)
			)
			(arc
				(start 1.016 -89.209118)
				(mid 1.110754 -89.216521)
				(end 1.203198 -89.238582)
			)
		)
		(stroke
			(width 0)
			(type solid)
		)
		(fill yes)
		(layer "F.Cu")
		(net "SG")
	)
	(gr_poly
		(pts
			(arc
				(start 166.649908 -110.386876)
				(mid 166.81748 -110.317466)
				(end 166.88689 -110.149894)
			)
			(arc
				(start 166.88689 -77.688186)
				(mid 166.825907 -77.595058)
				(end 166.716202 -77.613764)
			)
			(arc
				(start 166.716202 -77.613764)
				(mid 166.581744 -77.703577)
				(end 166.42588 -77.746606)
			)
			(xy 166.380668 -77.751686) (xy 166.380668 -109.8804)
			(arc
				(start 12.925806 -109.8804)
				(mid 12.884962 -109.90134)
				(end 12.877546 -109.946694)
			)
			(arc
				(start 12.877546 -109.946694)
				(mid 12.899574 -110.039143)
				(end 12.90701 -110.133892)
			)
			(arc
				(start 12.90701 -110.134146)
				(mid 12.899669 -110.228503)
				(end 12.8778 -110.320582)
			)
			(arc
				(start 12.8778 -110.320582)
				(mid 12.885106 -110.36594)
				(end 12.92606 -110.386876)
			)
		)
		(stroke
			(width 0)
			(type solid)
		)
		(fill yes)
		(layer "F.Cu")
		(net "SG")
	)
	(gr_poly
		(pts
			(arc
				(start 165.162484 -61.648594)
				(mid 165.21545 -61.737544)
				(end 165.318948 -61.733938)
			)
			(arc
				(start 165.318948 -61.733938)
				(mid 165.468987 -61.654241)
				(end 165.630098 -61.600334)
			)
			(xy 165.668706 -61.590936)
			(arc
				(start 165.668706 -61.324998)
				(mid 166.02293 -60.447949)
				(end 166.88689 -60.062872)
			)
			(xy 166.88689 -58.42) (xy 166.380668 -58.42)
			(arc
				(start 166.380668 -59.643772)
				(mid 165.570748 -60.194326)
				(end 165.177724 -61.091318)
			)
			(arc
				(start 165.177724 -61.19749)
				(mid 165.173905 -61.259682)
				(end 165.162484 -61.320934)
			)
		)
		(stroke
			(width 0)
			(type solid)
		)
		(fill yes)
		(layer "F.Cu")
		(net "SG")
	)
	(gr_poly
		(pts
			(arc
				(start 157.207204 -14.019276)
				(mid 157.248048 -13.998336)
				(end 157.255464 -13.952982)
			)
			(arc
				(start 157.255464 -13.952982)
				(mid 157.233456 -13.860658)
				(end 157.226 -13.766038)
			)
			(arc
				(start 157.226 -13.765784)
				(mid 157.233341 -13.671427)
				(end 157.25521 -13.579348)
			)
			(arc
				(start 157.25521 -13.579348)
				(mid 157.247904 -13.53399)
				(end 157.20695 -13.513054)
			)
			(arc
				(start 80.300068 -13.513054)
				(mid 79.053429 -12.996679)
				(end 78.537054 -11.75004)
			)
			(xy 78.537054 -6.6548) (xy 78.217776 -6.6548)
			(arc
				(start 78.217776 -6.805168)
				(mid 78.170879 -7.031208)
				(end 78.037944 -7.21995)
			)
			(arc
				(start 78.037944 -11.932666)
				(mid 78.761302 -13.417973)
				(end 80.300068 -14.019276)
			)
		)
		(stroke
			(width 0)
			(type solid)
		)
		(fill yes)
		(layer "F.Cu")
		(net "SG")
	)
	(gr_poly
		(pts
			(xy 39.514018 -26.934922) (xy 39.513521 -26.857068) (xy 39.50557 -26.701562) (xy 39.48969 -26.546665)
			(xy 39.465921 -26.392781) (xy 39.434326 -26.240311) (xy 39.394986 -26.089654) (xy 39.348006 -25.941202)
			(xy 39.293506 -25.795342) (xy 39.23163 -25.652455) (xy 39.162539 -25.512914) (xy 39.086413 -25.377083)
			(xy 39.003451 -25.245316) (xy 38.913869 -25.117957) (xy 38.8179 -24.995339) (xy 38.715796 -24.87778)
			(xy 38.607823 -24.765589) (xy 38.494261 -24.659057) (xy 38.375409 -24.558462) (xy 38.251575 -24.464068)
			(xy 38.123082 -24.376119) (xy 37.990267 -24.294846) (xy 37.853474 -24.220461) (xy 37.713063 -24.153157)
			(xy 37.569397 -24.093111) (xy 37.422853 -24.040479) (xy 37.273813 -23.995398) (xy 37.122666 -23.957986)
			(xy 36.969805 -23.92834) (xy 36.81563 -23.906539) (xy 36.660543 -23.892638) (xy 36.504948 -23.886674)
			(xy 36.349252 -23.888662) (xy 36.193861 -23.898598) (xy 36.039179 -23.916455) (xy 35.885611 -23.942187)
			(xy 35.733558 -23.975727) (xy 35.583415 -24.016987) (xy 35.435575 -24.065859) (xy 35.290423 -24.122217)
			(xy 35.148338 -24.185913) (xy 35.009691 -24.25678) (xy 34.874843 -24.334634) (xy 34.744146 -24.419273)
			(xy 34.617942 -24.510474) (xy 34.496559 -24.608) (xy 34.380314 -24.711598) (xy 34.26951 -24.820995)
			(xy 34.164437 -24.935908) (xy 34.065368 -25.056035) (xy 33.972563 -25.181065) (xy 33.886262 -25.31067)
			(xy 33.806692 -25.444512) (xy 33.73406 -25.582243) (xy 33.668555 -25.723503) (xy 33.610348 -25.867924)
			(xy 33.559592 -26.015128) (xy 33.516418 -26.164731) (xy 33.480939 -26.316344) (xy 33.453248 -26.469571)
			(xy 33.433417 -26.624012) (xy 33.421498 -26.779264) (xy 33.417521 -26.934922) (xy 34.878023 -26.934922)
			(xy 34.881979 -26.822906) (xy 34.893826 -26.711449) (xy 34.913506 -26.601105) (xy 34.94092 -26.492424)
			(xy 34.975932 -26.385947) (xy 35.018368 -26.282206) (xy 35.068016 -26.181716) (xy 35.124629 -26.084979)
			(xy 35.187925 -25.992476) (xy 35.257587 -25.904668) (xy 35.333271 -25.821993) (xy 35.414597 -25.744862)
			(xy 35.501162 -25.67366) (xy 35.592533 -25.608742) (xy 35.688257 -25.550431) (xy 35.787855 -25.499017)
			(xy 35.890831 -25.454757) (xy 35.996673 -25.417871) (xy 36.104853 -25.388543) (xy 36.214833 -25.366919)
			(xy 36.326064 -25.353106) (xy 36.437992 -25.347174) (xy 36.55006 -25.349152) (xy 36.661709 -25.359031)
			(xy 36.772384 -25.37676) (xy 36.881532 -25.402252) (xy 36.988609 -25.43538) (xy 37.093084 -25.475978)
			(xy 37.194434 -25.523845) (xy 37.292156 -25.578742) (xy 37.385761 -25.640395) (xy 37.474785 -25.708497)
			(xy 37.558783 -25.78271) (xy 37.637337 -25.862662) (xy 37.710055 -25.947957) (xy 37.776576 -26.038168)
			(xy 37.836567 -26.132848) (xy 37.889731 -26.231523) (xy 37.935801 -26.333702) (xy 37.974549 -26.438877)
			(xy 38.005782 -26.546522) (xy 38.029344 -26.656103) (xy 38.045117 -26.767073) (xy 38.053024 -26.878879)
			(xy 38.053518 -26.934922) (xy 38.053024 -26.990965) (xy 38.045117 -27.102771) (xy 38.029344 -27.213741)
			(xy 38.005782 -27.323322) (xy 37.974549 -27.430967) (xy 37.935801 -27.536142) (xy 37.889731 -27.638321)
			(xy 37.836567 -27.736996) (xy 37.776576 -27.831676) (xy 37.710055 -27.921887) (xy 37.637337 -28.007182)
			(xy 37.558783 -28.087134) (xy 37.474785 -28.161347) (xy 37.385761 -28.229449) (xy 37.292156 -28.291102)
			(xy 37.194434 -28.345999) (xy 37.093084 -28.393866) (xy 36.988609 -28.434464) (xy 36.881532 -28.467592)
			(xy 36.772384 -28.493084) (xy 36.661709 -28.510813) (xy 36.55006 -28.520692) (xy 36.437992 -28.52267)
			(xy 36.326064 -28.516738) (xy 36.214833 -28.502925) (xy 36.104853 -28.481301) (xy 35.996673 -28.451973)
			(xy 35.890831 -28.415087) (xy 35.787855 -28.370827) (xy 35.688257 -28.319413) (xy 35.592533 -28.261102)
			(xy 35.501162 -28.196184) (xy 35.414597 -28.124982) (xy 35.333271 -28.047851) (xy 35.257587 -27.965176)
			(xy 35.187925 -27.877368) (xy 35.124629 -27.784865) (xy 35.068016 -27.688128) (xy 35.018368 -27.587638)
			(xy 34.975932 -27.483897) (xy 34.94092 -27.37742) (xy 34.913506 -27.268739) (xy 34.893826 -27.158395)
			(xy 34.881979 -27.046938) (xy 34.878023 -26.934922) (xy 33.417521 -26.934922) (xy 33.421498 -27.09058)
			(xy 33.433417 -27.245832) (xy 33.453248 -27.400273) (xy 33.480939 -27.5535) (xy 33.516418 -27.705113)
			(xy 33.559592 -27.854716) (xy 33.610348 -28.00192) (xy 33.668555 -28.146341) (xy 33.73406 -28.287601)
			(xy 33.806692 -28.425332) (xy 33.886262 -28.559174) (xy 33.972563 -28.688779) (xy 34.065368 -28.813809)
			(xy 34.164437 -28.933936) (xy 34.26951 -29.048849) (xy 34.380314 -29.158246) (xy 34.496559 -29.261844)
			(xy 34.617942 -29.35937) (xy 34.744146 -29.450571) (xy 34.874843 -29.53521) (xy 35.009691 -29.613064)
			(xy 35.148338 -29.683931) (xy 35.290423 -29.747627) (xy 35.435575 -29.803985) (xy 35.583415 -29.852857)
			(xy 35.733558 -29.894117) (xy 35.885611 -29.927657) (xy 36.039179 -29.953389) (xy 36.193861 -29.971246)
			(xy 36.349252 -29.981182) (xy 36.504948 -29.98317) (xy 36.660543 -29.977206) (xy 36.81563 -29.963305)
			(xy 36.969805 -29.941504) (xy 37.122666 -29.911858) (xy 37.273813 -29.874446) (xy 37.422853 -29.829365)
			(xy 37.569397 -29.776733) (xy 37.713063 -29.716687) (xy 37.853474 -29.649383) (xy 37.990267 -29.574998)
			(xy 38.123082 -29.493725) (xy 38.251575 -29.405776) (xy 38.375409 -29.311382) (xy 38.494261 -29.210787)
			(xy 38.607823 -29.104255) (xy 38.715796 -28.992064) (xy 38.8179 -28.874505) (xy 38.913869 -28.751887)
			(xy 39.003451 -28.624528) (xy 39.086413 -28.492761) (xy 39.162539 -28.35693) (xy 39.23163 -28.217389)
			(xy 39.293506 -28.074502) (xy 39.348006 -27.928642) (xy 39.394986 -27.78019) (xy 39.434326 -27.629533)
			(xy 39.465921 -27.477063) (xy 39.48969 -27.323179) (xy 39.50557 -27.168282) (xy 39.513521 -27.012776)
		)
		(stroke
			(width 0)
			(type solid)
		)
		(fill yes)
		(layer "F.Cu")
		(net "Net_304")
	)
	(gr_poly
		(pts
			(xy 40.149018 -68.082922) (xy 40.148521 -68.005068) (xy 40.14057 -67.849562) (xy 40.12469 -67.694665)
			(xy 40.100921 -67.540781) (xy 40.069326 -67.388311) (xy 40.029986 -67.237654) (xy 39.983006 -67.089202)
			(xy 39.928506 -66.943342) (xy 39.86663 -66.800455) (xy 39.797539 -66.660914) (xy 39.721413 -66.525083)
			(xy 39.638451 -66.393316) (xy 39.548869 -66.265957) (xy 39.4529 -66.143339) (xy 39.350796 -66.02578)
			(xy 39.242823 -65.913589) (xy 39.129261 -65.807057) (xy 39.010409 -65.706462) (xy 38.886575 -65.612068)
			(xy 38.758082 -65.524119) (xy 38.625267 -65.442846) (xy 38.488474 -65.368461) (xy 38.348063 -65.301157)
			(xy 38.204397 -65.241111) (xy 38.057853 -65.188479) (xy 37.908813 -65.143398) (xy 37.757666 -65.105986)
			(xy 37.604805 -65.07634) (xy 37.45063 -65.054539) (xy 37.295543 -65.040638) (xy 37.139948 -65.034674)
			(xy 36.984252 -65.036662) (xy 36.828861 -65.046598) (xy 36.674179 -65.064455) (xy 36.520611 -65.090187)
			(xy 36.368558 -65.123727) (xy 36.218415 -65.164987) (xy 36.070575 -65.213859) (xy 35.925423 -65.270217)
			(xy 35.783338 -65.333913) (xy 35.644691 -65.40478) (xy 35.509843 -65.482634) (xy 35.379146 -65.567273)
			(xy 35.252942 -65.658474) (xy 35.131559 -65.756) (xy 35.015314 -65.859598) (xy 34.90451 -65.968995)
			(xy 34.799437 -66.083908) (xy 34.700368 -66.204035) (xy 34.607563 -66.329065) (xy 34.521262 -66.45867)
			(xy 34.441692 -66.592512) (xy 34.36906 -66.730243) (xy 34.303555 -66.871503) (xy 34.245348 -67.015924)
			(xy 34.194592 -67.163128) (xy 34.151418 -67.312731) (xy 34.115939 -67.464344) (xy 34.088248 -67.617571)
			(xy 34.068417 -67.772012) (xy 34.056498 -67.927264) (xy 34.052521 -68.082922) (xy 35.513023 -68.082922)
			(xy 35.516979 -67.970906) (xy 35.528826 -67.859449) (xy 35.548506 -67.749105) (xy 35.57592 -67.640424)
			(xy 35.610932 -67.533947) (xy 35.653368 -67.430206) (xy 35.703016 -67.329716) (xy 35.759629 -67.232979)
			(xy 35.822925 -67.140476) (xy 35.892587 -67.052668) (xy 35.968271 -66.969993) (xy 36.049597 -66.892862)
			(xy 36.136162 -66.82166) (xy 36.227533 -66.756742) (xy 36.323257 -66.698431) (xy 36.422855 -66.647017)
			(xy 36.525831 -66.602757) (xy 36.631673 -66.565871) (xy 36.739853 -66.536543) (xy 36.849833 -66.514919)
			(xy 36.961064 -66.501106) (xy 37.072992 -66.495174) (xy 37.18506 -66.497152) (xy 37.296709 -66.507031)
			(xy 37.407384 -66.52476) (xy 37.516532 -66.550252) (xy 37.623609 -66.58338) (xy 37.728084 -66.623978)
			(xy 37.829434 -66.671845) (xy 37.927156 -66.726742) (xy 38.020761 -66.788395) (xy 38.109785 -66.856497)
			(xy 38.193783 -66.93071) (xy 38.272337 -67.010662) (xy 38.345055 -67.095957) (xy 38.411576 -67.186168)
			(xy 38.471567 -67.280848) (xy 38.524731 -67.379523) (xy 38.570801 -67.481702) (xy 38.609549 -67.586877)
			(xy 38.640782 -67.694522) (xy 38.664344 -67.804103) (xy 38.680117 -67.915073) (xy 38.688024 -68.026879)
			(xy 38.688518 -68.082922) (xy 38.688024 -68.138965) (xy 38.680117 -68.250771) (xy 38.664344 -68.361741)
			(xy 38.640782 -68.471322) (xy 38.609549 -68.578967) (xy 38.570801 -68.684142) (xy 38.524731 -68.786321)
			(xy 38.471567 -68.884996) (xy 38.411576 -68.979676) (xy 38.345055 -69.069887) (xy 38.272337 -69.155182)
			(xy 38.193783 -69.235134) (xy 38.109785 -69.309347) (xy 38.020761 -69.377449) (xy 37.927156 -69.439102)
			(xy 37.829434 -69.493999) (xy 37.728084 -69.541866) (xy 37.623609 -69.582464) (xy 37.516532 -69.615592)
			(xy 37.407384 -69.641084) (xy 37.296709 -69.658813) (xy 37.18506 -69.668692) (xy 37.072992 -69.67067)
			(xy 36.961064 -69.664738) (xy 36.849833 -69.650925) (xy 36.739853 -69.629301) (xy 36.631673 -69.599973)
			(xy 36.525831 -69.563087) (xy 36.422855 -69.518827) (xy 36.323257 -69.467413) (xy 36.227533 -69.409102)
			(xy 36.136162 -69.344184) (xy 36.049597 -69.272982) (xy 35.968271 -69.195851) (xy 35.892587 -69.113176)
			(xy 35.822925 -69.025368) (xy 35.759629 -68.932865) (xy 35.703016 -68.836128) (xy 35.653368 -68.735638)
			(xy 35.610932 -68.631897) (xy 35.57592 -68.52542) (xy 35.548506 -68.416739) (xy 35.528826 -68.306395)
			(xy 35.516979 -68.194938) (xy 35.513023 -68.082922) (xy 34.052521 -68.082922) (xy 34.056498 -68.23858)
			(xy 34.068417 -68.393832) (xy 34.088248 -68.548273) (xy 34.115939 -68.7015) (xy 34.151418 -68.853113)
			(xy 34.194592 -69.002716) (xy 34.245348 -69.14992) (xy 34.303555 -69.294341) (xy 34.36906 -69.435601)
			(xy 34.441692 -69.573332) (xy 34.521262 -69.707174) (xy 34.607563 -69.836779) (xy 34.700368 -69.961809)
			(xy 34.799437 -70.081936) (xy 34.90451 -70.196849) (xy 35.015314 -70.306246) (xy 35.131559 -70.409844)
			(xy 35.252942 -70.50737) (xy 35.379146 -70.598571) (xy 35.509843 -70.68321) (xy 35.644691 -70.761064)
			(xy 35.783338 -70.831931) (xy 35.925423 -70.895627) (xy 36.070575 -70.951985) (xy 36.218415 -71.000857)
			(xy 36.368558 -71.042117) (xy 36.520611 -71.075657) (xy 36.674179 -71.101389) (xy 36.828861 -71.119246)
			(xy 36.984252 -71.129182) (xy 37.139948 -71.13117) (xy 37.295543 -71.125206) (xy 37.45063 -71.111305)
			(xy 37.604805 -71.089504) (xy 37.757666 -71.059858) (xy 37.908813 -71.022446) (xy 38.057853 -70.977365)
			(xy 38.204397 -70.924733) (xy 38.348063 -70.864687) (xy 38.488474 -70.797383) (xy 38.625267 -70.722998)
			(xy 38.758082 -70.641725) (xy 38.886575 -70.553776) (xy 39.010409 -70.459382) (xy 39.129261 -70.358787)
			(xy 39.242823 -70.252255) (xy 39.350796 -70.140064) (xy 39.4529 -70.022505) (xy 39.548869 -69.899887)
			(xy 39.638451 -69.772528) (xy 39.721413 -69.640761) (xy 39.797539 -69.50493) (xy 39.86663 -69.365389)
			(xy 39.928506 -69.222502) (xy 39.983006 -69.076642) (xy 40.029986 -68.92819) (xy 40.069326 -68.777533)
			(xy 40.100921 -68.625063) (xy 40.12469 -68.471179) (xy 40.14057 -68.316282) (xy 40.148521 -68.160776)
		)
		(stroke
			(width 0)
			(type solid)
		)
		(fill yes)
		(layer "F.Cu")
		(net "Net_302")
	)
	(gr_poly
		(pts
			(xy 71.264018 -65.009522) (xy 71.263521 -64.931668) (xy 71.25557 -64.776162) (xy 71.23969 -64.621265)
			(xy 71.215921 -64.467381) (xy 71.184326 -64.314911) (xy 71.144986 -64.164254) (xy 71.098006 -64.015802)
			(xy 71.043506 -63.869942) (xy 70.98163 -63.727055) (xy 70.912539 -63.587514) (xy 70.836413 -63.451683)
			(xy 70.753451 -63.319916) (xy 70.663869 -63.192557) (xy 70.5679 -63.069939) (xy 70.465796 -62.95238)
			(xy 70.357823 -62.840189) (xy 70.244261 -62.733657) (xy 70.125409 -62.633062) (xy 70.001575 -62.538668)
			(xy 69.873082 -62.450719) (xy 69.740267 -62.369446) (xy 69.603474 -62.295061) (xy 69.463063 -62.227757)
			(xy 69.319397 -62.167711) (xy 69.172853 -62.115079) (xy 69.023813 -62.069998) (xy 68.872666 -62.032586)
			(xy 68.719805 -62.00294) (xy 68.56563 -61.981139) (xy 68.410543 -61.967238) (xy 68.254948 -61.961274)
			(xy 68.099252 -61.963262) (xy 67.943861 -61.973198) (xy 67.789179 -61.991055) (xy 67.635611 -62.016787)
			(xy 67.483558 -62.050327) (xy 67.333415 -62.091587) (xy 67.185575 -62.140459) (xy 67.040423 -62.196817)
			(xy 66.898338 -62.260513) (xy 66.759691 -62.33138) (xy 66.624843 -62.409234) (xy 66.494146 -62.493873)
			(xy 66.367942 -62.585074) (xy 66.246559 -62.6826) (xy 66.130314 -62.786198) (xy 66.01951 -62.895595)
			(xy 65.914437 -63.010508) (xy 65.815368 -63.130635) (xy 65.722563 -63.255665) (xy 65.636262 -63.38527)
			(xy 65.556692 -63.519112) (xy 65.48406 -63.656843) (xy 65.418555 -63.798103) (xy 65.360348 -63.942524)
			(xy 65.309592 -64.089728) (xy 65.266418 -64.239331) (xy 65.230939 -64.390944) (xy 65.203248 -64.544171)
			(xy 65.183417 -64.698612) (xy 65.171498 -64.853864) (xy 65.167521 -65.009522) (xy 66.628023 -65.009522)
			(xy 66.631979 -64.897506) (xy 66.643826 -64.786049) (xy 66.663506 -64.675705) (xy 66.69092 -64.567024)
			(xy 66.725932 -64.460547) (xy 66.768368 -64.356806) (xy 66.818016 -64.256316) (xy 66.874629 -64.159579)
			(xy 66.937925 -64.067076) (xy 67.007587 -63.979268) (xy 67.083271 -63.896593) (xy 67.164597 -63.819462)
			(xy 67.251162 -63.74826) (xy 67.342533 -63.683342) (xy 67.438257 -63.625031) (xy 67.537855 -63.573617)
			(xy 67.640831 -63.529357) (xy 67.746673 -63.492471) (xy 67.854853 -63.463143) (xy 67.964833 -63.441519)
			(xy 68.076064 -63.427706) (xy 68.187992 -63.421774) (xy 68.30006 -63.423752) (xy 68.411709 -63.433631)
			(xy 68.522384 -63.45136) (xy 68.631532 -63.476852) (xy 68.738609 -63.50998) (xy 68.843084 -63.550578)
			(xy 68.944434 -63.598445) (xy 69.042156 -63.653342) (xy 69.135761 -63.714995) (xy 69.224785 -63.783097)
			(xy 69.308783 -63.85731) (xy 69.387337 -63.937262) (xy 69.460055 -64.022557) (xy 69.526576 -64.112768)
			(xy 69.586567 -64.207448) (xy 69.639731 -64.306123) (xy 69.685801 -64.408302) (xy 69.724549 -64.513477)
			(xy 69.755782 -64.621122) (xy 69.779344 -64.730703) (xy 69.795117 -64.841673) (xy 69.803024 -64.953479)
			(xy 69.803518 -65.009522) (xy 69.803024 -65.065565) (xy 69.795117 -65.177371) (xy 69.779344 -65.288341)
			(xy 69.755782 -65.397922) (xy 69.724549 -65.505567) (xy 69.685801 -65.610742) (xy 69.639731 -65.712921)
			(xy 69.586567 -65.811596) (xy 69.526576 -65.906276) (xy 69.460055 -65.996487) (xy 69.387337 -66.081782)
			(xy 69.308783 -66.161734) (xy 69.224785 -66.235947) (xy 69.135761 -66.304049) (xy 69.042156 -66.365702)
			(xy 68.944434 -66.420599) (xy 68.843084 -66.468466) (xy 68.738609 -66.509064) (xy 68.631532 -66.542192)
			(xy 68.522384 -66.567684) (xy 68.411709 -66.585413) (xy 68.30006 -66.595292) (xy 68.187992 -66.59727)
			(xy 68.076064 -66.591338) (xy 67.964833 -66.577525) (xy 67.854853 -66.555901) (xy 67.746673 -66.526573)
			(xy 67.640831 -66.489687) (xy 67.537855 -66.445427) (xy 67.438257 -66.394013) (xy 67.342533 -66.335702)
			(xy 67.251162 -66.270784) (xy 67.164597 -66.199582) (xy 67.083271 -66.122451) (xy 67.007587 -66.039776)
			(xy 66.937925 -65.951968) (xy 66.874629 -65.859465) (xy 66.818016 -65.762728) (xy 66.768368 -65.662238)
			(xy 66.725932 -65.558497) (xy 66.69092 -65.45202) (xy 66.663506 -65.343339) (xy 66.643826 -65.232995)
			(xy 66.631979 -65.121538) (xy 66.628023 -65.009522) (xy 65.167521 -65.009522) (xy 65.171498 -65.16518)
			(xy 65.183417 -65.320432) (xy 65.203248 -65.474873) (xy 65.230939 -65.6281) (xy 65.266418 -65.779713)
			(xy 65.309592 -65.929316) (xy 65.360348 -66.07652) (xy 65.418555 -66.220941) (xy 65.48406 -66.362201)
			(xy 65.556692 -66.499932) (xy 65.636262 -66.633774) (xy 65.722563 -66.763379) (xy 65.815368 -66.888409)
			(xy 65.914437 -67.008536) (xy 66.01951 -67.123449) (xy 66.130314 -67.232846) (xy 66.246559 -67.336444)
			(xy 66.367942 -67.43397) (xy 66.494146 -67.525171) (xy 66.624843 -67.60981) (xy 66.759691 -67.687664)
			(xy 66.898338 -67.758531) (xy 67.040423 -67.822227) (xy 67.185575 -67.878585) (xy 67.333415 -67.927457)
			(xy 67.483558 -67.968717) (xy 67.635611 -68.002257) (xy 67.789179 -68.027989) (xy 67.943861 -68.045846)
			(xy 68.099252 -68.055782) (xy 68.254948 -68.05777) (xy 68.410543 -68.051806) (xy 68.56563 -68.037905)
			(xy 68.719805 -68.016104) (xy 68.872666 -67.986458) (xy 69.023813 -67.949046) (xy 69.172853 -67.903965)
			(xy 69.319397 -67.851333) (xy 69.463063 -67.791287) (xy 69.603474 -67.723983) (xy 69.740267 -67.649598)
			(xy 69.873082 -67.568325) (xy 70.001575 -67.480376) (xy 70.125409 -67.385982) (xy 70.244261 -67.285387)
			(xy 70.357823 -67.178855) (xy 70.465796 -67.066664) (xy 70.5679 -66.949105) (xy 70.663869 -66.826487)
			(xy 70.753451 -66.699128) (xy 70.836413 -66.567361) (xy 70.912539 -66.43153) (xy 70.98163 -66.291989)
			(xy 71.043506 -66.149102) (xy 71.098006 -66.003242) (xy 71.144986 -65.85479) (xy 71.184326 -65.704133)
			(xy 71.215921 -65.551663) (xy 71.23969 -65.397779) (xy 71.25557 -65.242882) (xy 71.263521 -65.087376)
		)
		(stroke
			(width 0)
			(type solid)
		)
		(fill yes)
		(layer "F.Cu")
		(net "Net_300")
	)
	(gr_poly
		(pts
			(xy 71.264018 -28.484322) (xy 71.263521 -28.406468) (xy 71.25557 -28.250962) (xy 71.23969 -28.096065)
			(xy 71.215921 -27.942181) (xy 71.184326 -27.789711) (xy 71.144986 -27.639054) (xy 71.098006 -27.490602)
			(xy 71.043506 -27.344742) (xy 70.98163 -27.201855) (xy 70.912539 -27.062314) (xy 70.836413 -26.926483)
			(xy 70.753451 -26.794716) (xy 70.663869 -26.667357) (xy 70.5679 -26.544739) (xy 70.465796 -26.42718)
			(xy 70.357823 -26.314989) (xy 70.244261 -26.208457) (xy 70.125409 -26.107862) (xy 70.001575 -26.013468)
			(xy 69.873082 -25.925519) (xy 69.740267 -25.844246) (xy 69.603474 -25.769861) (xy 69.463063 -25.702557)
			(xy 69.319397 -25.642511) (xy 69.172853 -25.589879) (xy 69.023813 -25.544798) (xy 68.872666 -25.507386)
			(xy 68.719805 -25.47774) (xy 68.56563 -25.455939) (xy 68.410543 -25.442038) (xy 68.254948 -25.436074)
			(xy 68.099252 -25.438062) (xy 67.943861 -25.447998) (xy 67.789179 -25.465855) (xy 67.635611 -25.491587)
			(xy 67.483558 -25.525127) (xy 67.333415 -25.566387) (xy 67.185575 -25.615259) (xy 67.040423 -25.671617)
			(xy 66.898338 -25.735313) (xy 66.759691 -25.80618) (xy 66.624843 -25.884034) (xy 66.494146 -25.968673)
			(xy 66.367942 -26.059874) (xy 66.246559 -26.1574) (xy 66.130314 -26.260998) (xy 66.01951 -26.370395)
			(xy 65.914437 -26.485308) (xy 65.815368 -26.605435) (xy 65.722563 -26.730465) (xy 65.636262 -26.86007)
			(xy 65.556692 -26.993912) (xy 65.48406 -27.131643) (xy 65.418555 -27.272903) (xy 65.360348 -27.417324)
			(xy 65.309592 -27.564528) (xy 65.266418 -27.714131) (xy 65.230939 -27.865744) (xy 65.203248 -28.018971)
			(xy 65.183417 -28.173412) (xy 65.171498 -28.328664) (xy 65.167521 -28.484322) (xy 66.628023 -28.484322)
			(xy 66.631979 -28.372306) (xy 66.643826 -28.260849) (xy 66.663506 -28.150505) (xy 66.69092 -28.041824)
			(xy 66.725932 -27.935347) (xy 66.768368 -27.831606) (xy 66.818016 -27.731116) (xy 66.874629 -27.634379)
			(xy 66.937925 -27.541876) (xy 67.007587 -27.454068) (xy 67.083271 -27.371393) (xy 67.164597 -27.294262)
			(xy 67.251162 -27.22306) (xy 67.342533 -27.158142) (xy 67.438257 -27.099831) (xy 67.537855 -27.048417)
			(xy 67.640831 -27.004157) (xy 67.746673 -26.967271) (xy 67.854853 -26.937943) (xy 67.964833 -26.916319)
			(xy 68.076064 -26.902506) (xy 68.187992 -26.896574) (xy 68.30006 -26.898552) (xy 68.411709 -26.908431)
			(xy 68.522384 -26.92616) (xy 68.631532 -26.951652) (xy 68.738609 -26.98478) (xy 68.843084 -27.025378)
			(xy 68.944434 -27.073245) (xy 69.042156 -27.128142) (xy 69.135761 -27.189795) (xy 69.224785 -27.257897)
			(xy 69.308783 -27.33211) (xy 69.387337 -27.412062) (xy 69.460055 -27.497357) (xy 69.526576 -27.587568)
			(xy 69.586567 -27.682248) (xy 69.639731 -27.780923) (xy 69.685801 -27.883102) (xy 69.724549 -27.988277)
			(xy 69.755782 -28.095922) (xy 69.779344 -28.205503) (xy 69.795117 -28.316473) (xy 69.803024 -28.428279)
			(xy 69.803518 -28.484322) (xy 69.803024 -28.540365) (xy 69.795117 -28.652171) (xy 69.779344 -28.763141)
			(xy 69.755782 -28.872722) (xy 69.724549 -28.980367) (xy 69.685801 -29.085542) (xy 69.639731 -29.187721)
			(xy 69.586567 -29.286396) (xy 69.526576 -29.381076) (xy 69.460055 -29.471287) (xy 69.387337 -29.556582)
			(xy 69.308783 -29.636534) (xy 69.224785 -29.710747) (xy 69.135761 -29.778849) (xy 69.042156 -29.840502)
			(xy 68.944434 -29.895399) (xy 68.843084 -29.943266) (xy 68.738609 -29.983864) (xy 68.631532 -30.016992)
			(xy 68.522384 -30.042484) (xy 68.411709 -30.060213) (xy 68.30006 -30.070092) (xy 68.187992 -30.07207)
			(xy 68.076064 -30.066138) (xy 67.964833 -30.052325) (xy 67.854853 -30.030701) (xy 67.746673 -30.001373)
			(xy 67.640831 -29.964487) (xy 67.537855 -29.920227) (xy 67.438257 -29.868813) (xy 67.342533 -29.810502)
			(xy 67.251162 -29.745584) (xy 67.164597 -29.674382) (xy 67.083271 -29.597251) (xy 67.007587 -29.514576)
			(xy 66.937925 -29.426768) (xy 66.874629 -29.334265) (xy 66.818016 -29.237528) (xy 66.768368 -29.137038)
			(xy 66.725932 -29.033297) (xy 66.69092 -28.92682) (xy 66.663506 -28.818139) (xy 66.643826 -28.707795)
			(xy 66.631979 -28.596338) (xy 66.628023 -28.484322) (xy 65.167521 -28.484322) (xy 65.171498 -28.63998)
			(xy 65.183417 -28.795232) (xy 65.203248 -28.949673) (xy 65.230939 -29.1029) (xy 65.266418 -29.254513)
			(xy 65.309592 -29.404116) (xy 65.360348 -29.55132) (xy 65.418555 -29.695741) (xy 65.48406 -29.837001)
			(xy 65.556692 -29.974732) (xy 65.636262 -30.108574) (xy 65.722563 -30.238179) (xy 65.815368 -30.363209)
			(xy 65.914437 -30.483336) (xy 66.01951 -30.598249) (xy 66.130314 -30.707646) (xy 66.246559 -30.811244)
			(xy 66.367942 -30.90877) (xy 66.494146 -30.999971) (xy 66.624843 -31.08461) (xy 66.759691 -31.162464)
			(xy 66.898338 -31.233331) (xy 67.040423 -31.297027) (xy 67.185575 -31.353385) (xy 67.333415 -31.402257)
			(xy 67.483558 -31.443517) (xy 67.635611 -31.477057) (xy 67.789179 -31.502789) (xy 67.943861 -31.520646)
			(xy 68.099252 -31.530582) (xy 68.254948 -31.53257) (xy 68.410543 -31.526606) (xy 68.56563 -31.512705)
			(xy 68.719805 -31.490904) (xy 68.872666 -31.461258) (xy 69.023813 -31.423846) (xy 69.172853 -31.378765)
			(xy 69.319397 -31.326133) (xy 69.463063 -31.266087) (xy 69.603474 -31.198783) (xy 69.740267 -31.124398)
			(xy 69.873082 -31.043125) (xy 70.001575 -30.955176) (xy 70.125409 -30.860782) (xy 70.244261 -30.760187)
			(xy 70.357823 -30.653655) (xy 70.465796 -30.541464) (xy 70.5679 -30.423905) (xy 70.663869 -30.301287)
			(xy 70.753451 -30.173928) (xy 70.836413 -30.042161) (xy 70.912539 -29.90633) (xy 70.98163 -29.766789)
			(xy 71.043506 -29.623902) (xy 71.098006 -29.478042) (xy 71.144986 -29.32959) (xy 71.184326 -29.178933)
			(xy 71.215921 -29.026463) (xy 71.23969 -28.872579) (xy 71.25557 -28.717682) (xy 71.263521 -28.562176)
		)
		(stroke
			(width 0)
			(type solid)
		)
		(fill yes)
		(layer "F.Cu")
		(net "Net_2")
	)
	(gr_poly
		(pts
			(xy 10.497312 -94.749874) (xy 10.496815 -94.67269) (xy 10.488868 -94.518525) (xy 10.472996 -94.364975)
			(xy 10.44924 -94.212445) (xy 10.417664 -94.06134) (xy 10.37835 -93.912061) (xy 10.331405 -93.765003)
			(xy 10.276951 -93.620558) (xy 10.215133 -93.479107) (xy 10.146116 -93.341026) (xy 10.070081 -93.206681)
			(xy 9.987232 -93.076428) (xy 9.897788 -92.950613) (xy 9.801985 -92.82957) (xy 9.700078 -92.713618)
			(xy 9.592337 -92.603067) (xy 9.479048 -92.498208) (xy 9.360511 -92.39932) (xy 9.237041 -92.306666)
			(xy 9.108965 -92.220491) (xy 8.976622 -92.141023) (xy 8.840364 -92.068473) (xy 8.700551 -92.003034)
			(xy 8.557556 -91.944878) (xy 8.411756 -91.894162) (xy 8.263539 -91.851018) (xy 8.113297 -91.815561)
			(xy 7.961429 -91.787886) (xy 7.808338 -91.768065) (xy 7.65443 -91.756152) (xy 7.500112 -91.752177)
			(xy 7.345794 -91.756152) (xy 7.191886 -91.768065) (xy 7.038795 -91.787886) (xy 6.886927 -91.815561)
			(xy 6.736685 -91.851018) (xy 6.588468 -91.894162) (xy 6.442668 -91.944878) (xy 6.299673 -92.003034)
			(xy 6.15986 -92.068473) (xy 6.023602 -92.141023) (xy 5.891259 -92.220491) (xy 5.763183 -92.306666)
			(xy 5.639713 -92.39932) (xy 5.521176 -92.498208) (xy 5.407887 -92.603067) (xy 5.300146 -92.713618)
			(xy 5.198239 -92.82957) (xy 5.102436 -92.950613) (xy 5.012992 -93.076428) (xy 4.930143 -93.206681)
			(xy 4.854108 -93.341026) (xy 4.785091 -93.479107) (xy 4.723273 -93.620558) (xy 4.668819 -93.765003)
			(xy 4.621874 -93.912061) (xy 4.58256 -94.06134) (xy 4.550984 -94.212445) (xy 4.527228 -94.364975)
			(xy 4.511356 -94.518525) (xy 4.503409 -94.67269) (xy 4.503409 -94.749874) (xy 5.594612 -94.749874)
			(xy 5.598608 -94.626531) (xy 5.61058 -94.503706) (xy 5.630477 -94.381913) (xy 5.658216 -94.261664)
			(xy 5.693681 -94.143462) (xy 5.736722 -94.027804) (xy 5.787159 -93.915174) (xy 5.844782 -93.806046)
			(xy 5.909347 -93.700876) (xy 5.980585 -93.600106) (xy 6.058196 -93.504158) (xy 6.141855 -93.413436)
			(xy 6.231211 -93.328319) (xy 6.325889 -93.249164) (xy 6.425492 -93.176304) (xy 6.529602 -93.110044)
			(xy 6.637784 -93.050662) (xy 6.749582 -92.998408) (xy 6.864528 -92.953499) (xy 6.98214 -92.916125)
			(xy 7.101924 -92.886443) (xy 7.223379 -92.864576) (xy 7.345994 -92.850617) (xy 7.469256 -92.844624)
			(xy 7.592647 -92.846622) (xy 7.71565 -92.856603) (xy 7.837749 -92.874526) (xy 7.958432 -92.900314)
			(xy 8.077193 -92.93386) (xy 8.193533 -92.975023) (xy 8.306964 -93.02363) (xy 8.417012 -93.079477)
			(xy 8.523213 -93.142331) (xy 8.625124 -93.211928) (xy 8.722315 -93.287975) (xy 8.814381 -93.370154)
			(xy 8.900933 -93.45812) (xy 8.981611 -93.551504) (xy 9.056074 -93.649914) (xy 9.124011 -93.752938)
			(xy 9.185137 -93.860143) (xy 9.239195 -93.971081) (xy 9.285959 -94.085284) (xy 9.325233 -94.202276)
			(xy 9.356851 -94.321564) (xy 9.380682 -94.442648) (xy 9.396625 -94.565022) (xy 9.404613 -94.68817)
			(xy 9.405112 -94.749874) (xy 9.404613 -94.811578) (xy 9.396625 -94.934726) (xy 9.380682 -95.0571)
			(xy 9.356851 -95.178184) (xy 9.325233 -95.297472) (xy 9.285959 -95.414464) (xy 9.239195 -95.528667)
			(xy 9.185137 -95.639605) (xy 9.124011 -95.74681) (xy 9.056074 -95.849834) (xy 8.981611 -95.948244)
			(xy 8.900933 -96.041628) (xy 8.814381 -96.129594) (xy 8.722315 -96.211773) (xy 8.625124 -96.28782)
			(xy 8.523213 -96.357417) (xy 8.417012 -96.420271) (xy 8.306964 -96.476118) (xy 8.193533 -96.524725)
			(xy 8.077193 -96.565888) (xy 7.958432 -96.599434) (xy 7.837749 -96.625222) (xy 7.71565 -96.643145)
			(xy 7.592647 -96.653126) (xy 7.469256 -96.655124) (xy 7.345994 -96.649131) (xy 7.223379 -96.635172)
			(xy 7.101924 -96.613305) (xy 6.98214 -96.583623) (xy 6.864528 -96.546249) (xy 6.749582 -96.50134)
			(xy 6.637784 -96.449086) (xy 6.529602 -96.389704) (xy 6.425492 -96.323444) (xy 6.325889 -96.250584)
			(xy 6.231211 -96.171429) (xy 6.141855 -96.086312) (xy 6.058196 -95.99559) (xy 5.980585 -95.899642)
			(xy 5.909347 -95.798872) (xy 5.844782 -95.693702) (xy 5.787159 -95.584574) (xy 5.736722 -95.471944)
			(xy 5.693681 -95.356286) (xy 5.658216 -95.238084) (xy 5.630477 -95.117835) (xy 5.61058 -94.996042)
			(xy 5.598608 -94.873217) (xy 5.594612 -94.749874) (xy 4.503409 -94.749874) (xy 4.503409 -94.827058)
			(xy 4.511356 -94.981223) (xy 4.527228 -95.134773) (xy 4.550984 -95.287303) (xy 4.58256 -95.438408)
			(xy 4.621874 -95.587687) (xy 4.668819 -95.734745) (xy 4.723273 -95.87919) (xy 4.785091 -96.020641)
			(xy 4.854108 -96.158722) (xy 4.930143 -96.293067) (xy 5.012992 -96.42332) (xy 5.102436 -96.549135)
			(xy 5.198239 -96.670178) (xy 5.300146 -96.78613) (xy 5.407887 -96.896681) (xy 5.521176 -97.00154)
			(xy 5.639713 -97.100428) (xy 5.763183 -97.193082) (xy 5.891259 -97.279257) (xy 6.023602 -97.358725)
			(xy 6.15986 -97.431275) (xy 6.299673 -97.496714) (xy 6.442668 -97.55487) (xy 6.588468 -97.605586)
			(xy 6.736685 -97.64873) (xy 6.886927 -97.684187) (xy 7.038795 -97.711862) (xy 7.191886 -97.731683)
			(xy 7.345794 -97.743596) (xy 7.500112 -97.747571) (xy 7.65443 -97.743596) (xy 7.808338 -97.731683)
			(xy 7.961429 -97.711862) (xy 8.113297 -97.684187) (xy 8.263539 -97.64873) (xy 8.411756 -97.605586)
			(xy 8.557556 -97.55487) (xy 8.700551 -97.496714) (xy 8.840364 -97.431275) (xy 8.976622 -97.358725)
			(xy 9.108965 -97.279257) (xy 9.237041 -97.193082) (xy 9.360511 -97.100428) (xy 9.479048 -97.00154)
			(xy 9.592337 -96.896681) (xy 9.700078 -96.78613) (xy 9.801985 -96.670178) (xy 9.897788 -96.549135)
			(xy 9.987232 -96.42332) (xy 10.070081 -96.293067) (xy 10.146116 -96.158722) (xy 10.215133 -96.020641)
			(xy 10.276951 -95.87919) (xy 10.331405 -95.734745) (xy 10.37835 -95.587687) (xy 10.417664 -95.438408)
			(xy 10.44924 -95.287303) (xy 10.472996 -95.134773) (xy 10.488868 -94.981223) (xy 10.496815 -94.827058)
		)
		(stroke
			(width 0)
			(type solid)
		)
		(fill yes)
		(layer "F.Cu")
		(net "SG")
	)
	(gr_poly
		(pts
			(xy 10.497312 -9.349994) (xy 10.496815 -9.27281) (xy 10.488868 -9.118645) (xy 10.472996 -8.965095)
			(xy 10.44924 -8.812565) (xy 10.417664 -8.66146) (xy 10.37835 -8.512181) (xy 10.331405 -8.365123)
			(xy 10.276951 -8.220678) (xy 10.215133 -8.079227) (xy 10.146116 -7.941146) (xy 10.070081 -7.806801)
			(xy 9.987232 -7.676548) (xy 9.897788 -7.550733) (xy 9.801985 -7.42969) (xy 9.700078 -7.313738) (xy 9.592337 -7.203187)
			(xy 9.479048 -7.098328) (xy 9.360511 -6.99944) (xy 9.237041 -6.906786) (xy 9.108965 -6.820611) (xy 8.976622 -6.741143)
			(xy 8.840364 -6.668593) (xy 8.700551 -6.603154) (xy 8.557556 -6.544998) (xy 8.411756 -6.494282) (xy 8.263539 -6.451138)
			(xy 8.113297 -6.415681) (xy 7.961429 -6.388006) (xy 7.808338 -6.368185) (xy 7.65443 -6.356272) (xy 7.500112 -6.352297)
			(xy 7.345794 -6.356272) (xy 7.191886 -6.368185) (xy 7.038795 -6.388006) (xy 6.886927 -6.415681) (xy 6.736685 -6.451138)
			(xy 6.588468 -6.494282) (xy 6.442668 -6.544998) (xy 6.299673 -6.603154) (xy 6.15986 -6.668593) (xy 6.023602 -6.741143)
			(xy 5.891259 -6.820611) (xy 5.763183 -6.906786) (xy 5.639713 -6.99944) (xy 5.521176 -7.098328) (xy 5.407887 -7.203187)
			(xy 5.300146 -7.313738) (xy 5.198239 -7.42969) (xy 5.102436 -7.550733) (xy 5.012992 -7.676548) (xy 4.930143 -7.806801)
			(xy 4.854108 -7.941146) (xy 4.785091 -8.079227) (xy 4.723273 -8.220678) (xy 4.668819 -8.365123) (xy 4.621874 -8.512181)
			(xy 4.58256 -8.66146) (xy 4.550984 -8.812565) (xy 4.527228 -8.965095) (xy 4.511356 -9.118645) (xy 4.503409 -9.27281)
			(xy 4.503409 -9.349994) (xy 5.594612 -9.349994) (xy 5.598608 -9.226651) (xy 5.61058 -9.103826) (xy 5.630477 -8.982033)
			(xy 5.658216 -8.861784) (xy 5.693681 -8.743582) (xy 5.736722 -8.627924) (xy 5.787159 -8.515294) (xy 5.844782 -8.406166)
			(xy 5.909347 -8.300996) (xy 5.980585 -8.200226) (xy 6.058196 -8.104278) (xy 6.141855 -8.013556) (xy 6.231211 -7.928439)
			(xy 6.325889 -7.849284) (xy 6.425492 -7.776424) (xy 6.529602 -7.710164) (xy 6.637784 -7.650782) (xy 6.749582 -7.598528)
			(xy 6.864528 -7.553619) (xy 6.98214 -7.516245) (xy 7.101924 -7.486563) (xy 7.223379 -7.464696) (xy 7.345994 -7.450737)
			(xy 7.469256 -7.444744) (xy 7.592647 -7.446742) (xy 7.71565 -7.456723) (xy 7.837749 -7.474646) (xy 7.958432 -7.500434)
			(xy 8.077193 -7.53398) (xy 8.193533 -7.575143) (xy 8.306964 -7.62375) (xy 8.417012 -7.679597) (xy 8.523213 -7.742451)
			(xy 8.625124 -7.812048) (xy 8.722315 -7.888095) (xy 8.814381 -7.970274) (xy 8.900933 -8.05824) (xy 8.981611 -8.151624)
			(xy 9.056074 -8.250034) (xy 9.124011 -8.353058) (xy 9.185137 -8.460263) (xy 9.239195 -8.571201) (xy 9.285959 -8.685404)
			(xy 9.325233 -8.802396) (xy 9.356851 -8.921684) (xy 9.380682 -9.042768) (xy 9.396625 -9.165142) (xy 9.404613 -9.28829)
			(xy 9.405112 -9.349994) (xy 9.404613 -9.411698) (xy 9.396625 -9.534846) (xy 9.380682 -9.65722) (xy 9.356851 -9.778304)
			(xy 9.325233 -9.897592) (xy 9.285959 -10.014584) (xy 9.239195 -10.128787) (xy 9.185137 -10.239725)
			(xy 9.124011 -10.34693) (xy 9.056074 -10.449954) (xy 8.981611 -10.548364) (xy 8.900933 -10.641748)
			(xy 8.814381 -10.729714) (xy 8.722315 -10.811893) (xy 8.625124 -10.88794) (xy 8.523213 -10.957537)
			(xy 8.417012 -11.020391) (xy 8.306964 -11.076238) (xy 8.193533 -11.124845) (xy 8.077193 -11.166008)
			(xy 7.958432 -11.199554) (xy 7.837749 -11.225342) (xy 7.71565 -11.243265) (xy 7.592647 -11.253246)
			(xy 7.469256 -11.255244) (xy 7.345994 -11.249251) (xy 7.223379 -11.235292) (xy 7.101924 -11.213425)
			(xy 6.98214 -11.183743) (xy 6.864528 -11.146369) (xy 6.749582 -11.10146) (xy 6.637784 -11.049206)
			(xy 6.529602 -10.989824) (xy 6.425492 -10.923564) (xy 6.325889 -10.850704) (xy 6.231211 -10.771549)
			(xy 6.141855 -10.686432) (xy 6.058196 -10.59571) (xy 5.980585 -10.499762) (xy 5.909347 -10.398992)
			(xy 5.844782 -10.293822) (xy 5.787159 -10.184694) (xy 5.736722 -10.072064) (xy 5.693681 -9.956406)
			(xy 5.658216 -9.838204) (xy 5.630477 -9.717955) (xy 5.61058 -9.596162) (xy 5.598608 -9.473337) (xy 5.594612 -9.349994)
			(xy 4.503409 -9.349994) (xy 4.503409 -9.427178) (xy 4.511356 -9.581343) (xy 4.527228 -9.734893) (xy 4.550984 -9.887423)
			(xy 4.58256 -10.038528) (xy 4.621874 -10.187807) (xy 4.668819 -10.334865) (xy 4.723273 -10.47931)
			(xy 4.785091 -10.620761) (xy 4.854108 -10.758842) (xy 4.930143 -10.893187) (xy 5.012992 -11.02344)
			(xy 5.102436 -11.149255) (xy 5.198239 -11.270298) (xy 5.300146 -11.38625) (xy 5.407887 -11.496801)
			(xy 5.521176 -11.60166) (xy 5.639713 -11.700548) (xy 5.763183 -11.793202) (xy 5.891259 -11.879377)
			(xy 6.023602 -11.958845) (xy 6.15986 -12.031395) (xy 6.299673 -12.096834) (xy 6.442668 -12.15499)
			(xy 6.588468 -12.205706) (xy 6.736685 -12.24885) (xy 6.886927 -12.284307) (xy 7.038795 -12.311982)
			(xy 7.191886 -12.331803) (xy 7.345794 -12.343716) (xy 7.500112 -12.347691) (xy 7.65443 -12.343716)
			(xy 7.808338 -12.331803) (xy 7.961429 -12.311982) (xy 8.113297 -12.284307) (xy 8.263539 -12.24885)
			(xy 8.411756 -12.205706) (xy 8.557556 -12.15499) (xy 8.700551 -12.096834) (xy 8.840364 -12.031395)
			(xy 8.976622 -11.958845) (xy 9.108965 -11.879377) (xy 9.237041 -11.793202) (xy 9.360511 -11.700548)
			(xy 9.479048 -11.60166) (xy 9.592337 -11.496801) (xy 9.700078 -11.38625) (xy 9.801985 -11.270298)
			(xy 9.897788 -11.149255) (xy 9.987232 -11.02344) (xy 10.070081 -10.893187) (xy 10.146116 -10.758842)
			(xy 10.215133 -10.620761) (xy 10.276951 -10.47931) (xy 10.331405 -10.334865) (xy 10.37835 -10.187807)
			(xy 10.417664 -10.038528) (xy 10.44924 -9.887423) (xy 10.472996 -9.734893) (xy 10.488868 -9.581343)
			(xy 10.496815 -9.427178)
		)
		(stroke
			(width 0)
			(type solid)
		)
		(fill yes)
		(layer "F.Cu")
		(net "SG")
	)
	(gr_poly
		(pts
			(xy 165.567106 -106.13009) (xy 165.566609 -106.052906) (xy 165.558662 -105.898741) (xy 165.54279 -105.745191)
			(xy 165.519034 -105.592661) (xy 165.487458 -105.441556) (xy 165.448144 -105.292277) (xy 165.401199 -105.145219)
			(xy 165.346745 -105.000774) (xy 165.284927 -104.859323) (xy 165.21591 -104.721242) (xy 165.139875 -104.586897)
			(xy 165.057026 -104.456644) (xy 164.967582 -104.330829) (xy 164.871779 -104.209786) (xy 164.769872 -104.093834)
			(xy 164.662131 -103.983283) (xy 164.548842 -103.878424) (xy 164.430305 -103.779536) (xy 164.306835 -103.686882)
			(xy 164.178759 -103.600707) (xy 164.046416 -103.521239) (xy 163.910158 -103.448689) (xy 163.770345 -103.38325)
			(xy 163.62735 -103.325094) (xy 163.48155 -103.274378) (xy 163.333333 -103.231234) (xy 163.183091 -103.195777)
			(xy 163.031223 -103.168102) (xy 162.878132 -103.148281) (xy 162.724224 -103.136368) (xy 162.569906 -103.132393)
			(xy 162.415588 -103.136368) (xy 162.26168 -103.148281) (xy 162.108589 -103.168102) (xy 161.956721 -103.195777)
			(xy 161.806479 -103.231234) (xy 161.658262 -103.274378) (xy 161.512462 -103.325094) (xy 161.369467 -103.38325)
			(xy 161.229654 -103.448689) (xy 161.093396 -103.521239) (xy 160.961053 -103.600707) (xy 160.832977 -103.686882)
			(xy 160.709507 -103.779536) (xy 160.59097 -103.878424) (xy 160.477681 -103.983283) (xy 160.36994 -104.093834)
			(xy 160.268033 -104.209786) (xy 160.17223 -104.330829) (xy 160.082786 -104.456644) (xy 159.999937 -104.586897)
			(xy 159.923902 -104.721242) (xy 159.854885 -104.859323) (xy 159.793067 -105.000774) (xy 159.738613 -105.145219)
			(xy 159.691668 -105.292277) (xy 159.652354 -105.441556) (xy 159.620778 -105.592661) (xy 159.597022 -105.745191)
			(xy 159.58115 -105.898741) (xy 159.573203 -106.052906) (xy 159.573203 -106.13009) (xy 160.664406 -106.13009)
			(xy 160.668402 -106.006747) (xy 160.680374 -105.883922) (xy 160.700271 -105.762129) (xy 160.72801 -105.64188)
			(xy 160.763475 -105.523678) (xy 160.806516 -105.40802) (xy 160.856953 -105.29539) (xy 160.914576 -105.186262)
			(xy 160.979141 -105.081092) (xy 161.050379 -104.980322) (xy 161.12799 -104.884374) (xy 161.211649 -104.793652)
			(xy 161.301005 -104.708535) (xy 161.395683 -104.62938) (xy 161.495286 -104.55652) (xy 161.599396 -104.49026)
			(xy 161.707578 -104.430878) (xy 161.819376 -104.378624) (xy 161.934322 -104.333715) (xy 162.051934 -104.296341)
			(xy 162.171718 -104.266659) (xy 162.293173 -104.244792) (xy 162.415788 -104.230833) (xy 162.53905 -104.22484)
			(xy 162.662441 -104.226838) (xy 162.785444 -104.236819) (xy 162.907543 -104.254742) (xy 163.028226 -104.28053)
			(xy 163.146987 -104.314076) (xy 163.263327 -104.355239) (xy 163.376758 -104.403846) (xy 163.486806 -104.459693)
			(xy 163.593007 -104.522547) (xy 163.694918 -104.592144) (xy 163.792109 -104.668191) (xy 163.884175 -104.75037)
			(xy 163.970727 -104.838336) (xy 164.051405 -104.93172) (xy 164.125868 -105.03013) (xy 164.193805 -105.133154)
			(xy 164.254931 -105.240359) (xy 164.308989 -105.351297) (xy 164.355753 -105.4655) (xy 164.395027 -105.582492)
			(xy 164.426645 -105.70178) (xy 164.450476 -105.822864) (xy 164.466419 -105.945238) (xy 164.474407 -106.068386)
			(xy 164.474906 -106.13009) (xy 164.474407 -106.191794) (xy 164.466419 -106.314942) (xy 164.450476 -106.437316)
			(xy 164.426645 -106.5584) (xy 164.395027 -106.677688) (xy 164.355753 -106.79468) (xy 164.308989 -106.908883)
			(xy 164.254931 -107.019821) (xy 164.193805 -107.127026) (xy 164.125868 -107.23005) (xy 164.051405 -107.32846)
			(xy 163.970727 -107.421844) (xy 163.884175 -107.50981) (xy 163.792109 -107.591989) (xy 163.694918 -107.668036)
			(xy 163.593007 -107.737633) (xy 163.486806 -107.800487) (xy 163.376758 -107.856334) (xy 163.263327 -107.904941)
			(xy 163.146987 -107.946104) (xy 163.028226 -107.97965) (xy 162.907543 -108.005438) (xy 162.785444 -108.023361)
			(xy 162.662441 -108.033342) (xy 162.53905 -108.03534) (xy 162.415788 -108.029347) (xy 162.293173 -108.015388)
			(xy 162.171718 -107.993521) (xy 162.051934 -107.963839) (xy 161.934322 -107.926465) (xy 161.819376 -107.881556)
			(xy 161.707578 -107.829302) (xy 161.599396 -107.76992) (xy 161.495286 -107.70366) (xy 161.395683 -107.6308)
			(xy 161.301005 -107.551645) (xy 161.211649 -107.466528) (xy 161.12799 -107.375806) (xy 161.050379 -107.279858)
			(xy 160.979141 -107.179088) (xy 160.914576 -107.073918) (xy 160.856953 -106.96479) (xy 160.806516 -106.85216)
			(xy 160.763475 -106.736502) (xy 160.72801 -106.6183) (xy 160.700271 -106.498051) (xy 160.680374 -106.376258)
			(xy 160.668402 -106.253433) (xy 160.664406 -106.13009) (xy 159.573203 -106.13009) (xy 159.573203 -106.207274)
			(xy 159.58115 -106.361439) (xy 159.597022 -106.514989) (xy 159.620778 -106.667519) (xy 159.652354 -106.818624)
			(xy 159.691668 -106.967903) (xy 159.738613 -107.114961) (xy 159.793067 -107.259406) (xy 159.854885 -107.400857)
			(xy 159.923902 -107.538938) (xy 159.999937 -107.673283) (xy 160.082786 -107.803536) (xy 160.17223 -107.929351)
			(xy 160.268033 -108.050394) (xy 160.36994 -108.166346) (xy 160.477681 -108.276897) (xy 160.59097 -108.381756)
			(xy 160.709507 -108.480644) (xy 160.832977 -108.573298) (xy 160.961053 -108.659473) (xy 161.093396 -108.738941)
			(xy 161.229654 -108.811491) (xy 161.369467 -108.87693) (xy 161.512462 -108.935086) (xy 161.658262 -108.985802)
			(xy 161.806479 -109.028946) (xy 161.956721 -109.064403) (xy 162.108589 -109.092078) (xy 162.26168 -109.111899)
			(xy 162.415588 -109.123812) (xy 162.569906 -109.127787) (xy 162.724224 -109.123812) (xy 162.878132 -109.111899)
			(xy 163.031223 -109.092078) (xy 163.183091 -109.064403) (xy 163.333333 -109.028946) (xy 163.48155 -108.985802)
			(xy 163.62735 -108.935086) (xy 163.770345 -108.87693) (xy 163.910158 -108.811491) (xy 164.046416 -108.738941)
			(xy 164.178759 -108.659473) (xy 164.306835 -108.573298) (xy 164.430305 -108.480644) (xy 164.548842 -108.381756)
			(xy 164.662131 -108.276897) (xy 164.769872 -108.166346) (xy 164.871779 -108.050394) (xy 164.967582 -107.929351)
			(xy 165.057026 -107.803536) (xy 165.139875 -107.673283) (xy 165.21591 -107.538938) (xy 165.284927 -107.400857)
			(xy 165.346745 -107.259406) (xy 165.401199 -107.114961) (xy 165.448144 -106.967903) (xy 165.487458 -106.818624)
			(xy 165.519034 -106.667519) (xy 165.54279 -106.514989) (xy 165.558662 -106.361439) (xy 165.566609 -106.207274)
		)
		(stroke
			(width 0)
			(type solid)
		)
		(fill yes)
		(layer "F.Cu")
		(net "SG")
	)
	(gr_poly
		(pts
			(xy 165.567106 -16.599916) (xy 165.566609 -16.522732) (xy 165.558662 -16.368567) (xy 165.54279 -16.215017)
			(xy 165.519034 -16.062487) (xy 165.487458 -15.911382) (xy 165.448144 -15.762103) (xy 165.401199 -15.615045)
			(xy 165.346745 -15.4706) (xy 165.284927 -15.329149) (xy 165.21591 -15.191068) (xy 165.139875 -15.056723)
			(xy 165.057026 -14.92647) (xy 164.967582 -14.800655) (xy 164.871779 -14.679612) (xy 164.769872 -14.56366)
			(xy 164.662131 -14.453109) (xy 164.548842 -14.34825) (xy 164.430305 -14.249362) (xy 164.306835 -14.156708)
			(xy 164.178759 -14.070533) (xy 164.046416 -13.991065) (xy 163.910158 -13.918515) (xy 163.770345 -13.853076)
			(xy 163.62735 -13.79492) (xy 163.48155 -13.744204) (xy 163.333333 -13.70106) (xy 163.183091 -13.665603)
			(xy 163.031223 -13.637928) (xy 162.878132 -13.618107) (xy 162.724224 -13.606194) (xy 162.569906 -13.602219)
			(xy 162.415588 -13.606194) (xy 162.26168 -13.618107) (xy 162.108589 -13.637928) (xy 161.956721 -13.665603)
			(xy 161.806479 -13.70106) (xy 161.658262 -13.744204) (xy 161.512462 -13.79492) (xy 161.369467 -13.853076)
			(xy 161.229654 -13.918515) (xy 161.093396 -13.991065) (xy 160.961053 -14.070533) (xy 160.832977 -14.156708)
			(xy 160.709507 -14.249362) (xy 160.59097 -14.34825) (xy 160.477681 -14.453109) (xy 160.36994 -14.56366)
			(xy 160.268033 -14.679612) (xy 160.17223 -14.800655) (xy 160.082786 -14.92647) (xy 159.999937 -15.056723)
			(xy 159.923902 -15.191068) (xy 159.854885 -15.329149) (xy 159.793067 -15.4706) (xy 159.738613 -15.615045)
			(xy 159.691668 -15.762103) (xy 159.652354 -15.911382) (xy 159.620778 -16.062487) (xy 159.597022 -16.215017)
			(xy 159.58115 -16.368567) (xy 159.573203 -16.522732) (xy 159.573203 -16.599916) (xy 160.664406 -16.599916)
			(xy 160.668402 -16.476573) (xy 160.680374 -16.353748) (xy 160.700271 -16.231955) (xy 160.72801 -16.111706)
			(xy 160.763475 -15.993504) (xy 160.806516 -15.877846) (xy 160.856953 -15.765216) (xy 160.914576 -15.656088)
			(xy 160.979141 -15.550918) (xy 161.050379 -15.450148) (xy 161.12799 -15.3542) (xy 161.211649 -15.263478)
			(xy 161.301005 -15.178361) (xy 161.395683 -15.099206) (xy 161.495286 -15.026346) (xy 161.599396 -14.960086)
			(xy 161.707578 -14.900704) (xy 161.819376 -14.84845) (xy 161.934322 -14.803541) (xy 162.051934 -14.766167)
			(xy 162.171718 -14.736485) (xy 162.293173 -14.714618) (xy 162.415788 -14.700659) (xy 162.53905 -14.694666)
			(xy 162.662441 -14.696664) (xy 162.785444 -14.706645) (xy 162.907543 -14.724568) (xy 163.028226 -14.750356)
			(xy 163.146987 -14.783902) (xy 163.263327 -14.825065) (xy 163.376758 -14.873672) (xy 163.486806 -14.929519)
			(xy 163.593007 -14.992373) (xy 163.694918 -15.06197) (xy 163.792109 -15.138017) (xy 163.884175 -15.220196)
			(xy 163.970727 -15.308162) (xy 164.051405 -15.401546) (xy 164.125868 -15.499956) (xy 164.193805 -15.60298)
			(xy 164.254931 -15.710185) (xy 164.308989 -15.821123) (xy 164.355753 -15.935326) (xy 164.395027 -16.052318)
			(xy 164.426645 -16.171606) (xy 164.450476 -16.29269) (xy 164.466419 -16.415064) (xy 164.474407 -16.538212)
			(xy 164.474906 -16.599916) (xy 164.474407 -16.66162) (xy 164.466419 -16.784768) (xy 164.450476 -16.907142)
			(xy 164.426645 -17.028226) (xy 164.395027 -17.147514) (xy 164.355753 -17.264506) (xy 164.308989 -17.378709)
			(xy 164.254931 -17.489647) (xy 164.193805 -17.596852) (xy 164.125868 -17.699876) (xy 164.051405 -17.798286)
			(xy 163.970727 -17.89167) (xy 163.884175 -17.979636) (xy 163.792109 -18.061815) (xy 163.694918 -18.137862)
			(xy 163.593007 -18.207459) (xy 163.486806 -18.270313) (xy 163.376758 -18.32616) (xy 163.263327 -18.374767)
			(xy 163.146987 -18.41593) (xy 163.028226 -18.449476) (xy 162.907543 -18.475264) (xy 162.785444 -18.493187)
			(xy 162.662441 -18.503168) (xy 162.53905 -18.505166) (xy 162.415788 -18.499173) (xy 162.293173 -18.485214)
			(xy 162.171718 -18.463347) (xy 162.051934 -18.433665) (xy 161.934322 -18.396291) (xy 161.819376 -18.351382)
			(xy 161.707578 -18.299128) (xy 161.599396 -18.239746) (xy 161.495286 -18.173486) (xy 161.395683 -18.100626)
			(xy 161.301005 -18.021471) (xy 161.211649 -17.936354) (xy 161.12799 -17.845632) (xy 161.050379 -17.749684)
			(xy 160.979141 -17.648914) (xy 160.914576 -17.543744) (xy 160.856953 -17.434616) (xy 160.806516 -17.321986)
			(xy 160.763475 -17.206328) (xy 160.72801 -17.088126) (xy 160.700271 -16.967877) (xy 160.680374 -16.846084)
			(xy 160.668402 -16.723259) (xy 160.664406 -16.599916) (xy 159.573203 -16.599916) (xy 159.573203 -16.6771)
			(xy 159.58115 -16.831265) (xy 159.597022 -16.984815) (xy 159.620778 -17.137345) (xy 159.652354 -17.28845)
			(xy 159.691668 -17.437729) (xy 159.738613 -17.584787) (xy 159.793067 -17.729232) (xy 159.854885 -17.870683)
			(xy 159.923902 -18.008764) (xy 159.999937 -18.143109) (xy 160.082786 -18.273362) (xy 160.17223 -18.399177)
			(xy 160.268033 -18.52022) (xy 160.36994 -18.636172) (xy 160.477681 -18.746723) (xy 160.59097 -18.851582)
			(xy 160.709507 -18.95047) (xy 160.832977 -19.043124) (xy 160.961053 -19.129299) (xy 161.093396 -19.208767)
			(xy 161.229654 -19.281317) (xy 161.369467 -19.346756) (xy 161.512462 -19.404912) (xy 161.658262 -19.455628)
			(xy 161.806479 -19.498772) (xy 161.956721 -19.534229) (xy 162.108589 -19.561904) (xy 162.26168 -19.581725)
			(xy 162.415588 -19.593638) (xy 162.569906 -19.597613) (xy 162.724224 -19.593638) (xy 162.878132 -19.581725)
			(xy 163.031223 -19.561904) (xy 163.183091 -19.534229) (xy 163.333333 -19.498772) (xy 163.48155 -19.455628)
			(xy 163.62735 -19.404912) (xy 163.770345 -19.346756) (xy 163.910158 -19.281317) (xy 164.046416 -19.208767)
			(xy 164.178759 -19.129299) (xy 164.306835 -19.043124) (xy 164.430305 -18.95047) (xy 164.548842 -18.851582)
			(xy 164.662131 -18.746723) (xy 164.769872 -18.636172) (xy 164.871779 -18.52022) (xy 164.967582 -18.399177)
			(xy 165.057026 -18.273362) (xy 165.139875 -18.143109) (xy 165.21591 -18.008764) (xy 165.284927 -17.870683)
			(xy 165.346745 -17.729232) (xy 165.401199 -17.584787) (xy 165.448144 -17.437729) (xy 165.487458 -17.28845)
			(xy 165.519034 -17.137345) (xy 165.54279 -16.984815) (xy 165.558662 -16.831265) (xy 165.566609 -16.6771)
		)
		(stroke
			(width 0)
			(type solid)
		)
		(fill yes)
		(layer "F.Cu")
		(net "SG")
	)
	(gr_poly
		(pts
			(xy 166.87292 -110.21441) (xy 166.87292 -99.70008) (xy 157.619954 -99.70008) (xy 157.619954 -110.149894)
			(xy 157.619954 -110.360968) (xy 166.726362 -110.360968)
		)
		(stroke
			(width 0)
			(type solid)
		)
		(fill yes)
		(layer "B.Cu")
		(net "SG")
	)
	(gr_poly
		(pts
			(xy 14.234922 -5.50164) (xy 14.002004 -5.268722) (xy 1.813052 -5.268722) (xy 0.972058 -5.268722)
			(xy 0.770382 -5.470398) (xy 0.770382 -13.59662) (xy 14.234922 -13.59662)
		)
		(stroke
			(width 0)
			(type solid)
		)
		(fill yes)
		(layer "B.Cu")
		(net "SG")
	)
	(gr_poly
		(pts
			(xy 166.882318 -13.71727) (xy 166.685468 -13.52042) (xy 157.607 -13.52042) (xy 157.607 -13.750036)
			(xy 157.619954 -13.750036) (xy 157.619954 -22.899878) (xy 166.882318 -22.899878)
		)
		(stroke
			(width 0)
			(type solid)
		)
		(fill yes)
		(layer "B.Cu")
		(net "SG")
	)
	(gr_poly
		(pts
			(xy 12.7 -110.149894) (xy 12.7 -89.7001) (xy 0.999998 -89.7001) (xy 0.765048 -89.7001) (xy 0.765048 -99.51466)
			(xy 0.765048 -110.171738) (xy 0.978916 -110.385606) (xy 12.7 -110.385606)
		)
		(stroke
			(width 0)
			(type solid)
		)
		(fill yes)
		(layer "B.Cu")
		(net "SG")
	)
	(gr_poly
		(pts
			(xy 144.2466 -55.9562) (xy 144.2466 -55.3212) (xy 144.0942 -55.1688) (xy 142.8496 -55.1688) (xy 142.7988 -55.2196)
			(xy 142.7988 -56.1848) (xy 142.9004 -56.2864) (xy 143.9164 -56.2864)
		)
		(stroke
			(width 0)
			(type solid)
		)
		(fill yes)
		(layer "B.Cu")
		(net "XP1R0V_AGND")
	)
	(gr_poly
		(pts
			(xy 85.4964 -100.6602) (xy 85.4964 -99.5934) (xy 85.4964 -99.4918) (xy 85.1916 -99.187) (xy 82.3722 -99.187)
			(xy 82.3722 -100.584) (xy 82.4992 -100.711) (xy 84.4804 -100.711) (xy 84.761578 -100.711) (xy 85.4456 -100.711)
		)
		(stroke
			(width 0)
			(type solid)
		)
		(fill yes)
		(layer "B.Cu")
		(net "SG")
	)
	(gr_poly
		(pts
			(xy 41.3766 -103.2256) (xy 41.3766 -103.0478) (xy 41.3766 -101.981) (xy 41.3258 -101.9302) (xy 40.641778 -101.9302)
			(xy 40.3606 -101.9302) (xy 40.259 -102.0318) (xy 40.259 -103.0478) (xy 40.259 -103.251) (xy 40.386 -103.378)
			(xy 41.2242 -103.378)
		)
		(stroke
			(width 0)
			(type solid)
		)
		(fill yes)
		(layer "B.Cu")
		(net "XP5R0V_AGND")
	)
	(gr_poly
		(pts
			(xy 86.7156 -100.6094) (xy 86.7156 -99.5934) (xy 86.7156 -99.3902) (xy 86.5886 -99.2632) (xy 85.7504 -99.2632)
			(xy 85.598 -99.4156) (xy 85.598 -99.5934) (xy 85.598 -100.6602) (xy 85.6488 -100.711) (xy 86.332822 -100.711)
			(xy 86.614 -100.711)
		)
		(stroke
			(width 0)
			(type solid)
		)
		(fill yes)
		(layer "B.Cu")
		(net "XP3R3V_AGND")
	)
	(gr_poly
		(pts
			(xy 144.2466 -55.0164) (xy 144.2466 -54.0258) (xy 144.0688 -53.848) (xy 142.9004 -53.848) (xy 142.7988 -53.9496)
			(xy 142.7988 -54.0512) (xy 142.7988 -54.332378) (xy 142.7988 -55.0164) (xy 142.8496 -55.0672) (xy 143.9164 -55.0672)
			(xy 144.1958 -55.0672)
		)
		(stroke
			(width 0)
			(type solid)
		)
		(fill yes)
		(layer "B.Cu")
		(net "SG")
	)
	(gr_poly
		(pts
			(xy 42.5958 -103.0478) (xy 42.5958 -102.0318) (xy 42.4942 -101.9302) (xy 42.213022 -101.9302) (xy 41.529 -101.9302)
			(xy 41.4782 -101.981) (xy 41.4782 -103.0478) (xy 41.550082 -103.119682)
			(arc
				(start 42.088816 -103.119682)
				(mid 42.103264 -103.122894)
				(end 42.118026 -103.124)
			)
			(xy 42.5196 -103.124)
		)
		(stroke
			(width 0)
			(type solid)
		)
		(fill yes)
		(layer "B.Cu")
		(net "SG")
	)
	(gr_poly
		(pts
			(arc
				(start 157.207204 -14.019276)
				(mid 157.248048 -13.998336)
				(end 157.255464 -13.952982)
			)
			(xy 157.255464 -13.54328) (xy 157.225492 -13.513308) (xy 80.374998 -13.513308) (xy 80.336644 -13.551662)
			(xy 80.336644 -13.97762) (xy 80.3783 -14.019276)
		)
		(stroke
			(width 0)
			(type solid)
		)
		(fill yes)
		(layer "B.Cu")
		(net "SG")
	)
	(gr_poly
		(pts
			(xy 157.016958 -109.8804)
			(arc
				(start 12.925806 -109.8804)
				(mid 12.884962 -109.90134)
				(end 12.877546 -109.946694)
			)
			(arc
				(start 12.877546 -109.946694)
				(mid 12.899554 -110.039018)
				(end 12.90701 -110.133638)
			)
			(xy 12.90701 -110.133892) (xy 12.906756 -110.149132) (xy 12.906756 -110.375446) (xy 12.918186 -110.386876)
			(xy 157.016958 -110.386876)
		)
		(stroke
			(width 0)
			(type solid)
		)
		(fill yes)
		(layer "B.Cu")
		(net "SG")
	)
	(gr_poly
		(pts
			(arc
				(start 1.203198 -89.238582)
				(mid 1.24873 -89.231194)
				(end 1.269492 -89.190068)
			)
			(xy 1.269492 -70.485) (xy 0.763016 -70.485)
			(arc
				(start 0.763016 -89.190068)
				(mid 0.783885 -89.231114)
				(end 0.82931 -89.238328)
			)
			(arc
				(start 0.82931 -89.238328)
				(mid 0.921393 -89.216484)
				(end 1.015746 -89.209118)
			)
			(arc
				(start 1.016 -89.209118)
				(mid 1.110754 -89.216521)
				(end 1.203198 -89.238582)
			)
		)
		(stroke
			(width 0)
			(type solid)
		)
		(fill yes)
		(layer "B.Cu")
		(net "SG")
	)
	(gr_poly
		(pts
			(arc
				(start 166.88689 -23.353522)
				(mid 166.849046 -23.274416)
				(end 166.7637 -23.254208)
			)
			(arc
				(start 166.7637 -23.254208)
				(mid 166.699178 -23.264677)
				(end 166.633906 -23.268178)
			)
			(arc
				(start 166.633398 -23.268178)
				(mid 166.568254 -23.264663)
				(end 166.503858 -23.254208)
			)
			(arc
				(start 166.503858 -23.254208)
				(mid 166.41859 -23.274311)
				(end 166.380668 -23.353268)
			)
			(xy 166.380668 -48.641) (xy 166.88689 -48.641)
		)
		(stroke
			(width 0)
			(type solid)
		)
		(fill yes)
		(layer "B.Cu")
		(net "SG")
	)
	(gr_poly
		(pts
			(arc
				(start 165.162484 -61.648594)
				(mid 165.21545 -61.737544)
				(end 165.318948 -61.733938)
			)
			(arc
				(start 165.318948 -61.733938)
				(mid 165.468987 -61.654241)
				(end 165.630098 -61.600334)
			)
			(xy 165.668706 -61.590936)
			(arc
				(start 165.668706 -61.324998)
				(mid 166.02293 -60.447949)
				(end 166.88689 -60.062872)
			)
			(xy 166.88689 -58.42) (xy 166.380668 -58.42)
			(arc
				(start 166.380668 -59.643772)
				(mid 165.498986 -60.286888)
				(end 165.162484 -61.324998)
			)
		)
		(stroke
			(width 0)
			(type solid)
		)
		(fill yes)
		(layer "B.Cu")
		(net "SG")
	)
	(gr_poly
		(pts
			(arc
				(start 166.88689 -73.062338)
				(mid 166.023068 -72.677197)
				(end 165.668706 -71.800212)
			)
			(arc
				(start 165.668706 -70.936104)
				(mid 165.480788 -70.600062)
				(end 165.668706 -70.26402)
			)
			(xy 165.668706 -63.60922)
			(arc
				(start 165.630098 -63.599822)
				(mid 165.468998 -63.54589)
				(end 165.318948 -63.466218)
			)
			(arc
				(start 165.318948 -63.466218)
				(mid 165.215416 -63.46255)
				(end 165.162484 -63.551562)
			)
			(arc
				(start 165.162484 -65.775332)
				(mid 165.430742 -66.294)
				(end 165.162484 -66.812668)
			)
			(arc
				(start 165.162484 -71.800212)
				(mid 165.499029 -72.838326)
				(end 166.380668 -73.481438)
			)
			(xy 166.380668 -99.699572) (xy 166.88689 -99.699572)
		)
		(stroke
			(width 0)
			(type solid)
		)
		(fill yes)
		(layer "B.Cu")
		(net "SG")
	)
	(gr_poly
		(pts
			(xy 39.514018 -26.934922) (xy 39.513521 -26.857068) (xy 39.50557 -26.701562) (xy 39.48969 -26.546665)
			(xy 39.465921 -26.392781) (xy 39.434326 -26.240311) (xy 39.394986 -26.089654) (xy 39.348006 -25.941202)
			(xy 39.293506 -25.795342) (xy 39.23163 -25.652455) (xy 39.162539 -25.512914) (xy 39.086413 -25.377083)
			(xy 39.003451 -25.245316) (xy 38.913869 -25.117957) (xy 38.8179 -24.995339) (xy 38.715796 -24.87778)
			(xy 38.607823 -24.765589) (xy 38.494261 -24.659057) (xy 38.375409 -24.558462) (xy 38.251575 -24.464068)
			(xy 38.123082 -24.376119) (xy 37.990267 -24.294846) (xy 37.853474 -24.220461) (xy 37.713063 -24.153157)
			(xy 37.569397 -24.093111) (xy 37.422853 -24.040479) (xy 37.273813 -23.995398) (xy 37.122666 -23.957986)
			(xy 36.969805 -23.92834) (xy 36.81563 -23.906539) (xy 36.660543 -23.892638) (xy 36.504948 -23.886674)
			(xy 36.349252 -23.888662) (xy 36.193861 -23.898598) (xy 36.039179 -23.916455) (xy 35.885611 -23.942187)
			(xy 35.733558 -23.975727) (xy 35.583415 -24.016987) (xy 35.435575 -24.065859) (xy 35.290423 -24.122217)
			(xy 35.148338 -24.185913) (xy 35.009691 -24.25678) (xy 34.874843 -24.334634) (xy 34.744146 -24.419273)
			(xy 34.617942 -24.510474) (xy 34.496559 -24.608) (xy 34.380314 -24.711598) (xy 34.26951 -24.820995)
			(xy 34.164437 -24.935908) (xy 34.065368 -25.056035) (xy 33.972563 -25.181065) (xy 33.886262 -25.31067)
			(xy 33.806692 -25.444512) (xy 33.73406 -25.582243) (xy 33.668555 -25.723503) (xy 33.610348 -25.867924)
			(xy 33.559592 -26.015128) (xy 33.516418 -26.164731) (xy 33.480939 -26.316344) (xy 33.453248 -26.469571)
			(xy 33.433417 -26.624012) (xy 33.421498 -26.779264) (xy 33.417521 -26.934922) (xy 34.878023 -26.934922)
			(xy 34.881979 -26.822906) (xy 34.893826 -26.711449) (xy 34.913506 -26.601105) (xy 34.94092 -26.492424)
			(xy 34.975932 -26.385947) (xy 35.018368 -26.282206) (xy 35.068016 -26.181716) (xy 35.124629 -26.084979)
			(xy 35.187925 -25.992476) (xy 35.257587 -25.904668) (xy 35.333271 -25.821993) (xy 35.414597 -25.744862)
			(xy 35.501162 -25.67366) (xy 35.592533 -25.608742) (xy 35.688257 -25.550431) (xy 35.787855 -25.499017)
			(xy 35.890831 -25.454757) (xy 35.996673 -25.417871) (xy 36.104853 -25.388543) (xy 36.214833 -25.366919)
			(xy 36.326064 -25.353106) (xy 36.437992 -25.347174) (xy 36.55006 -25.349152) (xy 36.661709 -25.359031)
			(xy 36.772384 -25.37676) (xy 36.881532 -25.402252) (xy 36.988609 -25.43538) (xy 37.093084 -25.475978)
			(xy 37.194434 -25.523845) (xy 37.292156 -25.578742) (xy 37.385761 -25.640395) (xy 37.474785 -25.708497)
			(xy 37.558783 -25.78271) (xy 37.637337 -25.862662) (xy 37.710055 -25.947957) (xy 37.776576 -26.038168)
			(xy 37.836567 -26.132848) (xy 37.889731 -26.231523) (xy 37.935801 -26.333702) (xy 37.974549 -26.438877)
			(xy 38.005782 -26.546522) (xy 38.029344 -26.656103) (xy 38.045117 -26.767073) (xy 38.053024 -26.878879)
			(xy 38.053518 -26.934922) (xy 38.053024 -26.990965) (xy 38.045117 -27.102771) (xy 38.029344 -27.213741)
			(xy 38.005782 -27.323322) (xy 37.974549 -27.430967) (xy 37.935801 -27.536142) (xy 37.889731 -27.638321)
			(xy 37.836567 -27.736996) (xy 37.776576 -27.831676) (xy 37.710055 -27.921887) (xy 37.637337 -28.007182)
			(xy 37.558783 -28.087134) (xy 37.474785 -28.161347) (xy 37.385761 -28.229449) (xy 37.292156 -28.291102)
			(xy 37.194434 -28.345999) (xy 37.093084 -28.393866) (xy 36.988609 -28.434464) (xy 36.881532 -28.467592)
			(xy 36.772384 -28.493084) (xy 36.661709 -28.510813) (xy 36.55006 -28.520692) (xy 36.437992 -28.52267)
			(xy 36.326064 -28.516738) (xy 36.214833 -28.502925) (xy 36.104853 -28.481301) (xy 35.996673 -28.451973)
			(xy 35.890831 -28.415087) (xy 35.787855 -28.370827) (xy 35.688257 -28.319413) (xy 35.592533 -28.261102)
			(xy 35.501162 -28.196184) (xy 35.414597 -28.124982) (xy 35.333271 -28.047851) (xy 35.257587 -27.965176)
			(xy 35.187925 -27.877368) (xy 35.124629 -27.784865) (xy 35.068016 -27.688128) (xy 35.018368 -27.587638)
			(xy 34.975932 -27.483897) (xy 34.94092 -27.37742) (xy 34.913506 -27.268739) (xy 34.893826 -27.158395)
			(xy 34.881979 -27.046938) (xy 34.878023 -26.934922) (xy 33.417521 -26.934922) (xy 33.421498 -27.09058)
			(xy 33.433417 -27.245832) (xy 33.453248 -27.400273) (xy 33.480939 -27.5535) (xy 33.516418 -27.705113)
			(xy 33.559592 -27.854716) (xy 33.610348 -28.00192) (xy 33.668555 -28.146341) (xy 33.73406 -28.287601)
			(xy 33.806692 -28.425332) (xy 33.886262 -28.559174) (xy 33.972563 -28.688779) (xy 34.065368 -28.813809)
			(xy 34.164437 -28.933936) (xy 34.26951 -29.048849) (xy 34.380314 -29.158246) (xy 34.496559 -29.261844)
			(xy 34.617942 -29.35937) (xy 34.744146 -29.450571) (xy 34.874843 -29.53521) (xy 35.009691 -29.613064)
			(xy 35.148338 -29.683931) (xy 35.290423 -29.747627) (xy 35.435575 -29.803985) (xy 35.583415 -29.852857)
			(xy 35.733558 -29.894117) (xy 35.885611 -29.927657) (xy 36.039179 -29.953389) (xy 36.193861 -29.971246)
			(xy 36.349252 -29.981182) (xy 36.504948 -29.98317) (xy 36.660543 -29.977206) (xy 36.81563 -29.963305)
			(xy 36.969805 -29.941504) (xy 37.122666 -29.911858) (xy 37.273813 -29.874446) (xy 37.422853 -29.829365)
			(xy 37.569397 -29.776733) (xy 37.713063 -29.716687) (xy 37.853474 -29.649383) (xy 37.990267 -29.574998)
			(xy 38.123082 -29.493725) (xy 38.251575 -29.405776) (xy 38.375409 -29.311382) (xy 38.494261 -29.210787)
			(xy 38.607823 -29.104255) (xy 38.715796 -28.992064) (xy 38.8179 -28.874505) (xy 38.913869 -28.751887)
			(xy 39.003451 -28.624528) (xy 39.086413 -28.492761) (xy 39.162539 -28.35693) (xy 39.23163 -28.217389)
			(xy 39.293506 -28.074502) (xy 39.348006 -27.928642) (xy 39.394986 -27.78019) (xy 39.434326 -27.629533)
			(xy 39.465921 -27.477063) (xy 39.48969 -27.323179) (xy 39.50557 -27.168282) (xy 39.513521 -27.012776)
		)
		(stroke
			(width 0)
			(type solid)
		)
		(fill yes)
		(layer "B.Cu")
		(net "Net_303")
	)
	(gr_poly
		(pts
			(xy 40.149018 -68.082922) (xy 40.148521 -68.005068) (xy 40.14057 -67.849562) (xy 40.12469 -67.694665)
			(xy 40.100921 -67.540781) (xy 40.069326 -67.388311) (xy 40.029986 -67.237654) (xy 39.983006 -67.089202)
			(xy 39.928506 -66.943342) (xy 39.86663 -66.800455) (xy 39.797539 -66.660914) (xy 39.721413 -66.525083)
			(xy 39.638451 -66.393316) (xy 39.548869 -66.265957) (xy 39.4529 -66.143339) (xy 39.350796 -66.02578)
			(xy 39.242823 -65.913589) (xy 39.129261 -65.807057) (xy 39.010409 -65.706462) (xy 38.886575 -65.612068)
			(xy 38.758082 -65.524119) (xy 38.625267 -65.442846) (xy 38.488474 -65.368461) (xy 38.348063 -65.301157)
			(xy 38.204397 -65.241111) (xy 38.057853 -65.188479) (xy 37.908813 -65.143398) (xy 37.757666 -65.105986)
			(xy 37.604805 -65.07634) (xy 37.45063 -65.054539) (xy 37.295543 -65.040638) (xy 37.139948 -65.034674)
			(xy 36.984252 -65.036662) (xy 36.828861 -65.046598) (xy 36.674179 -65.064455) (xy 36.520611 -65.090187)
			(xy 36.368558 -65.123727) (xy 36.218415 -65.164987) (xy 36.070575 -65.213859) (xy 35.925423 -65.270217)
			(xy 35.783338 -65.333913) (xy 35.644691 -65.40478) (xy 35.509843 -65.482634) (xy 35.379146 -65.567273)
			(xy 35.252942 -65.658474) (xy 35.131559 -65.756) (xy 35.015314 -65.859598) (xy 34.90451 -65.968995)
			(xy 34.799437 -66.083908) (xy 34.700368 -66.204035) (xy 34.607563 -66.329065) (xy 34.521262 -66.45867)
			(xy 34.441692 -66.592512) (xy 34.36906 -66.730243) (xy 34.303555 -66.871503) (xy 34.245348 -67.015924)
			(xy 34.194592 -67.163128) (xy 34.151418 -67.312731) (xy 34.115939 -67.464344) (xy 34.088248 -67.617571)
			(xy 34.068417 -67.772012) (xy 34.056498 -67.927264) (xy 34.052521 -68.082922) (xy 35.513023 -68.082922)
			(xy 35.516979 -67.970906) (xy 35.528826 -67.859449) (xy 35.548506 -67.749105) (xy 35.57592 -67.640424)
			(xy 35.610932 -67.533947) (xy 35.653368 -67.430206) (xy 35.703016 -67.329716) (xy 35.759629 -67.232979)
			(xy 35.822925 -67.140476) (xy 35.892587 -67.052668) (xy 35.968271 -66.969993) (xy 36.049597 -66.892862)
			(xy 36.136162 -66.82166) (xy 36.227533 -66.756742) (xy 36.323257 -66.698431) (xy 36.422855 -66.647017)
			(xy 36.525831 -66.602757) (xy 36.631673 -66.565871) (xy 36.739853 -66.536543) (xy 36.849833 -66.514919)
			(xy 36.961064 -66.501106) (xy 37.072992 -66.495174) (xy 37.18506 -66.497152) (xy 37.296709 -66.507031)
			(xy 37.407384 -66.52476) (xy 37.516532 -66.550252) (xy 37.623609 -66.58338) (xy 37.728084 -66.623978)
			(xy 37.829434 -66.671845) (xy 37.927156 -66.726742) (xy 38.020761 -66.788395) (xy 38.109785 -66.856497)
			(xy 38.193783 -66.93071) (xy 38.272337 -67.010662) (xy 38.345055 -67.095957) (xy 38.411576 -67.186168)
			(xy 38.471567 -67.280848) (xy 38.524731 -67.379523) (xy 38.570801 -67.481702) (xy 38.609549 -67.586877)
			(xy 38.640782 -67.694522) (xy 38.664344 -67.804103) (xy 38.680117 -67.915073) (xy 38.688024 -68.026879)
			(xy 38.688518 -68.082922) (xy 38.688024 -68.138965) (xy 38.680117 -68.250771) (xy 38.664344 -68.361741)
			(xy 38.640782 -68.471322) (xy 38.609549 -68.578967) (xy 38.570801 -68.684142) (xy 38.524731 -68.786321)
			(xy 38.471567 -68.884996) (xy 38.411576 -68.979676) (xy 38.345055 -69.069887) (xy 38.272337 -69.155182)
			(xy 38.193783 -69.235134) (xy 38.109785 -69.309347) (xy 38.020761 -69.377449) (xy 37.927156 -69.439102)
			(xy 37.829434 -69.493999) (xy 37.728084 -69.541866) (xy 37.623609 -69.582464) (xy 37.516532 -69.615592)
			(xy 37.407384 -69.641084) (xy 37.296709 -69.658813) (xy 37.18506 -69.668692) (xy 37.072992 -69.67067)
			(xy 36.961064 -69.664738) (xy 36.849833 -69.650925) (xy 36.739853 -69.629301) (xy 36.631673 -69.599973)
			(xy 36.525831 -69.563087) (xy 36.422855 -69.518827) (xy 36.323257 -69.467413) (xy 36.227533 -69.409102)
			(xy 36.136162 -69.344184) (xy 36.049597 -69.272982) (xy 35.968271 -69.195851) (xy 35.892587 -69.113176)
			(xy 35.822925 -69.025368) (xy 35.759629 -68.932865) (xy 35.703016 -68.836128) (xy 35.653368 -68.735638)
			(xy 35.610932 -68.631897) (xy 35.57592 -68.52542) (xy 35.548506 -68.416739) (xy 35.528826 -68.306395)
			(xy 35.516979 -68.194938) (xy 35.513023 -68.082922) (xy 34.052521 -68.082922) (xy 34.056498 -68.23858)
			(xy 34.068417 -68.393832) (xy 34.088248 -68.548273) (xy 34.115939 -68.7015) (xy 34.151418 -68.853113)
			(xy 34.194592 -69.002716) (xy 34.245348 -69.14992) (xy 34.303555 -69.294341) (xy 34.36906 -69.435601)
			(xy 34.441692 -69.573332) (xy 34.521262 -69.707174) (xy 34.607563 -69.836779) (xy 34.700368 -69.961809)
			(xy 34.799437 -70.081936) (xy 34.90451 -70.196849) (xy 35.015314 -70.306246) (xy 35.131559 -70.409844)
			(xy 35.252942 -70.50737) (xy 35.379146 -70.598571) (xy 35.509843 -70.68321) (xy 35.644691 -70.761064)
			(xy 35.783338 -70.831931) (xy 35.925423 -70.895627) (xy 36.070575 -70.951985) (xy 36.218415 -71.000857)
			(xy 36.368558 -71.042117) (xy 36.520611 -71.075657) (xy 36.674179 -71.101389) (xy 36.828861 -71.119246)
			(xy 36.984252 -71.129182) (xy 37.139948 -71.13117) (xy 37.295543 -71.125206) (xy 37.45063 -71.111305)
			(xy 37.604805 -71.089504) (xy 37.757666 -71.059858) (xy 37.908813 -71.022446) (xy 38.057853 -70.977365)
			(xy 38.204397 -70.924733) (xy 38.348063 -70.864687) (xy 38.488474 -70.797383) (xy 38.625267 -70.722998)
			(xy 38.758082 -70.641725) (xy 38.886575 -70.553776) (xy 39.010409 -70.459382) (xy 39.129261 -70.358787)
			(xy 39.242823 -70.252255) (xy 39.350796 -70.140064) (xy 39.4529 -70.022505) (xy 39.548869 -69.899887)
			(xy 39.638451 -69.772528) (xy 39.721413 -69.640761) (xy 39.797539 -69.50493) (xy 39.86663 -69.365389)
			(xy 39.928506 -69.222502) (xy 39.983006 -69.076642) (xy 40.029986 -68.92819) (xy 40.069326 -68.777533)
			(xy 40.100921 -68.625063) (xy 40.12469 -68.471179) (xy 40.14057 -68.316282) (xy 40.148521 -68.160776)
		)
		(stroke
			(width 0)
			(type solid)
		)
		(fill yes)
		(layer "B.Cu")
		(net "Net_301")
	)
	(gr_poly
		(pts
			(xy 71.264018 -65.009522) (xy 71.263521 -64.931668) (xy 71.25557 -64.776162) (xy 71.23969 -64.621265)
			(xy 71.215921 -64.467381) (xy 71.184326 -64.314911) (xy 71.144986 -64.164254) (xy 71.098006 -64.015802)
			(xy 71.043506 -63.869942) (xy 70.98163 -63.727055) (xy 70.912539 -63.587514) (xy 70.836413 -63.451683)
			(xy 70.753451 -63.319916) (xy 70.663869 -63.192557) (xy 70.5679 -63.069939) (xy 70.465796 -62.95238)
			(xy 70.357823 -62.840189) (xy 70.244261 -62.733657) (xy 70.125409 -62.633062) (xy 70.001575 -62.538668)
			(xy 69.873082 -62.450719) (xy 69.740267 -62.369446) (xy 69.603474 -62.295061) (xy 69.463063 -62.227757)
			(xy 69.319397 -62.167711) (xy 69.172853 -62.115079) (xy 69.023813 -62.069998) (xy 68.872666 -62.032586)
			(xy 68.719805 -62.00294) (xy 68.56563 -61.981139) (xy 68.410543 -61.967238) (xy 68.254948 -61.961274)
			(xy 68.099252 -61.963262) (xy 67.943861 -61.973198) (xy 67.789179 -61.991055) (xy 67.635611 -62.016787)
			(xy 67.483558 -62.050327) (xy 67.333415 -62.091587) (xy 67.185575 -62.140459) (xy 67.040423 -62.196817)
			(xy 66.898338 -62.260513) (xy 66.759691 -62.33138) (xy 66.624843 -62.409234) (xy 66.494146 -62.493873)
			(xy 66.367942 -62.585074) (xy 66.246559 -62.6826) (xy 66.130314 -62.786198) (xy 66.01951 -62.895595)
			(xy 65.914437 -63.010508) (xy 65.815368 -63.130635) (xy 65.722563 -63.255665) (xy 65.636262 -63.38527)
			(xy 65.556692 -63.519112) (xy 65.48406 -63.656843) (xy 65.418555 -63.798103) (xy 65.360348 -63.942524)
			(xy 65.309592 -64.089728) (xy 65.266418 -64.239331) (xy 65.230939 -64.390944) (xy 65.203248 -64.544171)
			(xy 65.183417 -64.698612) (xy 65.171498 -64.853864) (xy 65.167521 -65.009522) (xy 66.628023 -65.009522)
			(xy 66.631979 -64.897506) (xy 66.643826 -64.786049) (xy 66.663506 -64.675705) (xy 66.69092 -64.567024)
			(xy 66.725932 -64.460547) (xy 66.768368 -64.356806) (xy 66.818016 -64.256316) (xy 66.874629 -64.159579)
			(xy 66.937925 -64.067076) (xy 67.007587 -63.979268) (xy 67.083271 -63.896593) (xy 67.164597 -63.819462)
			(xy 67.251162 -63.74826) (xy 67.342533 -63.683342) (xy 67.438257 -63.625031) (xy 67.537855 -63.573617)
			(xy 67.640831 -63.529357) (xy 67.746673 -63.492471) (xy 67.854853 -63.463143) (xy 67.964833 -63.441519)
			(xy 68.076064 -63.427706) (xy 68.187992 -63.421774) (xy 68.30006 -63.423752) (xy 68.411709 -63.433631)
			(xy 68.522384 -63.45136) (xy 68.631532 -63.476852) (xy 68.738609 -63.50998) (xy 68.843084 -63.550578)
			(xy 68.944434 -63.598445) (xy 69.042156 -63.653342) (xy 69.135761 -63.714995) (xy 69.224785 -63.783097)
			(xy 69.308783 -63.85731) (xy 69.387337 -63.937262) (xy 69.460055 -64.022557) (xy 69.526576 -64.112768)
			(xy 69.586567 -64.207448) (xy 69.639731 -64.306123) (xy 69.685801 -64.408302) (xy 69.724549 -64.513477)
			(xy 69.755782 -64.621122) (xy 69.779344 -64.730703) (xy 69.795117 -64.841673) (xy 69.803024 -64.953479)
			(xy 69.803518 -65.009522) (xy 69.803024 -65.065565) (xy 69.795117 -65.177371) (xy 69.779344 -65.288341)
			(xy 69.755782 -65.397922) (xy 69.724549 -65.505567) (xy 69.685801 -65.610742) (xy 69.639731 -65.712921)
			(xy 69.586567 -65.811596) (xy 69.526576 -65.906276) (xy 69.460055 -65.996487) (xy 69.387337 -66.081782)
			(xy 69.308783 -66.161734) (xy 69.224785 -66.235947) (xy 69.135761 -66.304049) (xy 69.042156 -66.365702)
			(xy 68.944434 -66.420599) (xy 68.843084 -66.468466) (xy 68.738609 -66.509064) (xy 68.631532 -66.542192)
			(xy 68.522384 -66.567684) (xy 68.411709 -66.585413) (xy 68.30006 -66.595292) (xy 68.187992 -66.59727)
			(xy 68.076064 -66.591338) (xy 67.964833 -66.577525) (xy 67.854853 -66.555901) (xy 67.746673 -66.526573)
			(xy 67.640831 -66.489687) (xy 67.537855 -66.445427) (xy 67.438257 -66.394013) (xy 67.342533 -66.335702)
			(xy 67.251162 -66.270784) (xy 67.164597 -66.199582) (xy 67.083271 -66.122451) (xy 67.007587 -66.039776)
			(xy 66.937925 -65.951968) (xy 66.874629 -65.859465) (xy 66.818016 -65.762728) (xy 66.768368 -65.662238)
			(xy 66.725932 -65.558497) (xy 66.69092 -65.45202) (xy 66.663506 -65.343339) (xy 66.643826 -65.232995)
			(xy 66.631979 -65.121538) (xy 66.628023 -65.009522) (xy 65.167521 -65.009522) (xy 65.171498 -65.16518)
			(xy 65.183417 -65.320432) (xy 65.203248 -65.474873) (xy 65.230939 -65.6281) (xy 65.266418 -65.779713)
			(xy 65.309592 -65.929316) (xy 65.360348 -66.07652) (xy 65.418555 -66.220941) (xy 65.48406 -66.362201)
			(xy 65.556692 -66.499932) (xy 65.636262 -66.633774) (xy 65.722563 -66.763379) (xy 65.815368 -66.888409)
			(xy 65.914437 -67.008536) (xy 66.01951 -67.123449) (xy 66.130314 -67.232846) (xy 66.246559 -67.336444)
			(xy 66.367942 -67.43397) (xy 66.494146 -67.525171) (xy 66.624843 -67.60981) (xy 66.759691 -67.687664)
			(xy 66.898338 -67.758531) (xy 67.040423 -67.822227) (xy 67.185575 -67.878585) (xy 67.333415 -67.927457)
			(xy 67.483558 -67.968717) (xy 67.635611 -68.002257) (xy 67.789179 -68.027989) (xy 67.943861 -68.045846)
			(xy 68.099252 -68.055782) (xy 68.254948 -68.05777) (xy 68.410543 -68.051806) (xy 68.56563 -68.037905)
			(xy 68.719805 -68.016104) (xy 68.872666 -67.986458) (xy 69.023813 -67.949046) (xy 69.172853 -67.903965)
			(xy 69.319397 -67.851333) (xy 69.463063 -67.791287) (xy 69.603474 -67.723983) (xy 69.740267 -67.649598)
			(xy 69.873082 -67.568325) (xy 70.001575 -67.480376) (xy 70.125409 -67.385982) (xy 70.244261 -67.285387)
			(xy 70.357823 -67.178855) (xy 70.465796 -67.066664) (xy 70.5679 -66.949105) (xy 70.663869 -66.826487)
			(xy 70.753451 -66.699128) (xy 70.836413 -66.567361) (xy 70.912539 -66.43153) (xy 70.98163 -66.291989)
			(xy 71.043506 -66.149102) (xy 71.098006 -66.003242) (xy 71.144986 -65.85479) (xy 71.184326 -65.704133)
			(xy 71.215921 -65.551663) (xy 71.23969 -65.397779) (xy 71.25557 -65.242882) (xy 71.263521 -65.087376)
		)
		(stroke
			(width 0)
			(type solid)
		)
		(fill yes)
		(layer "B.Cu")
		(net "Net_299")
	)
	(gr_poly
		(pts
			(xy 71.264018 -28.484322) (xy 71.263521 -28.406468) (xy 71.25557 -28.250962) (xy 71.23969 -28.096065)
			(xy 71.215921 -27.942181) (xy 71.184326 -27.789711) (xy 71.144986 -27.639054) (xy 71.098006 -27.490602)
			(xy 71.043506 -27.344742) (xy 70.98163 -27.201855) (xy 70.912539 -27.062314) (xy 70.836413 -26.926483)
			(xy 70.753451 -26.794716) (xy 70.663869 -26.667357) (xy 70.5679 -26.544739) (xy 70.465796 -26.42718)
			(xy 70.357823 -26.314989) (xy 70.244261 -26.208457) (xy 70.125409 -26.107862) (xy 70.001575 -26.013468)
			(xy 69.873082 -25.925519) (xy 69.740267 -25.844246) (xy 69.603474 -25.769861) (xy 69.463063 -25.702557)
			(xy 69.319397 -25.642511) (xy 69.172853 -25.589879) (xy 69.023813 -25.544798) (xy 68.872666 -25.507386)
			(xy 68.719805 -25.47774) (xy 68.56563 -25.455939) (xy 68.410543 -25.442038) (xy 68.254948 -25.436074)
			(xy 68.099252 -25.438062) (xy 67.943861 -25.447998) (xy 67.789179 -25.465855) (xy 67.635611 -25.491587)
			(xy 67.483558 -25.525127) (xy 67.333415 -25.566387) (xy 67.185575 -25.615259) (xy 67.040423 -25.671617)
			(xy 66.898338 -25.735313) (xy 66.759691 -25.80618) (xy 66.624843 -25.884034) (xy 66.494146 -25.968673)
			(xy 66.367942 -26.059874) (xy 66.246559 -26.1574) (xy 66.130314 -26.260998) (xy 66.01951 -26.370395)
			(xy 65.914437 -26.485308) (xy 65.815368 -26.605435) (xy 65.722563 -26.730465) (xy 65.636262 -26.86007)
			(xy 65.556692 -26.993912) (xy 65.48406 -27.131643) (xy 65.418555 -27.272903) (xy 65.360348 -27.417324)
			(xy 65.309592 -27.564528) (xy 65.266418 -27.714131) (xy 65.230939 -27.865744) (xy 65.203248 -28.018971)
			(xy 65.183417 -28.173412) (xy 65.171498 -28.328664) (xy 65.167521 -28.484322) (xy 66.628023 -28.484322)
			(xy 66.631979 -28.372306) (xy 66.643826 -28.260849) (xy 66.663506 -28.150505) (xy 66.69092 -28.041824)
			(xy 66.725932 -27.935347) (xy 66.768368 -27.831606) (xy 66.818016 -27.731116) (xy 66.874629 -27.634379)
			(xy 66.937925 -27.541876) (xy 67.007587 -27.454068) (xy 67.083271 -27.371393) (xy 67.164597 -27.294262)
			(xy 67.251162 -27.22306) (xy 67.342533 -27.158142) (xy 67.438257 -27.099831) (xy 67.537855 -27.048417)
			(xy 67.640831 -27.004157) (xy 67.746673 -26.967271) (xy 67.854853 -26.937943) (xy 67.964833 -26.916319)
			(xy 68.076064 -26.902506) (xy 68.187992 -26.896574) (xy 68.30006 -26.898552) (xy 68.411709 -26.908431)
			(xy 68.522384 -26.92616) (xy 68.631532 -26.951652) (xy 68.738609 -26.98478) (xy 68.843084 -27.025378)
			(xy 68.944434 -27.073245) (xy 69.042156 -27.128142) (xy 69.135761 -27.189795) (xy 69.224785 -27.257897)
			(xy 69.308783 -27.33211) (xy 69.387337 -27.412062) (xy 69.460055 -27.497357) (xy 69.526576 -27.587568)
			(xy 69.586567 -27.682248) (xy 69.639731 -27.780923) (xy 69.685801 -27.883102) (xy 69.724549 -27.988277)
			(xy 69.755782 -28.095922) (xy 69.779344 -28.205503) (xy 69.795117 -28.316473) (xy 69.803024 -28.428279)
			(xy 69.803518 -28.484322) (xy 69.803024 -28.540365) (xy 69.795117 -28.652171) (xy 69.779344 -28.763141)
			(xy 69.755782 -28.872722) (xy 69.724549 -28.980367) (xy 69.685801 -29.085542) (xy 69.639731 -29.187721)
			(xy 69.586567 -29.286396) (xy 69.526576 -29.381076) (xy 69.460055 -29.471287) (xy 69.387337 -29.556582)
			(xy 69.308783 -29.636534) (xy 69.224785 -29.710747) (xy 69.135761 -29.778849) (xy 69.042156 -29.840502)
			(xy 68.944434 -29.895399) (xy 68.843084 -29.943266) (xy 68.738609 -29.983864) (xy 68.631532 -30.016992)
			(xy 68.522384 -30.042484) (xy 68.411709 -30.060213) (xy 68.30006 -30.070092) (xy 68.187992 -30.07207)
			(xy 68.076064 -30.066138) (xy 67.964833 -30.052325) (xy 67.854853 -30.030701) (xy 67.746673 -30.001373)
			(xy 67.640831 -29.964487) (xy 67.537855 -29.920227) (xy 67.438257 -29.868813) (xy 67.342533 -29.810502)
			(xy 67.251162 -29.745584) (xy 67.164597 -29.674382) (xy 67.083271 -29.597251) (xy 67.007587 -29.514576)
			(xy 66.937925 -29.426768) (xy 66.874629 -29.334265) (xy 66.818016 -29.237528) (xy 66.768368 -29.137038)
			(xy 66.725932 -29.033297) (xy 66.69092 -28.92682) (xy 66.663506 -28.818139) (xy 66.643826 -28.707795)
			(xy 66.631979 -28.596338) (xy 66.628023 -28.484322) (xy 65.167521 -28.484322) (xy 65.171498 -28.63998)
			(xy 65.183417 -28.795232) (xy 65.203248 -28.949673) (xy 65.230939 -29.1029) (xy 65.266418 -29.254513)
			(xy 65.309592 -29.404116) (xy 65.360348 -29.55132) (xy 65.418555 -29.695741) (xy 65.48406 -29.837001)
			(xy 65.556692 -29.974732) (xy 65.636262 -30.108574) (xy 65.722563 -30.238179) (xy 65.815368 -30.363209)
			(xy 65.914437 -30.483336) (xy 66.01951 -30.598249) (xy 66.130314 -30.707646) (xy 66.246559 -30.811244)
			(xy 66.367942 -30.90877) (xy 66.494146 -30.999971) (xy 66.624843 -31.08461) (xy 66.759691 -31.162464)
			(xy 66.898338 -31.233331) (xy 67.040423 -31.297027) (xy 67.185575 -31.353385) (xy 67.333415 -31.402257)
			(xy 67.483558 -31.443517) (xy 67.635611 -31.477057) (xy 67.789179 -31.502789) (xy 67.943861 -31.520646)
			(xy 68.099252 -31.530582) (xy 68.254948 -31.53257) (xy 68.410543 -31.526606) (xy 68.56563 -31.512705)
			(xy 68.719805 -31.490904) (xy 68.872666 -31.461258) (xy 69.023813 -31.423846) (xy 69.172853 -31.378765)
			(xy 69.319397 -31.326133) (xy 69.463063 -31.266087) (xy 69.603474 -31.198783) (xy 69.740267 -31.124398)
			(xy 69.873082 -31.043125) (xy 70.001575 -30.955176) (xy 70.125409 -30.860782) (xy 70.244261 -30.760187)
			(xy 70.357823 -30.653655) (xy 70.465796 -30.541464) (xy 70.5679 -30.423905) (xy 70.663869 -30.301287)
			(xy 70.753451 -30.173928) (xy 70.836413 -30.042161) (xy 70.912539 -29.90633) (xy 70.98163 -29.766789)
			(xy 71.043506 -29.623902) (xy 71.098006 -29.478042) (xy 71.144986 -29.32959) (xy 71.184326 -29.178933)
			(xy 71.215921 -29.026463) (xy 71.23969 -28.872579) (xy 71.25557 -28.717682) (xy 71.263521 -28.562176)
		)
		(stroke
			(width 0)
			(type solid)
		)
		(fill yes)
		(layer "B.Cu")
		(net "Net_3")
	)
	(gr_poly
		(pts
			(xy 10.497312 -94.749874) (xy 10.496815 -94.67269) (xy 10.488868 -94.518525) (xy 10.472996 -94.364975)
			(xy 10.44924 -94.212445) (xy 10.417664 -94.06134) (xy 10.37835 -93.912061) (xy 10.331405 -93.765003)
			(xy 10.276951 -93.620558) (xy 10.215133 -93.479107) (xy 10.146116 -93.341026) (xy 10.070081 -93.206681)
			(xy 9.987232 -93.076428) (xy 9.897788 -92.950613) (xy 9.801985 -92.82957) (xy 9.700078 -92.713618)
			(xy 9.592337 -92.603067) (xy 9.479048 -92.498208) (xy 9.360511 -92.39932) (xy 9.237041 -92.306666)
			(xy 9.108965 -92.220491) (xy 8.976622 -92.141023) (xy 8.840364 -92.068473) (xy 8.700551 -92.003034)
			(xy 8.557556 -91.944878) (xy 8.411756 -91.894162) (xy 8.263539 -91.851018) (xy 8.113297 -91.815561)
			(xy 7.961429 -91.787886) (xy 7.808338 -91.768065) (xy 7.65443 -91.756152) (xy 7.500112 -91.752177)
			(xy 7.345794 -91.756152) (xy 7.191886 -91.768065) (xy 7.038795 -91.787886) (xy 6.886927 -91.815561)
			(xy 6.736685 -91.851018) (xy 6.588468 -91.894162) (xy 6.442668 -91.944878) (xy 6.299673 -92.003034)
			(xy 6.15986 -92.068473) (xy 6.023602 -92.141023) (xy 5.891259 -92.220491) (xy 5.763183 -92.306666)
			(xy 5.639713 -92.39932) (xy 5.521176 -92.498208) (xy 5.407887 -92.603067) (xy 5.300146 -92.713618)
			(xy 5.198239 -92.82957) (xy 5.102436 -92.950613) (xy 5.012992 -93.076428) (xy 4.930143 -93.206681)
			(xy 4.854108 -93.341026) (xy 4.785091 -93.479107) (xy 4.723273 -93.620558) (xy 4.668819 -93.765003)
			(xy 4.621874 -93.912061) (xy 4.58256 -94.06134) (xy 4.550984 -94.212445) (xy 4.527228 -94.364975)
			(xy 4.511356 -94.518525) (xy 4.503409 -94.67269) (xy 4.503409 -94.749874) (xy 5.594612 -94.749874)
			(xy 5.598608 -94.626531) (xy 5.61058 -94.503706) (xy 5.630477 -94.381913) (xy 5.658216 -94.261664)
			(xy 5.693681 -94.143462) (xy 5.736722 -94.027804) (xy 5.787159 -93.915174) (xy 5.844782 -93.806046)
			(xy 5.909347 -93.700876) (xy 5.980585 -93.600106) (xy 6.058196 -93.504158) (xy 6.141855 -93.413436)
			(xy 6.231211 -93.328319) (xy 6.325889 -93.249164) (xy 6.425492 -93.176304) (xy 6.529602 -93.110044)
			(xy 6.637784 -93.050662) (xy 6.749582 -92.998408) (xy 6.864528 -92.953499) (xy 6.98214 -92.916125)
			(xy 7.101924 -92.886443) (xy 7.223379 -92.864576) (xy 7.345994 -92.850617) (xy 7.469256 -92.844624)
			(xy 7.592647 -92.846622) (xy 7.71565 -92.856603) (xy 7.837749 -92.874526) (xy 7.958432 -92.900314)
			(xy 8.077193 -92.93386) (xy 8.193533 -92.975023) (xy 8.306964 -93.02363) (xy 8.417012 -93.079477)
			(xy 8.523213 -93.142331) (xy 8.625124 -93.211928) (xy 8.722315 -93.287975) (xy 8.814381 -93.370154)
			(xy 8.900933 -93.45812) (xy 8.981611 -93.551504) (xy 9.056074 -93.649914) (xy 9.124011 -93.752938)
			(xy 9.185137 -93.860143) (xy 9.239195 -93.971081) (xy 9.285959 -94.085284) (xy 9.325233 -94.202276)
			(xy 9.356851 -94.321564) (xy 9.380682 -94.442648) (xy 9.396625 -94.565022) (xy 9.404613 -94.68817)
			(xy 9.405112 -94.749874) (xy 9.404613 -94.811578) (xy 9.396625 -94.934726) (xy 9.380682 -95.0571)
			(xy 9.356851 -95.178184) (xy 9.325233 -95.297472) (xy 9.285959 -95.414464) (xy 9.239195 -95.528667)
			(xy 9.185137 -95.639605) (xy 9.124011 -95.74681) (xy 9.056074 -95.849834) (xy 8.981611 -95.948244)
			(xy 8.900933 -96.041628) (xy 8.814381 -96.129594) (xy 8.722315 -96.211773) (xy 8.625124 -96.28782)
			(xy 8.523213 -96.357417) (xy 8.417012 -96.420271) (xy 8.306964 -96.476118) (xy 8.193533 -96.524725)
			(xy 8.077193 -96.565888) (xy 7.958432 -96.599434) (xy 7.837749 -96.625222) (xy 7.71565 -96.643145)
			(xy 7.592647 -96.653126) (xy 7.469256 -96.655124) (xy 7.345994 -96.649131) (xy 7.223379 -96.635172)
			(xy 7.101924 -96.613305) (xy 6.98214 -96.583623) (xy 6.864528 -96.546249) (xy 6.749582 -96.50134)
			(xy 6.637784 -96.449086) (xy 6.529602 -96.389704) (xy 6.425492 -96.323444) (xy 6.325889 -96.250584)
			(xy 6.231211 -96.171429) (xy 6.141855 -96.086312) (xy 6.058196 -95.99559) (xy 5.980585 -95.899642)
			(xy 5.909347 -95.798872) (xy 5.844782 -95.693702) (xy 5.787159 -95.584574) (xy 5.736722 -95.471944)
			(xy 5.693681 -95.356286) (xy 5.658216 -95.238084) (xy 5.630477 -95.117835) (xy 5.61058 -94.996042)
			(xy 5.598608 -94.873217) (xy 5.594612 -94.749874) (xy 4.503409 -94.749874) (xy 4.503409 -94.827058)
			(xy 4.511356 -94.981223) (xy 4.527228 -95.134773) (xy 4.550984 -95.287303) (xy 4.58256 -95.438408)
			(xy 4.621874 -95.587687) (xy 4.668819 -95.734745) (xy 4.723273 -95.87919) (xy 4.785091 -96.020641)
			(xy 4.854108 -96.158722) (xy 4.930143 -96.293067) (xy 5.012992 -96.42332) (xy 5.102436 -96.549135)
			(xy 5.198239 -96.670178) (xy 5.300146 -96.78613) (xy 5.407887 -96.896681) (xy 5.521176 -97.00154)
			(xy 5.639713 -97.100428) (xy 5.763183 -97.193082) (xy 5.891259 -97.279257) (xy 6.023602 -97.358725)
			(xy 6.15986 -97.431275) (xy 6.299673 -97.496714) (xy 6.442668 -97.55487) (xy 6.588468 -97.605586)
			(xy 6.736685 -97.64873) (xy 6.886927 -97.684187) (xy 7.038795 -97.711862) (xy 7.191886 -97.731683)
			(xy 7.345794 -97.743596) (xy 7.500112 -97.747571) (xy 7.65443 -97.743596) (xy 7.808338 -97.731683)
			(xy 7.961429 -97.711862) (xy 8.113297 -97.684187) (xy 8.263539 -97.64873) (xy 8.411756 -97.605586)
			(xy 8.557556 -97.55487) (xy 8.700551 -97.496714) (xy 8.840364 -97.431275) (xy 8.976622 -97.358725)
			(xy 9.108965 -97.279257) (xy 9.237041 -97.193082) (xy 9.360511 -97.100428) (xy 9.479048 -97.00154)
			(xy 9.592337 -96.896681) (xy 9.700078 -96.78613) (xy 9.801985 -96.670178) (xy 9.897788 -96.549135)
			(xy 9.987232 -96.42332) (xy 10.070081 -96.293067) (xy 10.146116 -96.158722) (xy 10.215133 -96.020641)
			(xy 10.276951 -95.87919) (xy 10.331405 -95.734745) (xy 10.37835 -95.587687) (xy 10.417664 -95.438408)
			(xy 10.44924 -95.287303) (xy 10.472996 -95.134773) (xy 10.488868 -94.981223) (xy 10.496815 -94.827058)
		)
		(stroke
			(width 0)
			(type solid)
		)
		(fill yes)
		(layer "B.Cu")
		(net "SG")
	)
	(gr_poly
		(pts
			(xy 10.497312 -9.349994) (xy 10.496815 -9.27281) (xy 10.488868 -9.118645) (xy 10.472996 -8.965095)
			(xy 10.44924 -8.812565) (xy 10.417664 -8.66146) (xy 10.37835 -8.512181) (xy 10.331405 -8.365123)
			(xy 10.276951 -8.220678) (xy 10.215133 -8.079227) (xy 10.146116 -7.941146) (xy 10.070081 -7.806801)
			(xy 9.987232 -7.676548) (xy 9.897788 -7.550733) (xy 9.801985 -7.42969) (xy 9.700078 -7.313738) (xy 9.592337 -7.203187)
			(xy 9.479048 -7.098328) (xy 9.360511 -6.99944) (xy 9.237041 -6.906786) (xy 9.108965 -6.820611) (xy 8.976622 -6.741143)
			(xy 8.840364 -6.668593) (xy 8.700551 -6.603154) (xy 8.557556 -6.544998) (xy 8.411756 -6.494282) (xy 8.263539 -6.451138)
			(xy 8.113297 -6.415681) (xy 7.961429 -6.388006) (xy 7.808338 -6.368185) (xy 7.65443 -6.356272) (xy 7.500112 -6.352297)
			(xy 7.345794 -6.356272) (xy 7.191886 -6.368185) (xy 7.038795 -6.388006) (xy 6.886927 -6.415681) (xy 6.736685 -6.451138)
			(xy 6.588468 -6.494282) (xy 6.442668 -6.544998) (xy 6.299673 -6.603154) (xy 6.15986 -6.668593) (xy 6.023602 -6.741143)
			(xy 5.891259 -6.820611) (xy 5.763183 -6.906786) (xy 5.639713 -6.99944) (xy 5.521176 -7.098328) (xy 5.407887 -7.203187)
			(xy 5.300146 -7.313738) (xy 5.198239 -7.42969) (xy 5.102436 -7.550733) (xy 5.012992 -7.676548) (xy 4.930143 -7.806801)
			(xy 4.854108 -7.941146) (xy 4.785091 -8.079227) (xy 4.723273 -8.220678) (xy 4.668819 -8.365123) (xy 4.621874 -8.512181)
			(xy 4.58256 -8.66146) (xy 4.550984 -8.812565) (xy 4.527228 -8.965095) (xy 4.511356 -9.118645) (xy 4.503409 -9.27281)
			(xy 4.503409 -9.349994) (xy 5.594612 -9.349994) (xy 5.598608 -9.226651) (xy 5.61058 -9.103826) (xy 5.630477 -8.982033)
			(xy 5.658216 -8.861784) (xy 5.693681 -8.743582) (xy 5.736722 -8.627924) (xy 5.787159 -8.515294) (xy 5.844782 -8.406166)
			(xy 5.909347 -8.300996) (xy 5.980585 -8.200226) (xy 6.058196 -8.104278) (xy 6.141855 -8.013556) (xy 6.231211 -7.928439)
			(xy 6.325889 -7.849284) (xy 6.425492 -7.776424) (xy 6.529602 -7.710164) (xy 6.637784 -7.650782) (xy 6.749582 -7.598528)
			(xy 6.864528 -7.553619) (xy 6.98214 -7.516245) (xy 7.101924 -7.486563) (xy 7.223379 -7.464696) (xy 7.345994 -7.450737)
			(xy 7.469256 -7.444744) (xy 7.592647 -7.446742) (xy 7.71565 -7.456723) (xy 7.837749 -7.474646) (xy 7.958432 -7.500434)
			(xy 8.077193 -7.53398) (xy 8.193533 -7.575143) (xy 8.306964 -7.62375) (xy 8.417012 -7.679597) (xy 8.523213 -7.742451)
			(xy 8.625124 -7.812048) (xy 8.722315 -7.888095) (xy 8.814381 -7.970274) (xy 8.900933 -8.05824) (xy 8.981611 -8.151624)
			(xy 9.056074 -8.250034) (xy 9.124011 -8.353058) (xy 9.185137 -8.460263) (xy 9.239195 -8.571201) (xy 9.285959 -8.685404)
			(xy 9.325233 -8.802396) (xy 9.356851 -8.921684) (xy 9.380682 -9.042768) (xy 9.396625 -9.165142) (xy 9.404613 -9.28829)
			(xy 9.405112 -9.349994) (xy 9.404613 -9.411698) (xy 9.396625 -9.534846) (xy 9.380682 -9.65722) (xy 9.356851 -9.778304)
			(xy 9.325233 -9.897592) (xy 9.285959 -10.014584) (xy 9.239195 -10.128787) (xy 9.185137 -10.239725)
			(xy 9.124011 -10.34693) (xy 9.056074 -10.449954) (xy 8.981611 -10.548364) (xy 8.900933 -10.641748)
			(xy 8.814381 -10.729714) (xy 8.722315 -10.811893) (xy 8.625124 -10.88794) (xy 8.523213 -10.957537)
			(xy 8.417012 -11.020391) (xy 8.306964 -11.076238) (xy 8.193533 -11.124845) (xy 8.077193 -11.166008)
			(xy 7.958432 -11.199554) (xy 7.837749 -11.225342) (xy 7.71565 -11.243265) (xy 7.592647 -11.253246)
			(xy 7.469256 -11.255244) (xy 7.345994 -11.249251) (xy 7.223379 -11.235292) (xy 7.101924 -11.213425)
			(xy 6.98214 -11.183743) (xy 6.864528 -11.146369) (xy 6.749582 -11.10146) (xy 6.637784 -11.049206)
			(xy 6.529602 -10.989824) (xy 6.425492 -10.923564) (xy 6.325889 -10.850704) (xy 6.231211 -10.771549)
			(xy 6.141855 -10.686432) (xy 6.058196 -10.59571) (xy 5.980585 -10.499762) (xy 5.909347 -10.398992)
			(xy 5.844782 -10.293822) (xy 5.787159 -10.184694) (xy 5.736722 -10.072064) (xy 5.693681 -9.956406)
			(xy 5.658216 -9.838204) (xy 5.630477 -9.717955) (xy 5.61058 -9.596162) (xy 5.598608 -9.473337) (xy 5.594612 -9.349994)
			(xy 4.503409 -9.349994) (xy 4.503409 -9.427178) (xy 4.511356 -9.581343) (xy 4.527228 -9.734893) (xy 4.550984 -9.887423)
			(xy 4.58256 -10.038528) (xy 4.621874 -10.187807) (xy 4.668819 -10.334865) (xy 4.723273 -10.47931)
			(xy 4.785091 -10.620761) (xy 4.854108 -10.758842) (xy 4.930143 -10.893187) (xy 5.012992 -11.02344)
			(xy 5.102436 -11.149255) (xy 5.198239 -11.270298) (xy 5.300146 -11.38625) (xy 5.407887 -11.496801)
			(xy 5.521176 -11.60166) (xy 5.639713 -11.700548) (xy 5.763183 -11.793202) (xy 5.891259 -11.879377)
			(xy 6.023602 -11.958845) (xy 6.15986 -12.031395) (xy 6.299673 -12.096834) (xy 6.442668 -12.15499)
			(xy 6.588468 -12.205706) (xy 6.736685 -12.24885) (xy 6.886927 -12.284307) (xy 7.038795 -12.311982)
			(xy 7.191886 -12.331803) (xy 7.345794 -12.343716) (xy 7.500112 -12.347691) (xy 7.65443 -12.343716)
			(xy 7.808338 -12.331803) (xy 7.961429 -12.311982) (xy 8.113297 -12.284307) (xy 8.263539 -12.24885)
			(xy 8.411756 -12.205706) (xy 8.557556 -12.15499) (xy 8.700551 -12.096834) (xy 8.840364 -12.031395)
			(xy 8.976622 -11.958845) (xy 9.108965 -11.879377) (xy 9.237041 -11.793202) (xy 9.360511 -11.700548)
			(xy 9.479048 -11.60166) (xy 9.592337 -11.496801) (xy 9.700078 -11.38625) (xy 9.801985 -11.270298)
			(xy 9.897788 -11.149255) (xy 9.987232 -11.02344) (xy 10.070081 -10.893187) (xy 10.146116 -10.758842)
			(xy 10.215133 -10.620761) (xy 10.276951 -10.47931) (xy 10.331405 -10.334865) (xy 10.37835 -10.187807)
			(xy 10.417664 -10.038528) (xy 10.44924 -9.887423) (xy 10.472996 -9.734893) (xy 10.488868 -9.581343)
			(xy 10.496815 -9.427178)
		)
		(stroke
			(width 0)
			(type solid)
		)
		(fill yes)
		(layer "B.Cu")
		(net "SG")
	)
	(gr_poly
		(pts
			(xy 165.567106 -106.13009) (xy 165.566609 -106.052906) (xy 165.558662 -105.898741) (xy 165.54279 -105.745191)
			(xy 165.519034 -105.592661) (xy 165.487458 -105.441556) (xy 165.448144 -105.292277) (xy 165.401199 -105.145219)
			(xy 165.346745 -105.000774) (xy 165.284927 -104.859323) (xy 165.21591 -104.721242) (xy 165.139875 -104.586897)
			(xy 165.057026 -104.456644) (xy 164.967582 -104.330829) (xy 164.871779 -104.209786) (xy 164.769872 -104.093834)
			(xy 164.662131 -103.983283) (xy 164.548842 -103.878424) (xy 164.430305 -103.779536) (xy 164.306835 -103.686882)
			(xy 164.178759 -103.600707) (xy 164.046416 -103.521239) (xy 163.910158 -103.448689) (xy 163.770345 -103.38325)
			(xy 163.62735 -103.325094) (xy 163.48155 -103.274378) (xy 163.333333 -103.231234) (xy 163.183091 -103.195777)
			(xy 163.031223 -103.168102) (xy 162.878132 -103.148281) (xy 162.724224 -103.136368) (xy 162.569906 -103.132393)
			(xy 162.415588 -103.136368) (xy 162.26168 -103.148281) (xy 162.108589 -103.168102) (xy 161.956721 -103.195777)
			(xy 161.806479 -103.231234) (xy 161.658262 -103.274378) (xy 161.512462 -103.325094) (xy 161.369467 -103.38325)
			(xy 161.229654 -103.448689) (xy 161.093396 -103.521239) (xy 160.961053 -103.600707) (xy 160.832977 -103.686882)
			(xy 160.709507 -103.779536) (xy 160.59097 -103.878424) (xy 160.477681 -103.983283) (xy 160.36994 -104.093834)
			(xy 160.268033 -104.209786) (xy 160.17223 -104.330829) (xy 160.082786 -104.456644) (xy 159.999937 -104.586897)
			(xy 159.923902 -104.721242) (xy 159.854885 -104.859323) (xy 159.793067 -105.000774) (xy 159.738613 -105.145219)
			(xy 159.691668 -105.292277) (xy 159.652354 -105.441556) (xy 159.620778 -105.592661) (xy 159.597022 -105.745191)
			(xy 159.58115 -105.898741) (xy 159.573203 -106.052906) (xy 159.573203 -106.13009) (xy 160.664406 -106.13009)
			(xy 160.668402 -106.006747) (xy 160.680374 -105.883922) (xy 160.700271 -105.762129) (xy 160.72801 -105.64188)
			(xy 160.763475 -105.523678) (xy 160.806516 -105.40802) (xy 160.856953 -105.29539) (xy 160.914576 -105.186262)
			(xy 160.979141 -105.081092) (xy 161.050379 -104.980322) (xy 161.12799 -104.884374) (xy 161.211649 -104.793652)
			(xy 161.301005 -104.708535) (xy 161.395683 -104.62938) (xy 161.495286 -104.55652) (xy 161.599396 -104.49026)
			(xy 161.707578 -104.430878) (xy 161.819376 -104.378624) (xy 161.934322 -104.333715) (xy 162.051934 -104.296341)
			(xy 162.171718 -104.266659) (xy 162.293173 -104.244792) (xy 162.415788 -104.230833) (xy 162.53905 -104.22484)
			(xy 162.662441 -104.226838) (xy 162.785444 -104.236819) (xy 162.907543 -104.254742) (xy 163.028226 -104.28053)
			(xy 163.146987 -104.314076) (xy 163.263327 -104.355239) (xy 163.376758 -104.403846) (xy 163.486806 -104.459693)
			(xy 163.593007 -104.522547) (xy 163.694918 -104.592144) (xy 163.792109 -104.668191) (xy 163.884175 -104.75037)
			(xy 163.970727 -104.838336) (xy 164.051405 -104.93172) (xy 164.125868 -105.03013) (xy 164.193805 -105.133154)
			(xy 164.254931 -105.240359) (xy 164.308989 -105.351297) (xy 164.355753 -105.4655) (xy 164.395027 -105.582492)
			(xy 164.426645 -105.70178) (xy 164.450476 -105.822864) (xy 164.466419 -105.945238) (xy 164.474407 -106.068386)
			(xy 164.474906 -106.13009) (xy 164.474407 -106.191794) (xy 164.466419 -106.314942) (xy 164.450476 -106.437316)
			(xy 164.426645 -106.5584) (xy 164.395027 -106.677688) (xy 164.355753 -106.79468) (xy 164.308989 -106.908883)
			(xy 164.254931 -107.019821) (xy 164.193805 -107.127026) (xy 164.125868 -107.23005) (xy 164.051405 -107.32846)
			(xy 163.970727 -107.421844) (xy 163.884175 -107.50981) (xy 163.792109 -107.591989) (xy 163.694918 -107.668036)
			(xy 163.593007 -107.737633) (xy 163.486806 -107.800487) (xy 163.376758 -107.856334) (xy 163.263327 -107.904941)
			(xy 163.146987 -107.946104) (xy 163.028226 -107.97965) (xy 162.907543 -108.005438) (xy 162.785444 -108.023361)
			(xy 162.662441 -108.033342) (xy 162.53905 -108.03534) (xy 162.415788 -108.029347) (xy 162.293173 -108.015388)
			(xy 162.171718 -107.993521) (xy 162.051934 -107.963839) (xy 161.934322 -107.926465) (xy 161.819376 -107.881556)
			(xy 161.707578 -107.829302) (xy 161.599396 -107.76992) (xy 161.495286 -107.70366) (xy 161.395683 -107.6308)
			(xy 161.301005 -107.551645) (xy 161.211649 -107.466528) (xy 161.12799 -107.375806) (xy 161.050379 -107.279858)
			(xy 160.979141 -107.179088) (xy 160.914576 -107.073918) (xy 160.856953 -106.96479) (xy 160.806516 -106.85216)
			(xy 160.763475 -106.736502) (xy 160.72801 -106.6183) (xy 160.700271 -106.498051) (xy 160.680374 -106.376258)
			(xy 160.668402 -106.253433) (xy 160.664406 -106.13009) (xy 159.573203 -106.13009) (xy 159.573203 -106.207274)
			(xy 159.58115 -106.361439) (xy 159.597022 -106.514989) (xy 159.620778 -106.667519) (xy 159.652354 -106.818624)
			(xy 159.691668 -106.967903) (xy 159.738613 -107.114961) (xy 159.793067 -107.259406) (xy 159.854885 -107.400857)
			(xy 159.923902 -107.538938) (xy 159.999937 -107.673283) (xy 160.082786 -107.803536) (xy 160.17223 -107.929351)
			(xy 160.268033 -108.050394) (xy 160.36994 -108.166346) (xy 160.477681 -108.276897) (xy 160.59097 -108.381756)
			(xy 160.709507 -108.480644) (xy 160.832977 -108.573298) (xy 160.961053 -108.659473) (xy 161.093396 -108.738941)
			(xy 161.229654 -108.811491) (xy 161.369467 -108.87693) (xy 161.512462 -108.935086) (xy 161.658262 -108.985802)
			(xy 161.806479 -109.028946) (xy 161.956721 -109.064403) (xy 162.108589 -109.092078) (xy 162.26168 -109.111899)
			(xy 162.415588 -109.123812) (xy 162.569906 -109.127787) (xy 162.724224 -109.123812) (xy 162.878132 -109.111899)
			(xy 163.031223 -109.092078) (xy 163.183091 -109.064403) (xy 163.333333 -109.028946) (xy 163.48155 -108.985802)
			(xy 163.62735 -108.935086) (xy 163.770345 -108.87693) (xy 163.910158 -108.811491) (xy 164.046416 -108.738941)
			(xy 164.178759 -108.659473) (xy 164.306835 -108.573298) (xy 164.430305 -108.480644) (xy 164.548842 -108.381756)
			(xy 164.662131 -108.276897) (xy 164.769872 -108.166346) (xy 164.871779 -108.050394) (xy 164.967582 -107.929351)
			(xy 165.057026 -107.803536) (xy 165.139875 -107.673283) (xy 165.21591 -107.538938) (xy 165.284927 -107.400857)
			(xy 165.346745 -107.259406) (xy 165.401199 -107.114961) (xy 165.448144 -106.967903) (xy 165.487458 -106.818624)
			(xy 165.519034 -106.667519) (xy 165.54279 -106.514989) (xy 165.558662 -106.361439) (xy 165.566609 -106.207274)
		)
		(stroke
			(width 0)
			(type solid)
		)
		(fill yes)
		(layer "B.Cu")
		(net "SG")
	)
	(gr_poly
		(pts
			(xy 165.567106 -16.599916) (xy 165.566609 -16.522732) (xy 165.558662 -16.368567) (xy 165.54279 -16.215017)
			(xy 165.519034 -16.062487) (xy 165.487458 -15.911382) (xy 165.448144 -15.762103) (xy 165.401199 -15.615045)
			(xy 165.346745 -15.4706) (xy 165.284927 -15.329149) (xy 165.21591 -15.191068) (xy 165.139875 -15.056723)
			(xy 165.057026 -14.92647) (xy 164.967582 -14.800655) (xy 164.871779 -14.679612) (xy 164.769872 -14.56366)
			(xy 164.662131 -14.453109) (xy 164.548842 -14.34825) (xy 164.430305 -14.249362) (xy 164.306835 -14.156708)
			(xy 164.178759 -14.070533) (xy 164.046416 -13.991065) (xy 163.910158 -13.918515) (xy 163.770345 -13.853076)
			(xy 163.62735 -13.79492) (xy 163.48155 -13.744204) (xy 163.333333 -13.70106) (xy 163.183091 -13.665603)
			(xy 163.031223 -13.637928) (xy 162.878132 -13.618107) (xy 162.724224 -13.606194) (xy 162.569906 -13.602219)
			(xy 162.415588 -13.606194) (xy 162.26168 -13.618107) (xy 162.108589 -13.637928) (xy 161.956721 -13.665603)
			(xy 161.806479 -13.70106) (xy 161.658262 -13.744204) (xy 161.512462 -13.79492) (xy 161.369467 -13.853076)
			(xy 161.229654 -13.918515) (xy 161.093396 -13.991065) (xy 160.961053 -14.070533) (xy 160.832977 -14.156708)
			(xy 160.709507 -14.249362) (xy 160.59097 -14.34825) (xy 160.477681 -14.453109) (xy 160.36994 -14.56366)
			(xy 160.268033 -14.679612) (xy 160.17223 -14.800655) (xy 160.082786 -14.92647) (xy 159.999937 -15.056723)
			(xy 159.923902 -15.191068) (xy 159.854885 -15.329149) (xy 159.793067 -15.4706) (xy 159.738613 -15.615045)
			(xy 159.691668 -15.762103) (xy 159.652354 -15.911382) (xy 159.620778 -16.062487) (xy 159.597022 -16.215017)
			(xy 159.58115 -16.368567) (xy 159.573203 -16.522732) (xy 159.573203 -16.599916) (xy 160.664406 -16.599916)
			(xy 160.668402 -16.476573) (xy 160.680374 -16.353748) (xy 160.700271 -16.231955) (xy 160.72801 -16.111706)
			(xy 160.763475 -15.993504) (xy 160.806516 -15.877846) (xy 160.856953 -15.765216) (xy 160.914576 -15.656088)
			(xy 160.979141 -15.550918) (xy 161.050379 -15.450148) (xy 161.12799 -15.3542) (xy 161.211649 -15.263478)
			(xy 161.301005 -15.178361) (xy 161.395683 -15.099206) (xy 161.495286 -15.026346) (xy 161.599396 -14.960086)
			(xy 161.707578 -14.900704) (xy 161.819376 -14.84845) (xy 161.934322 -14.803541) (xy 162.051934 -14.766167)
			(xy 162.171718 -14.736485) (xy 162.293173 -14.714618) (xy 162.415788 -14.700659) (xy 162.53905 -14.694666)
			(xy 162.662441 -14.696664) (xy 162.785444 -14.706645) (xy 162.907543 -14.724568) (xy 163.028226 -14.750356)
			(xy 163.146987 -14.783902) (xy 163.263327 -14.825065) (xy 163.376758 -14.873672) (xy 163.486806 -14.929519)
			(xy 163.593007 -14.992373) (xy 163.694918 -15.06197) (xy 163.792109 -15.138017) (xy 163.884175 -15.220196)
			(xy 163.970727 -15.308162) (xy 164.051405 -15.401546) (xy 164.125868 -15.499956) (xy 164.193805 -15.60298)
			(xy 164.254931 -15.710185) (xy 164.308989 -15.821123) (xy 164.355753 -15.935326) (xy 164.395027 -16.052318)
			(xy 164.426645 -16.171606) (xy 164.450476 -16.29269) (xy 164.466419 -16.415064) (xy 164.474407 -16.538212)
			(xy 164.474906 -16.599916) (xy 164.474407 -16.66162) (xy 164.466419 -16.784768) (xy 164.450476 -16.907142)
			(xy 164.426645 -17.028226) (xy 164.395027 -17.147514) (xy 164.355753 -17.264506) (xy 164.308989 -17.378709)
			(xy 164.254931 -17.489647) (xy 164.193805 -17.596852) (xy 164.125868 -17.699876) (xy 164.051405 -17.798286)
			(xy 163.970727 -17.89167) (xy 163.884175 -17.979636) (xy 163.792109 -18.061815) (xy 163.694918 -18.137862)
			(xy 163.593007 -18.207459) (xy 163.486806 -18.270313) (xy 163.376758 -18.32616) (xy 163.263327 -18.374767)
			(xy 163.146987 -18.41593) (xy 163.028226 -18.449476) (xy 162.907543 -18.475264) (xy 162.785444 -18.493187)
			(xy 162.662441 -18.503168) (xy 162.53905 -18.505166) (xy 162.415788 -18.499173) (xy 162.293173 -18.485214)
			(xy 162.171718 -18.463347) (xy 162.051934 -18.433665) (xy 161.934322 -18.396291) (xy 161.819376 -18.351382)
			(xy 161.707578 -18.299128) (xy 161.599396 -18.239746) (xy 161.495286 -18.173486) (xy 161.395683 -18.100626)
			(xy 161.301005 -18.021471) (xy 161.211649 -17.936354) (xy 161.12799 -17.845632) (xy 161.050379 -17.749684)
			(xy 160.979141 -17.648914) (xy 160.914576 -17.543744) (xy 160.856953 -17.434616) (xy 160.806516 -17.321986)
			(xy 160.763475 -17.206328) (xy 160.72801 -17.088126) (xy 160.700271 -16.967877) (xy 160.680374 -16.846084)
			(xy 160.668402 -16.723259) (xy 160.664406 -16.599916) (xy 159.573203 -16.599916) (xy 159.573203 -16.6771)
			(xy 159.58115 -16.831265) (xy 159.597022 -16.984815) (xy 159.620778 -17.137345) (xy 159.652354 -17.28845)
			(xy 159.691668 -17.437729) (xy 159.738613 -17.584787) (xy 159.793067 -17.729232) (xy 159.854885 -17.870683)
			(xy 159.923902 -18.008764) (xy 159.999937 -18.143109) (xy 160.082786 -18.273362) (xy 160.17223 -18.399177)
			(xy 160.268033 -18.52022) (xy 160.36994 -18.636172) (xy 160.477681 -18.746723) (xy 160.59097 -18.851582)
			(xy 160.709507 -18.95047) (xy 160.832977 -19.043124) (xy 160.961053 -19.129299) (xy 161.093396 -19.208767)
			(xy 161.229654 -19.281317) (xy 161.369467 -19.346756) (xy 161.512462 -19.404912) (xy 161.658262 -19.455628)
			(xy 161.806479 -19.498772) (xy 161.956721 -19.534229) (xy 162.108589 -19.561904) (xy 162.26168 -19.581725)
			(xy 162.415588 -19.593638) (xy 162.569906 -19.597613) (xy 162.724224 -19.593638) (xy 162.878132 -19.581725)
			(xy 163.031223 -19.561904) (xy 163.183091 -19.534229) (xy 163.333333 -19.498772) (xy 163.48155 -19.455628)
			(xy 163.62735 -19.404912) (xy 163.770345 -19.346756) (xy 163.910158 -19.281317) (xy 164.046416 -19.208767)
			(xy 164.178759 -19.129299) (xy 164.306835 -19.043124) (xy 164.430305 -18.95047) (xy 164.548842 -18.851582)
			(xy 164.662131 -18.746723) (xy 164.769872 -18.636172) (xy 164.871779 -18.52022) (xy 164.967582 -18.399177)
			(xy 165.057026 -18.273362) (xy 165.139875 -18.143109) (xy 165.21591 -18.008764) (xy 165.284927 -17.870683)
			(xy 165.346745 -17.729232) (xy 165.401199 -17.584787) (xy 165.448144 -17.437729) (xy 165.487458 -17.28845)
			(xy 165.519034 -17.137345) (xy 165.54279 -16.984815) (xy 165.558662 -16.831265) (xy 165.566609 -16.6771)
		)
		(stroke
			(width 0)
			(type solid)
		)
		(fill yes)
		(layer "B.Cu")
		(net "SG")
	)
	(gr_poly
		(pts
			(arc
				(start 32.349948 -14.019276)
				(mid 33.95454 -13.354632)
				(end 34.619184 -11.75004)
			)
			(xy 34.619184 -5.769356) (xy 40.080692 -5.769356)
			(arc
				(start 40.080692 -10.925048)
				(mid 40.98697 -13.112998)
				(end 43.17492 -14.019276)
			)
			(arc
				(start 43.17492 -14.019276)
				(mid 44.940952 -13.465847)
				(end 46.075346 -12.003532)
			)
			(arc
				(start 45.792644 -11.72083)
				(mid 45.697719 -11.693702)
				(end 45.624496 -11.759946)
			)
			(arc
				(start 45.624496 -11.759946)
				(mid 44.681042 -13.029585)
				(end 43.17492 -13.513054)
			)
			(arc
				(start 43.17492 -13.513054)
				(mid 41.344923 -12.755045)
				(end 40.586914 -10.925048)
			)
			(arc
				(start 40.586914 -5.500116)
				(mid 40.517504 -5.332544)
				(end 40.349932 -5.263134)
			)
			(arc
				(start 34.349944 -5.263134)
				(mid 34.182372 -5.332544)
				(end 34.112962 -5.500116)
			)
			(arc
				(start 34.112962 -11.75004)
				(mid 33.596587 -12.996679)
				(end 32.349948 -13.513054)
			)
			(arc
				(start 15.999968 -13.513054)
				(mid 14.753329 -12.996679)
				(end 14.236954 -11.75004)
			)
			(arc
				(start 14.236954 -5.500116)
				(mid 14.167544 -5.332544)
				(end 13.999972 -5.263134)
			)
			(arc
				(start 0.999998 -5.263134)
				(mid 0.832426 -5.332544)
				(end 0.763016 -5.500116)
			)
			(xy 0.763016 -13.843) (xy 1.244092 -13.843) (xy 1.269492 -13.8176) (xy 1.269492 -5.769356) (xy 13.730732 -5.769356)
			(arc
				(start 13.730732 -11.75004)
				(mid 14.395376 -13.354632)
				(end 15.999968 -14.019276)
			)
		)
		(stroke
			(width 0)
			(type solid)
		)
		(fill yes)
		(layer "B.Cu")
		(net "SG")
	)
	(gr_line
		(start 0 -110.149894)
		(end 0 -5.500116)
		(stroke
			(width 4.064)
			(type default)
		)
		(layer "In4.Cu")
	)
	(gr_arc
		(start 0 -110.149894)
		(mid 0.292894 -110.856997)
		(end 0.999998 -111.149892)
		(stroke
			(width 4.064)
			(type default)
		)
		(layer "In4.Cu")
	)
	(gr_arc
		(start 0.999998 -4.500118)
		(mid 0.292893 -4.793011)
		(end 0 -5.500116)
		(stroke
			(width 4.064)
			(type default)
		)
		(layer "In4.Cu")
	)
	(gr_line
		(start 0.999998 -4.500118)
		(end 13.999972 -4.500118)
		(stroke
			(width 4.064)
			(type default)
		)
		(layer "In4.Cu")
	)
	(gr_line
		(start 12.85875 -109.6645)
		(end 13.81125 -108.712)
		(stroke
			(width 1.016)
			(type default)
		)
		(layer "In4.Cu")
	)
	(gr_line
		(start 13.81125 -108.712)
		(end 14.82725 -109.728)
		(stroke
			(width 1.016)
			(type default)
		)
		(layer "In4.Cu")
	)
	(gr_line
		(start 13.843 -98.425)
		(end 13.843 -114.3)
		(stroke
			(width 1.016)
			(type default)
		)
		(layer "In4.Cu")
	)
	(gr_line
		(start 14.732 -97.536)
		(end 13.843 -98.425)
		(stroke
			(width 1.016)
			(type default)
		)
		(layer "In4.Cu")
	)
	(gr_line
		(start 14.732 -97.536)
		(end 15.367 -98.171)
		(stroke
			(width 1.016)
			(type default)
		)
		(layer "In4.Cu")
	)
	(gr_line
		(start 14.732 -56.642)
		(end 14.732 -97.536)
		(stroke
			(width 1.016)
			(type default)
		)
		(layer "In4.Cu")
	)
	(gr_arc
		(start 14.99997 -11.75004)
		(mid 15.292863 -12.457145)
		(end 15.999968 -12.750038)
		(stroke
			(width 4.064)
			(type default)
		)
		(layer "In4.Cu")
	)
	(gr_arc
		(start 14.99997 -5.500116)
		(mid 14.707081 -4.79301)
		(end 13.999972 -4.500118)
		(stroke
			(width 4.064)
			(type default)
		)
		(layer "In4.Cu")
	)
	(gr_line
		(start 14.99997 -5.500116)
		(end 14.99997 -11.75004)
		(stroke
			(width 4.064)
			(type default)
		)
		(layer "In4.Cu")
	)
	(gr_line
		(start 15.367 -98.171)
		(end 18.923 -98.171)
		(stroke
			(width 1.016)
			(type default)
		)
		(layer "In4.Cu")
	)
	(gr_line
		(start 15.999968 -12.750038)
		(end 32.349948 -12.750038)
		(stroke
			(width 4.064)
			(type default)
		)
		(layer "In4.Cu")
	)
	(gr_line
		(start 18.923 -98.171)
		(end 19.812 -97.282)
		(stroke
			(width 1.016)
			(type default)
		)
		(layer "In4.Cu")
	)
	(gr_line
		(start 19.812 -97.282)
		(end 19.812 -92.202)
		(stroke
			(width 1.016)
			(type default)
		)
		(layer "In4.Cu")
	)
	(gr_line
		(start 19.812 -92.202)
		(end 22.987 -89.027)
		(stroke
			(width 1.016)
			(type default)
		)
		(layer "In4.Cu")
	)
	(gr_line
		(start 22.987 -89.154)
		(end 23.495 -89.662)
		(stroke
			(width 1.016)
			(type default)
		)
		(layer "In4.Cu")
	)
	(gr_line
		(start 22.987 -89.027)
		(end 22.987 -89.154)
		(stroke
			(width 1.016)
			(type default)
		)
		(layer "In4.Cu")
	)
	(gr_line
		(start 22.987 -89.027)
		(end 22.987 -63.754)
		(stroke
			(width 1.016)
			(type default)
		)
		(layer "In4.Cu")
	)
	(gr_line
		(start 22.987 -63.754)
		(end 57.15 -29.591)
		(stroke
			(width 1.016)
			(type default)
		)
		(layer "In4.Cu")
	)
	(gr_line
		(start 23.495 -89.662)
		(end 22.606 -89.662)
		(stroke
			(width 1.016)
			(type default)
		)
		(layer "In4.Cu")
	)
	(gr_line
		(start 24.511 -90.551)
		(end 22.987 -89.027)
		(stroke
			(width 1.016)
			(type default)
		)
		(layer "In4.Cu")
	)
	(gr_line
		(start 31.75 -90.551)
		(end 24.511 -90.551)
		(stroke
			(width 1.016)
			(type default)
		)
		(layer "In4.Cu")
	)
	(gr_arc
		(start 32.349948 -12.750038)
		(mid 33.057053 -12.457145)
		(end 33.349946 -11.75004)
		(stroke
			(width 4.064)
			(type default)
		)
		(layer "In4.Cu")
	)
	(gr_line
		(start 33.349946 -11.75004)
		(end 33.349946 -5.500116)
		(stroke
			(width 4.064)
			(type default)
		)
		(layer "In4.Cu")
	)
	(gr_line
		(start 34.163 -104.521)
		(end 36.957 -107.315)
		(stroke
			(width 1.016)
			(type default)
		)
		(layer "In4.Cu")
	)
	(gr_line
		(start 34.163 -92.964)
		(end 31.75 -90.551)
		(stroke
			(width 1.016)
			(type default)
		)
		(layer "In4.Cu")
	)
	(gr_line
		(start 34.163 -92.964)
		(end 34.163 -104.521)
		(stroke
			(width 1.016)
			(type default)
		)
		(layer "In4.Cu")
	)
	(gr_arc
		(start 34.349944 -4.500118)
		(mid 33.642816 -4.792996)
		(end 33.349946 -5.500116)
		(stroke
			(width 4.064)
			(type default)
		)
		(layer "In4.Cu")
	)
	(gr_line
		(start 34.349944 -4.500118)
		(end 40.349932 -4.500118)
		(stroke
			(width 4.064)
			(type default)
		)
		(layer "In4.Cu")
	)
	(gr_line
		(start 36.957 -107.315)
		(end 126.365 -107.315)
		(stroke
			(width 1.016)
			(type default)
		)
		(layer "In4.Cu")
	)
	(gr_line
		(start 38.65626 -84.52104)
		(end 38.65626 -80.73898)
		(stroke
			(width 0.508)
			(type default)
		)
		(layer "In4.Cu")
	)
	(gr_line
		(start 38.65626 -80.73898)
		(end 39.86784 -79.5274)
		(stroke
			(width 0.508)
			(type default)
		)
		(layer "In4.Cu")
	)
	(gr_line
		(start 39.10584 -84.97062)
		(end 38.65626 -84.52104)
		(stroke
			(width 0.508)
			(type default)
		)
		(layer "In4.Cu")
	)
	(gr_line
		(start 39.86784 -79.5274)
		(end 43.30192 -79.5274)
		(stroke
			(width 0.508)
			(type default)
		)
		(layer "In4.Cu")
	)
	(gr_arc
		(start 41.34993 -10.925048)
		(mid 43.17492 -12.750038)
		(end 44.99991 -10.925048)
		(stroke
			(width 4.064)
			(type default)
		)
		(layer "In4.Cu")
	)
	(gr_arc
		(start 41.34993 -5.500116)
		(mid 41.057045 -4.792989)
		(end 40.349932 -4.500118)
		(stroke
			(width 4.064)
			(type default)
		)
		(layer "In4.Cu")
	)
	(gr_line
		(start 41.34993 -5.500116)
		(end 41.34993 -10.925048)
		(stroke
			(width 4.064)
			(type default)
		)
		(layer "In4.Cu")
	)
	(gr_line
		(start 42.28592 -84.97062)
		(end 39.10584 -84.97062)
		(stroke
			(width 0.508)
			(type default)
		)
		(layer "In4.Cu")
	)
	(gr_line
		(start 42.672 -28.702)
		(end 14.732 -56.642)
		(stroke
			(width 1.016)
			(type default)
		)
		(layer "In4.Cu")
	)
	(gr_line
		(start 42.672 -5.842)
		(end 42.672 -28.702)
		(stroke
			(width 1.016)
			(type default)
		)
		(layer "In4.Cu")
	)
	(gr_line
		(start 43.30192 -79.5274)
		(end 50.44186 -86.66734)
		(stroke
			(width 0.508)
			(type default)
		)
		(layer "In4.Cu")
	)
	(gr_line
		(start 43.33875 -93.0275)
		(end 44.29125 -92.075)
		(stroke
			(width 0.508)
			(type default)
		)
		(layer "In4.Cu")
	)
	(gr_line
		(start 44.22902 -92.56776)
		(end 44.22902 -86.91372)
		(stroke
			(width 0.508)
			(type default)
		)
		(layer "In4.Cu")
	)
	(gr_line
		(start 44.22902 -86.91372)
		(end 42.28592 -84.97062)
		(stroke
			(width 0.508)
			(type default)
		)
		(layer "In4.Cu")
	)
	(gr_line
		(start 44.29125 -92.075)
		(end 45.30725 -93.091)
		(stroke
			(width 0.508)
			(type default)
		)
		(layer "In4.Cu")
	)
	(gr_line
		(start 44.5008 -6.103874)
		(end 44.5008 -0.292862)
		(stroke
			(width 0.2)
			(type default)
		)
		(layer "In4.Cu")
	)
	(gr_line
		(start 44.5008 -0.292862)
		(end 45.306488 0.512826)
		(stroke
			(width 0.2)
			(type default)
		)
		(layer "In4.Cu")
	)
	(gr_line
		(start 44.99991 -10.925048)
		(end 44.99991 -0.500126)
		(stroke
			(width 4.064)
			(type default)
		)
		(layer "In4.Cu")
	)
	(gr_line
		(start 44.99991 -0.500126)
		(end 45.500036 0)
		(stroke
			(width 4.064)
			(type default)
		)
		(layer "In4.Cu")
	)
	(gr_line
		(start 45.306488 0.512826)
		(end 79.001112 0.512826)
		(stroke
			(width 0.2)
			(type default)
		)
		(layer "In4.Cu")
	)
	(gr_line
		(start 45.500036 0)
		(end 55.699914 0)
		(stroke
			(width 4.064)
			(type default)
		)
		(layer "In4.Cu")
	)
	(gr_line
		(start 45.593 -92.964)
		(end 34.163 -92.964)
		(stroke
			(width 1.016)
			(type default)
		)
		(layer "In4.Cu")
	)
	(gr_line
		(start 47.86376 -72.33412)
		(end 23.18512 -72.33412)
		(stroke
			(width 0.508)
			(type default)
		)
		(layer "In4.Cu")
	)
	(gr_line
		(start 48.514 -95.885)
		(end 45.593 -92.964)
		(stroke
			(width 1.016)
			(type default)
		)
		(layer "In4.Cu")
	)
	(gr_line
		(start 50.44186 -86.66734)
		(end 57.26176 -86.66734)
		(stroke
			(width 0.508)
			(type default)
		)
		(layer "In4.Cu")
	)
	(gr_line
		(start 55.699914 0)
		(end 56.20004 -0.500126)
		(stroke
			(width 4.064)
			(type default)
		)
		(layer "In4.Cu")
	)
	(gr_arc
		(start 56.20004 -7.450074)
		(mid 57.15 -8.400034)
		(end 58.09996 -7.450074)
		(stroke
			(width 4.064)
			(type default)
		)
		(layer "In4.Cu")
	)
	(gr_line
		(start 56.20004 -0.500126)
		(end 56.20004 -7.450074)
		(stroke
			(width 4.064)
			(type default)
		)
		(layer "In4.Cu")
	)
	(gr_line
		(start 57.023 -19.558)
		(end 72.263 -19.558)
		(stroke
			(width 0.508)
			(type default)
		)
		(layer "In4.Cu")
	)
	(gr_line
		(start 57.0865 -18.57375)
		(end 58.039 -19.52625)
		(stroke
			(width 0.508)
			(type default)
		)
		(layer "In4.Cu")
	)
	(gr_line
		(start 57.15 -29.591)
		(end 57.15 -7.366)
		(stroke
			(width 1.016)
			(type default)
		)
		(layer "In4.Cu")
	)
	(gr_line
		(start 57.26176 -86.66734)
		(end 58.6359 -85.2932)
		(stroke
			(width 0.508)
			(type default)
		)
		(layer "In4.Cu")
	)
	(gr_line
		(start 58.039 -19.52625)
		(end 57.023 -20.54225)
		(stroke
			(width 0.508)
			(type default)
		)
		(layer "In4.Cu")
	)
	(gr_line
		(start 58.09996 -7.450074)
		(end 58.09996 -0.500126)
		(stroke
			(width 4.064)
			(type default)
		)
		(layer "In4.Cu")
	)
	(gr_line
		(start 58.09996 -0.500126)
		(end 58.600086 0)
		(stroke
			(width 4.064)
			(type default)
		)
		(layer "In4.Cu")
	)
	(gr_line
		(start 58.57875 -84.04225)
		(end 59.53125 -83.08975)
		(stroke
			(width 0.508)
			(type default)
		)
		(layer "In4.Cu")
	)
	(gr_line
		(start 58.600086 0)
		(end 78.799944 0)
		(stroke
			(width 4.064)
			(type default)
		)
		(layer "In4.Cu")
	)
	(gr_line
		(start 58.6359 -85.2932)
		(end 58.6359 -83.10626)
		(stroke
			(width 0.508)
			(type default)
		)
		(layer "In4.Cu")
	)
	(gr_line
		(start 58.6359 -83.10626)
		(end 47.86376 -72.33412)
		(stroke
			(width 0.508)
			(type default)
		)
		(layer "In4.Cu")
	)
	(gr_line
		(start 58.6359 -83.10626)
		(end 59.6519 -84.12226)
		(stroke
			(width 0.508)
			(type default)
		)
		(layer "In4.Cu")
	)
	(gr_line
		(start 58.928 -84.48675)
		(end 59.944 -83.47075)
		(stroke
			(width 1.016)
			(type default)
		)
		(layer "In4.Cu")
	)
	(gr_line
		(start 60.03925 -83.34375)
		(end 59.08675 -84.29625)
		(stroke
			(width 1.016)
			(type default)
		)
		(layer "In4.Cu")
	)
	(gr_line
		(start 63.19774 -83.10626)
		(end 58.6359 -83.10626)
		(stroke
			(width 0.508)
			(type default)
		)
		(layer "In4.Cu")
	)
	(gr_line
		(start 72.263 -90.805)
		(end 72.263 -87.376)
		(stroke
			(width 0.508)
			(type default)
		)
		(layer "In4.Cu")
	)
	(gr_line
		(start 72.263 -87.376)
		(end 83.185 -76.454)
		(stroke
			(width 0.508)
			(type default)
		)
		(layer "In4.Cu")
	)
	(gr_line
		(start 72.263 -19.558)
		(end 83.947 -31.242)
		(stroke
			(width 0.508)
			(type default)
		)
		(layer "In4.Cu")
	)
	(gr_line
		(start 73.025 -73.279)
		(end 63.19774 -83.10626)
		(stroke
			(width 0.508)
			(type default)
		)
		(layer "In4.Cu")
	)
	(gr_line
		(start 74.168 -92.71)
		(end 72.263 -90.805)
		(stroke
			(width 0.508)
			(type default)
		)
		(layer "In4.Cu")
	)
	(gr_line
		(start 78.799944 0)
		(end 79.30007 -0.500126)
		(stroke
			(width 4.064)
			(type default)
		)
		(layer "In4.Cu")
	)
	(gr_line
		(start 79.001112 0.512826)
		(end 79.8068 -0.292862)
		(stroke
			(width 0.2)
			(type default)
		)
		(layer "In4.Cu")
	)
	(gr_arc
		(start 79.30007 -11.75004)
		(mid 79.592963 -12.457145)
		(end 80.300068 -12.750038)
		(stroke
			(width 4.064)
			(type default)
		)
		(layer "In4.Cu")
	)
	(gr_line
		(start 79.30007 -0.500126)
		(end 79.30007 -11.75004)
		(stroke
			(width 4.064)
			(type default)
		)
		(layer "In4.Cu")
	)
	(gr_line
		(start 79.8068 -6.103874)
		(end 44.5008 -6.103874)
		(stroke
			(width 0.2)
			(type default)
		)
		(layer "In4.Cu")
	)
	(gr_line
		(start 79.8068 -0.292862)
		(end 79.8068 -6.103874)
		(stroke
			(width 0.2)
			(type default)
		)
		(layer "In4.Cu")
	)
	(gr_line
		(start 80.300068 -12.750038)
		(end 166.649908 -12.750038)
		(stroke
			(width 4.064)
			(type default)
		)
		(layer "In4.Cu")
	)
	(gr_line
		(start 82.296 -73.279)
		(end 73.025 -73.279)
		(stroke
			(width 0.508)
			(type default)
		)
		(layer "In4.Cu")
	)
	(gr_line
		(start 82.296 -32.893)
		(end 82.296 -73.279)
		(stroke
			(width 0.508)
			(type default)
		)
		(layer "In4.Cu")
	)
	(gr_line
		(start 83.185 -76.454)
		(end 83.185 -74.168)
		(stroke
			(width 0.508)
			(type default)
		)
		(layer "In4.Cu")
	)
	(gr_line
		(start 83.185 -74.168)
		(end 82.296 -73.279)
		(stroke
			(width 0.508)
			(type default)
		)
		(layer "In4.Cu")
	)
	(gr_line
		(start 83.947 -31.242)
		(end 82.296 -32.893)
		(stroke
			(width 0.508)
			(type default)
		)
		(layer "In4.Cu")
	)
	(gr_line
		(start 88.011 -39.37)
		(end 88.011 -37.084)
		(stroke
			(width 0.508)
			(type default)
		)
		(layer "In4.Cu")
	)
	(gr_line
		(start 88.011 -37.084)
		(end 88.519 -36.576)
		(stroke
			(width 0.508)
			(type default)
		)
		(layer "In4.Cu")
	)
	(gr_line
		(start 88.519 -36.576)
		(end 90.424 -36.576)
		(stroke
			(width 0.508)
			(type default)
		)
		(layer "In4.Cu")
	)
	(gr_line
		(start 89.027 -40.386)
		(end 88.011 -39.37)
		(stroke
			(width 0.508)
			(type default)
		)
		(layer "In4.Cu")
	)
	(gr_line
		(start 90.424 -36.576)
		(end 90.932 -36.068)
		(stroke
			(width 0.508)
			(type default)
		)
		(layer "In4.Cu")
	)
	(gr_line
		(start 90.932 -36.068)
		(end 90.932 -31.242)
		(stroke
			(width 0.508)
			(type default)
		)
		(layer "In4.Cu")
	)
	(gr_line
		(start 90.932 -31.242)
		(end 83.947 -31.242)
		(stroke
			(width 0.508)
			(type default)
		)
		(layer "In4.Cu")
	)
	(gr_line
		(start 90.932 -31.242)
		(end 92.075 -30.099)
		(stroke
			(width 0.508)
			(type default)
		)
		(layer "In4.Cu")
	)
	(gr_line
		(start 92.075 -30.099)
		(end 92.71 -30.099)
		(stroke
			(width 0.508)
			(type default)
		)
		(layer "In4.Cu")
	)
	(gr_line
		(start 92.837 -40.386)
		(end 89.027 -40.386)
		(stroke
			(width 0.508)
			(type default)
		)
		(layer "In4.Cu")
	)
	(gr_line
		(start 92.964 -42.799)
		(end 94.107 -43.942)
		(stroke
			(width 0.508)
			(type default)
		)
		(layer "In4.Cu")
	)
	(gr_line
		(start 92.964 -38.735)
		(end 92.964 -42.799)
		(stroke
			(width 0.508)
			(type default)
		)
		(layer "In4.Cu")
	)
	(gr_line
		(start 94.107 -43.942)
		(end 95.758 -43.942)
		(stroke
			(width 0.508)
			(type default)
		)
		(layer "In4.Cu")
	)
	(gr_line
		(start 94.107 -37.592)
		(end 92.964 -38.735)
		(stroke
			(width 0.508)
			(type default)
		)
		(layer "In4.Cu")
	)
	(gr_line
		(start 95.25 -37.592)
		(end 94.107 -37.592)
		(stroke
			(width 0.508)
			(type default)
		)
		(layer "In4.Cu")
	)
	(gr_line
		(start 95.25 -37.592)
		(end 103.759 -37.592)
		(stroke
			(width 0.508)
			(type default)
		)
		(layer "In4.Cu")
	)
	(gr_line
		(start 95.758 -67.437)
		(end 97.79 -69.469)
		(stroke
			(width 0.508)
			(type default)
		)
		(layer "In4.Cu")
	)
	(gr_line
		(start 95.758 -43.942)
		(end 95.758 -67.437)
		(stroke
			(width 0.508)
			(type default)
		)
		(layer "In4.Cu")
	)
	(gr_line
		(start 96.139 -74.168)
		(end 83.185 -74.168)
		(stroke
			(width 0.508)
			(type default)
		)
		(layer "In4.Cu")
	)
	(gr_line
		(start 97.79 -72.517)
		(end 96.139 -74.168)
		(stroke
			(width 0.508)
			(type default)
		)
		(layer "In4.Cu")
	)
	(gr_line
		(start 97.79 -72.517)
		(end 101.092 -75.819)
		(stroke
			(width 0.508)
			(type default)
		)
		(layer "In4.Cu")
	)
	(gr_line
		(start 97.79 -69.469)
		(end 97.79 -72.517)
		(stroke
			(width 0.508)
			(type default)
		)
		(layer "In4.Cu")
	)
	(gr_line
		(start 101.092 -75.819)
		(end 108.204 -75.819)
		(stroke
			(width 0.508)
			(type default)
		)
		(layer "In4.Cu")
	)
	(gr_line
		(start 103.759 -43.942)
		(end 95.758 -43.942)
		(stroke
			(width 0.508)
			(type default)
		)
		(layer "In4.Cu")
	)
	(gr_line
		(start 103.759 -37.592)
		(end 104.775 -38.608)
		(stroke
			(width 0.508)
			(type default)
		)
		(layer "In4.Cu")
	)
	(gr_line
		(start 104.775 -42.926)
		(end 103.759 -43.942)
		(stroke
			(width 0.508)
			(type default)
		)
		(layer "In4.Cu")
	)
	(gr_line
		(start 104.775 -42.926)
		(end 106.045 -44.196)
		(stroke
			(width 0.508)
			(type default)
		)
		(layer "In4.Cu")
	)
	(gr_line
		(start 104.775 -38.608)
		(end 104.775 -42.926)
		(stroke
			(width 0.508)
			(type default)
		)
		(layer "In4.Cu")
	)
	(gr_line
		(start 106.045 -44.196)
		(end 130.556 -44.196)
		(stroke
			(width 0.508)
			(type default)
		)
		(layer "In4.Cu")
	)
	(gr_line
		(start 106.426 -36.957)
		(end 104.775 -38.608)
		(stroke
			(width 0.508)
			(type default)
		)
		(layer "In4.Cu")
	)
	(gr_line
		(start 108.204 -75.819)
		(end 109.22 -74.803)
		(stroke
			(width 0.508)
			(type default)
		)
		(layer "In4.Cu")
	)
	(gr_line
		(start 109.22 -74.803)
		(end 109.22 -70.231)
		(stroke
			(width 0.508)
			(type default)
		)
		(layer "In4.Cu")
	)
	(gr_line
		(start 109.22 -70.231)
		(end 110.744 -68.707)
		(stroke
			(width 0.508)
			(type default)
		)
		(layer "In4.Cu")
	)
	(gr_line
		(start 110.744 -68.707)
		(end 119.888 -68.707)
		(stroke
			(width 0.508)
			(type default)
		)
		(layer "In4.Cu")
	)
	(gr_line
		(start 119.888 -68.707)
		(end 122.174 -66.421)
		(stroke
			(width 0.508)
			(type default)
		)
		(layer "In4.Cu")
	)
	(gr_line
		(start 122.174 -66.421)
		(end 122.174 -54.991)
		(stroke
			(width 0.508)
			(type default)
		)
		(layer "In4.Cu")
	)
	(gr_line
		(start 122.174 -55.372)
		(end 122.174 -44.196)
		(stroke
			(width 0.508)
			(type default)
		)
		(layer "In4.Cu")
	)
	(gr_line
		(start 126.365 -107.315)
		(end 130.175 -103.505)
		(stroke
			(width 1.016)
			(type default)
		)
		(layer "In4.Cu")
	)
	(gr_line
		(start 130.175 -103.505)
		(end 147.0787 -103.505)
		(stroke
			(width 1.016)
			(type default)
		)
		(layer "In4.Cu")
	)
	(gr_line
		(start 130.556 -44.196)
		(end 131.572 -43.18)
		(stroke
			(width 0.508)
			(type default)
		)
		(layer "In4.Cu")
	)
	(gr_line
		(start 130.556 -44.196)
		(end 131.826 -45.466)
		(stroke
			(width 0.508)
			(type default)
		)
		(layer "In4.Cu")
	)
	(gr_line
		(start 131.064 -36.957)
		(end 106.426 -36.957)
		(stroke
			(width 0.508)
			(type default)
		)
		(layer "In4.Cu")
	)
	(gr_line
		(start 131.572 -43.18)
		(end 131.572 -37.465)
		(stroke
			(width 0.508)
			(type default)
		)
		(layer "In4.Cu")
	)
	(gr_line
		(start 131.572 -37.465)
		(end 131.064 -36.957)
		(stroke
			(width 0.508)
			(type default)
		)
		(layer "In4.Cu")
	)
	(gr_line
		(start 131.826 -45.466)
		(end 137.922 -45.466)
		(stroke
			(width 0.508)
			(type default)
		)
		(layer "In4.Cu")
	)
	(gr_line
		(start 132.08 -95.885)
		(end 48.514 -95.885)
		(stroke
			(width 1.016)
			(type default)
		)
		(layer "In4.Cu")
	)
	(gr_line
		(start 132.969 -30.099)
		(end 92.71 -30.099)
		(stroke
			(width 0.508)
			(type default)
		)
		(layer "In4.Cu")
	)
	(gr_line
		(start 133.35 -92.74175)
		(end 134.366 -91.72575)
		(stroke
			(width 1.016)
			(type default)
		)
		(layer "In4.Cu")
	)
	(gr_line
		(start 134.239 -92.71)
		(end 74.168 -92.71)
		(stroke
			(width 0.508)
			(type default)
		)
		(layer "In4.Cu")
	)
	(gr_line
		(start 134.3025 -93.69425)
		(end 133.35 -92.74175)
		(stroke
			(width 1.016)
			(type default)
		)
		(layer "In4.Cu")
	)
	(gr_line
		(start 134.493 -93.472)
		(end 132.08 -95.885)
		(stroke
			(width 1.016)
			(type default)
		)
		(layer "In4.Cu")
	)
	(gr_line
		(start 134.493 -58.801)
		(end 134.493 -93.472)
		(stroke
			(width 1.016)
			(type default)
		)
		(layer "In4.Cu")
	)
	(gr_line
		(start 134.62 -92.329)
		(end 134.239 -92.71)
		(stroke
			(width 0.508)
			(type default)
		)
		(layer "In4.Cu")
	)
	(gr_line
		(start 135.509 -57.785)
		(end 134.493 -58.801)
		(stroke
			(width 1.016)
			(type default)
		)
		(layer "In4.Cu")
	)
	(gr_line
		(start 137.922 -45.466)
		(end 140.081 -43.307)
		(stroke
			(width 0.508)
			(type default)
		)
		(layer "In4.Cu")
	)
	(gr_line
		(start 138.938 -30.099)
		(end 132.969 -30.099)
		(stroke
			(width 0.508)
			(type default)
		)
		(layer "In4.Cu")
	)
	(gr_line
		(start 140.081 -43.307)
		(end 140.081 -37.211)
		(stroke
			(width 0.508)
			(type default)
		)
		(layer "In4.Cu")
	)
	(gr_line
		(start 140.081 -37.211)
		(end 140.081 -31.242)
		(stroke
			(width 0.508)
			(type default)
		)
		(layer "In4.Cu")
	)
	(gr_line
		(start 140.081 -31.242)
		(end 138.938 -30.099)
		(stroke
			(width 0.508)
			(type default)
		)
		(layer "In4.Cu")
	)
	(gr_line
		(start 145.034 -57.785)
		(end 135.509 -57.785)
		(stroke
			(width 1.016)
			(type default)
		)
		(layer "In4.Cu")
	)
	(gr_line
		(start 147.066 -78.359)
		(end 147.066 -59.817)
		(stroke
			(width 1.016)
			(type default)
		)
		(layer "In4.Cu")
	)
	(gr_line
		(start 147.066 -59.817)
		(end 145.034 -57.785)
		(stroke
			(width 1.016)
			(type default)
		)
		(layer "In4.Cu")
	)
	(gr_line
		(start 147.0787 -103.505)
		(end 149.01418 -101.56952)
		(stroke
			(width 1.016)
			(type default)
		)
		(layer "In4.Cu")
	)
	(gr_line
		(start 147.32 -93.726)
		(end 147.32 -83.312)
		(stroke
			(width 1.016)
			(type default)
		)
		(layer "In4.Cu")
	)
	(gr_line
		(start 147.32 -83.312)
		(end 149.606 -81.026)
		(stroke
			(width 1.016)
			(type default)
		)
		(layer "In4.Cu")
	)
	(gr_line
		(start 148.336 -54.483)
		(end 145.034 -57.785)
		(stroke
			(width 0.508)
			(type default)
		)
		(layer "In4.Cu")
	)
	(gr_line
		(start 148.336 -27.051)
		(end 148.336 -54.483)
		(stroke
			(width 0.508)
			(type default)
		)
		(layer "In4.Cu")
	)
	(gr_line
		(start 148.336 -27.051)
		(end 148.336 -11.049)
		(stroke
			(width 0.508)
			(type default)
		)
		(layer "In4.Cu")
	)
	(gr_line
		(start 148.336 -11.049)
		(end 148.463 -10.922)
		(stroke
			(width 0.508)
			(type default)
		)
		(layer "In4.Cu")
	)
	(gr_line
		(start 149.01418 -101.56952)
		(end 149.01418 -95.42018)
		(stroke
			(width 1.016)
			(type default)
		)
		(layer "In4.Cu")
	)
	(gr_line
		(start 149.01418 -95.42018)
		(end 147.32 -93.726)
		(stroke
			(width 1.016)
			(type default)
		)
		(layer "In4.Cu")
	)
	(gr_line
		(start 149.606 -81.026)
		(end 149.733 -81.026)
		(stroke
			(width 1.016)
			(type default)
		)
		(layer "In4.Cu")
	)
	(gr_line
		(start 149.733 -81.026)
		(end 147.066 -78.359)
		(stroke
			(width 1.016)
			(type default)
		)
		(layer "In4.Cu")
	)
	(gr_line
		(start 152.93975 -109.7915)
		(end 153.89225 -108.839)
		(stroke
			(width 1.016)
			(type default)
		)
		(layer "In4.Cu")
	)
	(gr_line
		(start 153.67 -81.026)
		(end 149.733 -81.026)
		(stroke
			(width 1.016)
			(type default)
		)
		(layer "In4.Cu")
	)
	(gr_line
		(start 153.89225 -108.839)
		(end 154.90825 -109.855)
		(stroke
			(width 1.016)
			(type default)
		)
		(layer "In4.Cu")
	)
	(gr_line
		(start 153.924 -114.681)
		(end 153.924 -99.314)
		(stroke
			(width 1.016)
			(type default)
		)
		(layer "In4.Cu")
	)
	(gr_line
		(start 153.924 -99.314)
		(end 155.829 -97.409)
		(stroke
			(width 1.016)
			(type default)
		)
		(layer "In4.Cu")
	)
	(gr_line
		(start 154.686 -115.443)
		(end 153.924 -114.681)
		(stroke
			(width 1.016)
			(type default)
		)
		(layer "In4.Cu")
	)
	(gr_line
		(start 155.829 -97.409)
		(end 155.829 -83.185)
		(stroke
			(width 1.016)
			(type default)
		)
		(layer "In4.Cu")
	)
	(gr_line
		(start 155.829 -83.185)
		(end 153.67 -81.026)
		(stroke
			(width 1.016)
			(type default)
		)
		(layer "In4.Cu")
	)
	(gr_line
		(start 163.56584 -110.26902)
		(end 163.56584 -106.66476)
		(stroke
			(width 0.2)
			(type default)
		)
		(layer "In4.Cu")
	)
	(gr_line
		(start 163.56584 -106.66476)
		(end 166.51732 -106.66476)
		(stroke
			(width 0.2)
			(type default)
		)
		(layer "In4.Cu")
	)
	(gr_arc
		(start 166.431722 -71.799958)
		(mid 166.578026 -72.153675)
		(end 166.931594 -72.300084)
		(stroke
			(width 4.064)
			(type default)
		)
		(layer "In4.Cu")
	)
	(gr_line
		(start 166.431722 -61.324998)
		(end 166.431722 -71.799958)
		(stroke
			(width 4.064)
			(type default)
		)
		(layer "In4.Cu")
	)
	(gr_line
		(start 166.51732 -110.26902)
		(end 163.56584 -110.26902)
		(stroke
			(width 0.2)
			(type default)
		)
		(layer "In4.Cu")
	)
	(gr_line
		(start 166.51732 -106.66476)
		(end 166.51732 -110.26902)
		(stroke
			(width 0.2)
			(type default)
		)
		(layer "In4.Cu")
	)
	(gr_line
		(start 166.649908 -111.149892)
		(end 0.999998 -111.149892)
		(stroke
			(width 4.064)
			(type default)
		)
		(layer "In4.Cu")
	)
	(gr_arc
		(start 166.649908 -111.149892)
		(mid 167.357006 -110.856996)
		(end 167.649906 -110.149894)
		(stroke
			(width 4.064)
			(type default)
		)
		(layer "In4.Cu")
	)
	(gr_line
		(start 166.931594 -72.300084)
		(end 167.150034 -72.300084)
		(stroke
			(width 4.064)
			(type default)
		)
		(layer "In4.Cu")
	)
	(gr_arc
		(start 166.931594 -60.825126)
		(mid 166.578131 -60.971535)
		(end 166.431722 -61.324998)
		(stroke
			(width 4.064)
			(type default)
		)
		(layer "In4.Cu")
	)
	(gr_line
		(start 167.150034 -60.825126)
		(end 166.931594 -60.825126)
		(stroke
			(width 4.064)
			(type default)
		)
		(layer "In4.Cu")
	)
	(gr_arc
		(start 167.150034 -60.825126)
		(mid 167.503548 -60.678612)
		(end 167.649906 -60.325)
		(stroke
			(width 4.064)
			(type default)
		)
		(layer "In4.Cu")
	)
	(gr_arc
		(start 167.649906 -72.799956)
		(mid 167.503483 -72.44651)
		(end 167.150034 -72.300084)
		(stroke
			(width 4.064)
			(type default)
		)
		(layer "In4.Cu")
	)
	(gr_line
		(start 167.649906 -72.799956)
		(end 167.649906 -110.149894)
		(stroke
			(width 4.064)
			(type default)
		)
		(layer "In4.Cu")
	)
	(gr_arc
		(start 167.649906 -13.750036)
		(mid 167.357027 -13.042905)
		(end 166.649908 -12.750038)
		(stroke
			(width 4.064)
			(type default)
		)
		(layer "In4.Cu")
	)
	(gr_line
		(start 167.649906 -13.750036)
		(end 167.649906 -60.325)
		(stroke
			(width 4.064)
			(type default)
		)
		(layer "In4.Cu")
	)
	(gr_line
		(start 0 -110.149894)
		(end 0 -5.500116)
		(stroke
			(width 4.064)
			(type default)
		)
		(layer "In5.Cu")
	)
	(gr_arc
		(start 0 -110.149894)
		(mid 0.292894 -110.856997)
		(end 0.999998 -111.149892)
		(stroke
			(width 4.064)
			(type default)
		)
		(layer "In5.Cu")
	)
	(gr_arc
		(start 0.762 -110.149894)
		(mid 0.831708 -110.318184)
		(end 0.999998 -110.387892)
		(stroke
			(width 1.27)
			(type default)
		)
		(layer "In5.Cu")
	)
	(gr_arc
		(start 0.999998 -4.500118)
		(mid 0.292893 -4.793011)
		(end 0 -5.500116)
		(stroke
			(width 4.064)
			(type default)
		)
		(layer "In5.Cu")
	)
	(gr_line
		(start 0.999998 -4.500118)
		(end 13.999972 -4.500118)
		(stroke
			(width 4.064)
			(type default)
		)
		(layer "In5.Cu")
	)
	(gr_line
		(start 12.8778 -109.69498)
		(end 13.8303 -108.74248)
		(stroke
			(width 1.016)
			(type default)
		)
		(layer "In5.Cu")
	)
	(gr_line
		(start 13.8303 -108.74248)
		(end 14.8463 -109.75848)
		(stroke
			(width 1.016)
			(type default)
		)
		(layer "In5.Cu")
	)
	(gr_line
		(start 13.843 -98.425)
		(end 13.843 -114.3)
		(stroke
			(width 1.016)
			(type default)
		)
		(layer "In5.Cu")
	)
	(gr_line
		(start 14.732 -97.536)
		(end 13.843 -98.425)
		(stroke
			(width 1.016)
			(type default)
		)
		(layer "In5.Cu")
	)
	(gr_line
		(start 14.732 -97.536)
		(end 15.367 -98.171)
		(stroke
			(width 1.016)
			(type default)
		)
		(layer "In5.Cu")
	)
	(gr_line
		(start 14.732 -56.642)
		(end 14.732 -97.536)
		(stroke
			(width 1.016)
			(type default)
		)
		(layer "In5.Cu")
	)
	(gr_arc
		(start 14.99997 -11.75004)
		(mid 15.292863 -12.457145)
		(end 15.999968 -12.750038)
		(stroke
			(width 4.064)
			(type default)
		)
		(layer "In5.Cu")
	)
	(gr_arc
		(start 14.99997 -5.500116)
		(mid 14.707081 -4.79301)
		(end 13.999972 -4.500118)
		(stroke
			(width 4.064)
			(type default)
		)
		(layer "In5.Cu")
	)
	(gr_line
		(start 14.99997 -5.500116)
		(end 14.99997 -11.75004)
		(stroke
			(width 4.064)
			(type default)
		)
		(layer "In5.Cu")
	)
	(gr_line
		(start 15.367 -98.171)
		(end 14.732 -97.536)
		(stroke
			(width 1.016)
			(type default)
		)
		(layer "In5.Cu")
	)
	(gr_line
		(start 15.367 -98.171)
		(end 18.923 -98.171)
		(stroke
			(width 1.016)
			(type default)
		)
		(layer "In5.Cu")
	)
	(gr_line
		(start 15.999968 -12.750038)
		(end 32.349948 -12.750038)
		(stroke
			(width 4.064)
			(type default)
		)
		(layer "In5.Cu")
	)
	(gr_line
		(start 18.923 -98.171)
		(end 19.812 -97.282)
		(stroke
			(width 1.016)
			(type default)
		)
		(layer "In5.Cu")
	)
	(gr_line
		(start 18.923 -98.171)
		(end 42.58818 -98.171)
		(stroke
			(width 1.016)
			(type default)
		)
		(layer "In5.Cu")
	)
	(gr_line
		(start 19.812 -97.282)
		(end 19.812 -92.202)
		(stroke
			(width 1.016)
			(type default)
		)
		(layer "In5.Cu")
	)
	(gr_line
		(start 19.812 -92.202)
		(end 22.987 -89.027)
		(stroke
			(width 1.016)
			(type default)
		)
		(layer "In5.Cu")
	)
	(gr_line
		(start 22.987 -89.027)
		(end 22.987 -63.754)
		(stroke
			(width 1.016)
			(type default)
		)
		(layer "In5.Cu")
	)
	(gr_line
		(start 22.987 -63.754)
		(end 57.15 -29.591)
		(stroke
			(width 1.016)
			(type default)
		)
		(layer "In5.Cu")
	)
	(gr_line
		(start 24.511 -90.551)
		(end 22.987 -89.027)
		(stroke
			(width 1.016)
			(type default)
		)
		(layer "In5.Cu")
	)
	(gr_line
		(start 27.051 -59.817)
		(end 27.051 -59.69)
		(stroke
			(width 0.508)
			(type default)
		)
		(layer "In5.Cu")
	)
	(gr_line
		(start 27.051 -59.69)
		(end 28.194 -58.547)
		(stroke
			(width 0.508)
			(type default)
		)
		(layer "In5.Cu")
	)
	(gr_line
		(start 27.178 -59.944)
		(end 27.051 -59.817)
		(stroke
			(width 0.508)
			(type default)
		)
		(layer "In5.Cu")
	)
	(gr_line
		(start 27.559 -59.69)
		(end 27.559 -59.563)
		(stroke
			(width 0.508)
			(type default)
		)
		(layer "In5.Cu")
	)
	(gr_line
		(start 27.559 -59.563)
		(end 27.686 -59.436)
		(stroke
			(width 0.508)
			(type default)
		)
		(layer "In5.Cu")
	)
	(gr_line
		(start 27.686 -59.436)
		(end 28.067 -59.817)
		(stroke
			(width 0.508)
			(type default)
		)
		(layer "In5.Cu")
	)
	(gr_line
		(start 27.813 -59.944)
		(end 27.178 -59.944)
		(stroke
			(width 0.508)
			(type default)
		)
		(layer "In5.Cu")
	)
	(gr_line
		(start 27.94 -59.309)
		(end 27.559 -59.69)
		(stroke
			(width 0.508)
			(type default)
		)
		(layer "In5.Cu")
	)
	(gr_line
		(start 28.067 -60.198)
		(end 27.813 -59.944)
		(stroke
			(width 0.508)
			(type default)
		)
		(layer "In5.Cu")
	)
	(gr_line
		(start 28.067 -59.817)
		(end 28.067 -60.198)
		(stroke
			(width 0.508)
			(type default)
		)
		(layer "In5.Cu")
	)
	(gr_line
		(start 28.194 -69.215)
		(end 34.83864 -75.85964)
		(stroke
			(width 0.508)
			(type default)
		)
		(layer "In5.Cu")
	)
	(gr_line
		(start 28.194 -58.547)
		(end 28.194 -69.215)
		(stroke
			(width 0.508)
			(type default)
		)
		(layer "In5.Cu")
	)
	(gr_line
		(start 31.75 -90.551)
		(end 24.511 -90.551)
		(stroke
			(width 1.016)
			(type default)
		)
		(layer "In5.Cu")
	)
	(gr_arc
		(start 32.349948 -12.750038)
		(mid 33.057053 -12.457145)
		(end 33.349946 -11.75004)
		(stroke
			(width 4.064)
			(type default)
		)
		(layer "In5.Cu")
	)
	(gr_line
		(start 33.349946 -11.75004)
		(end 33.349946 -5.500116)
		(stroke
			(width 4.064)
			(type default)
		)
		(layer "In5.Cu")
	)
	(gr_line
		(start 34.163 -92.964)
		(end 31.75 -90.551)
		(stroke
			(width 1.016)
			(type default)
		)
		(layer "In5.Cu")
	)
	(gr_arc
		(start 34.349944 -4.500118)
		(mid 33.642816 -4.792996)
		(end 33.349946 -5.500116)
		(stroke
			(width 4.064)
			(type default)
		)
		(layer "In5.Cu")
	)
	(gr_line
		(start 34.349944 -4.500118)
		(end 40.349932 -4.500118)
		(stroke
			(width 4.064)
			(type default)
		)
		(layer "In5.Cu")
	)
	(gr_line
		(start 34.83864 -78.17612)
		(end 35.21202 -78.5495)
		(stroke
			(width 0.508)
			(type default)
		)
		(layer "In5.Cu")
	)
	(gr_line
		(start 34.83864 -75.85964)
		(end 34.83864 -78.17612)
		(stroke
			(width 0.508)
			(type default)
		)
		(layer "In5.Cu")
	)
	(gr_line
		(start 35.21202 -78.5495)
		(end 37.5285 -78.5495)
		(stroke
			(width 0.508)
			(type default)
		)
		(layer "In5.Cu")
	)
	(gr_line
		(start 37.1475 -115.5065)
		(end 38.1 -114.554)
		(stroke
			(width 1.016)
			(type default)
		)
		(layer "In5.Cu")
	)
	(gr_line
		(start 37.5285 -78.5495)
		(end 44.577 -85.598)
		(stroke
			(width 0.508)
			(type default)
		)
		(layer "In5.Cu")
	)
	(gr_line
		(start 38.1 -114.554)
		(end 39.116 -115.57)
		(stroke
			(width 1.016)
			(type default)
		)
		(layer "In5.Cu")
	)
	(gr_arc
		(start 41.34993 -10.925048)
		(mid 43.17492 -12.750038)
		(end 44.99991 -10.925048)
		(stroke
			(width 4.064)
			(type default)
		)
		(layer "In5.Cu")
	)
	(gr_arc
		(start 41.34993 -5.500116)
		(mid 41.057045 -4.792989)
		(end 40.349932 -4.500118)
		(stroke
			(width 4.064)
			(type default)
		)
		(layer "In5.Cu")
	)
	(gr_line
		(start 41.34993 -5.500116)
		(end 41.34993 -10.925048)
		(stroke
			(width 4.064)
			(type default)
		)
		(layer "In5.Cu")
	)
	(gr_line
		(start 42.58818 -98.171)
		(end 43.3451 -98.92792)
		(stroke
			(width 1.016)
			(type default)
		)
		(layer "In5.Cu")
	)
	(gr_line
		(start 42.672 -28.702)
		(end 14.732 -56.642)
		(stroke
			(width 1.016)
			(type default)
		)
		(layer "In5.Cu")
	)
	(gr_line
		(start 42.672 -5.715)
		(end 42.672 -28.702)
		(stroke
			(width 1.016)
			(type default)
		)
		(layer "In5.Cu")
	)
	(gr_line
		(start 43.3451 -98.92792)
		(end 80.82788 -98.92792)
		(stroke
			(width 1.016)
			(type default)
		)
		(layer "In5.Cu")
	)
	(gr_line
		(start 44.5008 -6.103874)
		(end 44.5008 -0.292862)
		(stroke
			(width 0.2)
			(type default)
		)
		(layer "In5.Cu")
	)
	(gr_line
		(start 44.5008 -0.292862)
		(end 45.306488 0.512826)
		(stroke
			(width 0.2)
			(type default)
		)
		(layer "In5.Cu")
	)
	(gr_line
		(start 44.577 -85.598)
		(end 79.121 -85.598)
		(stroke
			(width 0.508)
			(type default)
		)
		(layer "In5.Cu")
	)
	(gr_line
		(start 44.99991 -10.925048)
		(end 44.99991 -0.500126)
		(stroke
			(width 4.064)
			(type default)
		)
		(layer "In5.Cu")
	)
	(gr_line
		(start 44.99991 -0.500126)
		(end 45.500036 0)
		(stroke
			(width 4.064)
			(type default)
		)
		(layer "In5.Cu")
	)
	(gr_line
		(start 45.306488 0.512826)
		(end 79.001112 0.512826)
		(stroke
			(width 0.2)
			(type default)
		)
		(layer "In5.Cu")
	)
	(gr_line
		(start 45.500036 0)
		(end 55.699914 0)
		(stroke
			(width 4.064)
			(type default)
		)
		(layer "In5.Cu")
	)
	(gr_line
		(start 45.593 -92.964)
		(end 34.163 -92.964)
		(stroke
			(width 1.016)
			(type default)
		)
		(layer "In5.Cu")
	)
	(gr_line
		(start 48.514 -95.885)
		(end 45.593 -92.964)
		(stroke
			(width 1.016)
			(type default)
		)
		(layer "In5.Cu")
	)
	(gr_line
		(start 55.699914 0)
		(end 56.20004 -0.500126)
		(stroke
			(width 4.064)
			(type default)
		)
		(layer "In5.Cu")
	)
	(gr_arc
		(start 56.20004 -7.450074)
		(mid 57.15 -8.400034)
		(end 58.09996 -7.450074)
		(stroke
			(width 4.064)
			(type default)
		)
		(layer "In5.Cu")
	)
	(gr_line
		(start 56.20004 -0.500126)
		(end 56.20004 -7.450074)
		(stroke
			(width 4.064)
			(type default)
		)
		(layer "In5.Cu")
	)
	(gr_line
		(start 57.15 -29.591)
		(end 57.15 -7.239)
		(stroke
			(width 1.016)
			(type default)
		)
		(layer "In5.Cu")
	)
	(gr_line
		(start 58.09996 -7.450074)
		(end 58.09996 -0.500126)
		(stroke
			(width 4.064)
			(type default)
		)
		(layer "In5.Cu")
	)
	(gr_line
		(start 58.09996 -0.500126)
		(end 58.600086 0)
		(stroke
			(width 4.064)
			(type default)
		)
		(layer "In5.Cu")
	)
	(gr_line
		(start 58.600086 0)
		(end 78.799944 0)
		(stroke
			(width 4.064)
			(type default)
		)
		(layer "In5.Cu")
	)
	(gr_line
		(start 78.799944 0)
		(end 79.30007 -0.500126)
		(stroke
			(width 4.064)
			(type default)
		)
		(layer "In5.Cu")
	)
	(gr_line
		(start 79.001112 0.512826)
		(end 79.8068 -0.292862)
		(stroke
			(width 0.2)
			(type default)
		)
		(layer "In5.Cu")
	)
	(gr_line
		(start 79.121 -85.598)
		(end 91.44 -73.279)
		(stroke
			(width 0.508)
			(type default)
		)
		(layer "In5.Cu")
	)
	(gr_arc
		(start 79.30007 -11.75004)
		(mid 79.592963 -12.457145)
		(end 80.300068 -12.750038)
		(stroke
			(width 4.064)
			(type default)
		)
		(layer "In5.Cu")
	)
	(gr_line
		(start 79.30007 -0.500126)
		(end 79.30007 -11.75004)
		(stroke
			(width 4.064)
			(type default)
		)
		(layer "In5.Cu")
	)
	(gr_line
		(start 79.8068 -6.103874)
		(end 44.5008 -6.103874)
		(stroke
			(width 0.2)
			(type default)
		)
		(layer "In5.Cu")
	)
	(gr_line
		(start 79.8068 -0.292862)
		(end 79.8068 -6.103874)
		(stroke
			(width 0.2)
			(type default)
		)
		(layer "In5.Cu")
	)
	(gr_line
		(start 80.300068 -12.750038)
		(end 166.649908 -12.750038)
		(stroke
			(width 4.064)
			(type default)
		)
		(layer "In5.Cu")
	)
	(gr_line
		(start 80.82788 -98.92792)
		(end 81.84642 -99.94646)
		(stroke
			(width 1.016)
			(type default)
		)
		(layer "In5.Cu")
	)
	(gr_line
		(start 81.84642 -99.94646)
		(end 117.09654 -99.94646)
		(stroke
			(width 1.016)
			(type default)
		)
		(layer "In5.Cu")
	)
	(gr_line
		(start 89.281 -64.008)
		(end 91.44 -66.167)
		(stroke
			(width 0.508)
			(type default)
		)
		(layer "In5.Cu")
	)
	(gr_line
		(start 89.281 -59.69)
		(end 89.281 -64.008)
		(stroke
			(width 0.508)
			(type default)
		)
		(layer "In5.Cu")
	)
	(gr_line
		(start 89.281 -55.372)
		(end 89.281 -59.69)
		(stroke
			(width 0.508)
			(type default)
		)
		(layer "In5.Cu")
	)
	(gr_line
		(start 90.043 -54.61)
		(end 89.281 -55.372)
		(stroke
			(width 0.508)
			(type default)
		)
		(layer "In5.Cu")
	)
	(gr_line
		(start 91.44 -73.279)
		(end 91.44 -66.929)
		(stroke
			(width 0.508)
			(type default)
		)
		(layer "In5.Cu")
	)
	(gr_line
		(start 91.44 -66.167)
		(end 91.44 -67.183)
		(stroke
			(width 0.508)
			(type default)
		)
		(layer "In5.Cu")
	)
	(gr_line
		(start 91.948 -44.069)
		(end 91.948 -35.687)
		(stroke
			(width 0.508)
			(type default)
		)
		(layer "In5.Cu")
	)
	(gr_line
		(start 91.948 -35.687)
		(end 92.71 -34.925)
		(stroke
			(width 0.508)
			(type default)
		)
		(layer "In5.Cu")
	)
	(gr_line
		(start 92.329 -35.306)
		(end 92.71 -34.925)
		(stroke
			(width 0.508)
			(type default)
		)
		(layer "In5.Cu")
	)
	(gr_line
		(start 92.71 -44.831)
		(end 91.948 -44.069)
		(stroke
			(width 0.508)
			(type default)
		)
		(layer "In5.Cu")
	)
	(gr_line
		(start 92.71 -34.925)
		(end 92.71 -19.812)
		(stroke
			(width 0.508)
			(type default)
		)
		(layer "In5.Cu")
	)
	(gr_line
		(start 92.71 -34.925)
		(end 99.822 -34.925)
		(stroke
			(width 0.508)
			(type default)
		)
		(layer "In5.Cu")
	)
	(gr_line
		(start 92.71 -19.812)
		(end 94.361 -18.161)
		(stroke
			(width 0.508)
			(type default)
		)
		(layer "In5.Cu")
	)
	(gr_line
		(start 94.234 -54.61)
		(end 90.043 -54.61)
		(stroke
			(width 0.508)
			(type default)
		)
		(layer "In5.Cu")
	)
	(gr_line
		(start 94.361 -58.166)
		(end 94.742 -58.547)
		(stroke
			(width 0.508)
			(type default)
		)
		(layer "In5.Cu")
	)
	(gr_line
		(start 94.361 -56.134)
		(end 94.361 -58.166)
		(stroke
			(width 0.508)
			(type default)
		)
		(layer "In5.Cu")
	)
	(gr_line
		(start 94.361 -56.134)
		(end 94.361 -44.831)
		(stroke
			(width 0.508)
			(type default)
		)
		(layer "In5.Cu")
	)
	(gr_line
		(start 94.361 -18.161)
		(end 139.954 -18.161)
		(stroke
			(width 0.508)
			(type default)
		)
		(layer "In5.Cu")
	)
	(gr_line
		(start 94.742 -58.547)
		(end 99.06 -58.547)
		(stroke
			(width 0.508)
			(type default)
		)
		(layer "In5.Cu")
	)
	(gr_line
		(start 99.06 -58.547)
		(end 100.076 -57.531)
		(stroke
			(width 0.508)
			(type default)
		)
		(layer "In5.Cu")
	)
	(gr_line
		(start 99.822 -34.925)
		(end 100.584 -35.687)
		(stroke
			(width 0.508)
			(type default)
		)
		(layer "In5.Cu")
	)
	(gr_line
		(start 100.076 -57.531)
		(end 100.076 -53.975)
		(stroke
			(width 0.508)
			(type default)
		)
		(layer "In5.Cu")
	)
	(gr_line
		(start 100.457 -44.831)
		(end 92.71 -44.831)
		(stroke
			(width 0.508)
			(type default)
		)
		(layer "In5.Cu")
	)
	(gr_line
		(start 100.965 -44.323)
		(end 100.457 -44.831)
		(stroke
			(width 0.508)
			(type default)
		)
		(layer "In5.Cu")
	)
	(gr_line
		(start 100.965 -43.942)
		(end 100.965 -44.323)
		(stroke
			(width 0.508)
			(type default)
		)
		(layer "In5.Cu")
	)
	(gr_line
		(start 100.965 -43.942)
		(end 100.965 -36.068)
		(stroke
			(width 0.508)
			(type default)
		)
		(layer "In5.Cu")
	)
	(gr_line
		(start 100.965 -41.783)
		(end 112.776 -41.783)
		(stroke
			(width 0.508)
			(type default)
		)
		(layer "In5.Cu")
	)
	(gr_line
		(start 100.965 -36.068)
		(end 100.584 -35.687)
		(stroke
			(width 0.508)
			(type default)
		)
		(layer "In5.Cu")
	)
	(gr_line
		(start 103.505 -75.184)
		(end 103.505 -62.992)
		(stroke
			(width 0.508)
			(type default)
		)
		(layer "In5.Cu")
	)
	(gr_line
		(start 103.505 -62.992)
		(end 99.06 -58.547)
		(stroke
			(width 0.508)
			(type default)
		)
		(layer "In5.Cu")
	)
	(gr_line
		(start 105.791 -77.47)
		(end 103.505 -75.184)
		(stroke
			(width 0.508)
			(type default)
		)
		(layer "In5.Cu")
	)
	(gr_line
		(start 106.426 -47.625)
		(end 100.076 -53.975)
		(stroke
			(width 0.508)
			(type default)
		)
		(layer "In5.Cu")
	)
	(gr_line
		(start 112.395 -47.625)
		(end 106.426 -47.625)
		(stroke
			(width 0.508)
			(type default)
		)
		(layer "In5.Cu")
	)
	(gr_line
		(start 112.776 -41.783)
		(end 113.538 -41.783)
		(stroke
			(width 0.508)
			(type default)
		)
		(layer "In5.Cu")
	)
	(gr_line
		(start 113.538 -46.482)
		(end 112.395 -47.625)
		(stroke
			(width 0.508)
			(type default)
		)
		(layer "In5.Cu")
	)
	(gr_line
		(start 113.538 -44.323)
		(end 113.538 -46.482)
		(stroke
			(width 0.508)
			(type default)
		)
		(layer "In5.Cu")
	)
	(gr_line
		(start 113.538 -41.783)
		(end 124.968 -41.783)
		(stroke
			(width 0.508)
			(type default)
		)
		(layer "In5.Cu")
	)
	(gr_line
		(start 114.173 -43.688)
		(end 113.538 -44.323)
		(stroke
			(width 0.508)
			(type default)
		)
		(layer "In5.Cu")
	)
	(gr_line
		(start 114.173 -42.418)
		(end 114.173 -43.688)
		(stroke
			(width 0.508)
			(type default)
		)
		(layer "In5.Cu")
	)
	(gr_line
		(start 114.173 -42.418)
		(end 114.173 -41.783)
		(stroke
			(width 0.508)
			(type default)
		)
		(layer "In5.Cu")
	)
	(gr_line
		(start 117.09654 -99.94646)
		(end 118.491 -98.552)
		(stroke
			(width 1.016)
			(type default)
		)
		(layer "In5.Cu")
	)
	(gr_line
		(start 117.221 -77.47)
		(end 105.791 -77.47)
		(stroke
			(width 0.508)
			(type default)
		)
		(layer "In5.Cu")
	)
	(gr_line
		(start 118.491 -98.552)
		(end 134.62 -98.552)
		(stroke
			(width 1.016)
			(type default)
		)
		(layer "In5.Cu")
	)
	(gr_line
		(start 123.317 -71.374)
		(end 117.221 -77.47)
		(stroke
			(width 0.508)
			(type default)
		)
		(layer "In5.Cu")
	)
	(gr_line
		(start 123.317 -62.611)
		(end 123.317 -71.374)
		(stroke
			(width 0.508)
			(type default)
		)
		(layer "In5.Cu")
	)
	(gr_line
		(start 124.079 -61.849)
		(end 123.317 -62.611)
		(stroke
			(width 0.508)
			(type default)
		)
		(layer "In5.Cu")
	)
	(gr_line
		(start 124.968 -41.783)
		(end 141.097 -25.654)
		(stroke
			(width 0.508)
			(type default)
		)
		(layer "In5.Cu")
	)
	(gr_line
		(start 132.08 -95.885)
		(end 48.514 -95.885)
		(stroke
			(width 1.016)
			(type default)
		)
		(layer "In5.Cu")
	)
	(gr_line
		(start 134.366 -61.849)
		(end 124.079 -61.849)
		(stroke
			(width 0.508)
			(type default)
		)
		(layer "In5.Cu")
	)
	(gr_line
		(start 134.493 -93.472)
		(end 132.08 -95.885)
		(stroke
			(width 1.016)
			(type default)
		)
		(layer "In5.Cu")
	)
	(gr_line
		(start 134.493 -58.801)
		(end 134.493 -93.472)
		(stroke
			(width 1.016)
			(type default)
		)
		(layer "In5.Cu")
	)
	(gr_line
		(start 134.62 -98.552)
		(end 139.065 -94.107)
		(stroke
			(width 1.016)
			(type default)
		)
		(layer "In5.Cu")
	)
	(gr_line
		(start 135.509 -57.785)
		(end 134.493 -58.801)
		(stroke
			(width 1.016)
			(type default)
		)
		(layer "In5.Cu")
	)
	(gr_line
		(start 139.065 -94.107)
		(end 139.065 -81.407)
		(stroke
			(width 1.016)
			(type default)
		)
		(layer "In5.Cu")
	)
	(gr_line
		(start 139.065 -81.407)
		(end 140.208 -80.264)
		(stroke
			(width 1.016)
			(type default)
		)
		(layer "In5.Cu")
	)
	(gr_line
		(start 139.954 -18.161)
		(end 141.097 -19.304)
		(stroke
			(width 0.508)
			(type default)
		)
		(layer "In5.Cu")
	)
	(gr_line
		(start 140.208 -80.264)
		(end 143.256 -80.264)
		(stroke
			(width 1.016)
			(type default)
		)
		(layer "In5.Cu")
	)
	(gr_line
		(start 141.097 -25.654)
		(end 141.097 -24.638)
		(stroke
			(width 0.508)
			(type default)
		)
		(layer "In5.Cu")
	)
	(gr_line
		(start 141.097 -19.304)
		(end 141.097 -25.019)
		(stroke
			(width 0.508)
			(type default)
		)
		(layer "In5.Cu")
	)
	(gr_line
		(start 143.256 -80.264)
		(end 144.272 -81.28)
		(stroke
			(width 1.016)
			(type default)
		)
		(layer "In5.Cu")
	)
	(gr_line
		(start 144.272 -82.55)
		(end 147.32 -85.598)
		(stroke
			(width 1.016)
			(type default)
		)
		(layer "In5.Cu")
	)
	(gr_line
		(start 144.272 -81.28)
		(end 144.272 -82.55)
		(stroke
			(width 1.016)
			(type default)
		)
		(layer "In5.Cu")
	)
	(gr_line
		(start 145.034 -57.785)
		(end 135.509 -57.785)
		(stroke
			(width 1.016)
			(type default)
		)
		(layer "In5.Cu")
	)
	(gr_line
		(start 147.066 -78.359)
		(end 147.066 -59.817)
		(stroke
			(width 1.016)
			(type default)
		)
		(layer "In5.Cu")
	)
	(gr_line
		(start 147.066 -59.817)
		(end 145.034 -57.785)
		(stroke
			(width 1.016)
			(type default)
		)
		(layer "In5.Cu")
	)
	(gr_line
		(start 147.32 -94.996)
		(end 151.638 -99.314)
		(stroke
			(width 1.016)
			(type default)
		)
		(layer "In5.Cu")
	)
	(gr_line
		(start 147.32 -85.598)
		(end 147.32 -94.996)
		(stroke
			(width 1.016)
			(type default)
		)
		(layer "In5.Cu")
	)
	(gr_line
		(start 149.733 -81.026)
		(end 147.066 -78.359)
		(stroke
			(width 1.016)
			(type default)
		)
		(layer "In5.Cu")
	)
	(gr_line
		(start 151.638 -99.314)
		(end 153.924 -99.314)
		(stroke
			(width 1.016)
			(type default)
		)
		(layer "In5.Cu")
	)
	(gr_line
		(start 153.0096 -109.68736)
		(end 153.9621 -108.73486)
		(stroke
			(width 1.016)
			(type default)
		)
		(layer "In5.Cu")
	)
	(gr_line
		(start 153.67 -81.026)
		(end 149.733 -81.026)
		(stroke
			(width 1.016)
			(type default)
		)
		(layer "In5.Cu")
	)
	(gr_line
		(start 153.924 -114.427)
		(end 153.924 -99.314)
		(stroke
			(width 1.016)
			(type default)
		)
		(layer "In5.Cu")
	)
	(gr_line
		(start 153.924 -99.314)
		(end 155.829 -97.409)
		(stroke
			(width 1.016)
			(type default)
		)
		(layer "In5.Cu")
	)
	(gr_line
		(start 153.9621 -108.73486)
		(end 154.9781 -109.75086)
		(stroke
			(width 1.016)
			(type default)
		)
		(layer "In5.Cu")
	)
	(gr_line
		(start 155.829 -97.409)
		(end 155.829 -83.185)
		(stroke
			(width 1.016)
			(type default)
		)
		(layer "In5.Cu")
	)
	(gr_line
		(start 155.829 -83.185)
		(end 153.67 -81.026)
		(stroke
			(width 1.016)
			(type default)
		)
		(layer "In5.Cu")
	)
	(gr_rect
		(start 163.56584 -106.66476)
		(end 166.51732 -110.26902)
		(stroke
			(width 0)
			(type default)
		)
		(fill no)
		(layer "In5.Cu")
	)
	(gr_arc
		(start 166.431722 -71.799958)
		(mid 166.578026 -72.153675)
		(end 166.931594 -72.300084)
		(stroke
			(width 4.064)
			(type default)
		)
		(layer "In5.Cu")
	)
	(gr_line
		(start 166.431722 -61.324998)
		(end 166.431722 -71.799958)
		(stroke
			(width 4.064)
			(type default)
		)
		(layer "In5.Cu")
	)
	(gr_line
		(start 166.649908 -111.149892)
		(end 0.999998 -111.149892)
		(stroke
			(width 4.064)
			(type default)
		)
		(layer "In5.Cu")
	)
	(gr_arc
		(start 166.649908 -111.149892)
		(mid 167.357006 -110.856996)
		(end 167.649906 -110.149894)
		(stroke
			(width 4.064)
			(type default)
		)
		(layer "In5.Cu")
	)
	(gr_arc
		(start 166.887906 -13.750036)
		(mid 166.818198 -13.581746)
		(end 166.649908 -13.512038)
		(stroke
			(width 1.27)
			(type default)
		)
		(layer "In5.Cu")
	)
	(gr_line
		(start 166.931594 -72.300084)
		(end 167.150034 -72.300084)
		(stroke
			(width 4.064)
			(type default)
		)
		(layer "In5.Cu")
	)
	(gr_arc
		(start 166.931594 -60.825126)
		(mid 166.578131 -60.971535)
		(end 166.431722 -61.324998)
		(stroke
			(width 4.064)
			(type default)
		)
		(layer "In5.Cu")
	)
	(gr_line
		(start 167.150034 -60.825126)
		(end 166.931594 -60.825126)
		(stroke
			(width 4.064)
			(type default)
		)
		(layer "In5.Cu")
	)
	(gr_arc
		(start 167.150034 -60.825126)
		(mid 167.503548 -60.678612)
		(end 167.649906 -60.325)
		(stroke
			(width 4.064)
			(type default)
		)
		(layer "In5.Cu")
	)
	(gr_arc
		(start 167.649906 -72.799956)
		(mid 167.503483 -72.44651)
		(end 167.150034 -72.300084)
		(stroke
			(width 4.064)
			(type default)
		)
		(layer "In5.Cu")
	)
	(gr_line
		(start 167.649906 -72.799956)
		(end 167.649906 -110.149894)
		(stroke
			(width 4.064)
			(type default)
		)
		(layer "In5.Cu")
	)
	(gr_arc
		(start 167.649906 -13.750036)
		(mid 167.357027 -13.042905)
		(end 166.649908 -12.750038)
		(stroke
			(width 4.064)
			(type default)
		)
		(layer "In5.Cu")
	)
	(gr_line
		(start 167.649906 -13.750036)
		(end 167.649906 -60.325)
		(stroke
			(width 4.064)
			(type default)
		)
		(layer "In5.Cu")
	)
	(gr_line
		(start 0 -110.149894)
		(end 0 -5.500116)
		(stroke
			(width 0.05)
			(type default)
		)
		(layer "Edge.Cuts")
	)
	(gr_arc
		(start 0 -110.149894)
		(mid 0.292894 -110.856997)
		(end 0.999998 -111.149892)
		(stroke
			(width 0.05)
			(type default)
		)
		(layer "Edge.Cuts")
	)
	(gr_arc
		(start 0.999998 -4.500118)
		(mid 0.292893 -4.793011)
		(end 0 -5.500116)
		(stroke
			(width 0.05)
			(type default)
		)
		(layer "Edge.Cuts")
	)
	(gr_line
		(start 0.999998 -4.500118)
		(end 13.999972 -4.500118)
		(stroke
			(width 0.05)
			(type default)
		)
		(layer "Edge.Cuts")
	)
	(gr_arc
		(start 14.99997 -11.75004)
		(mid 15.292863 -12.457145)
		(end 15.999968 -12.750038)
		(stroke
			(width 0.05)
			(type default)
		)
		(layer "Edge.Cuts")
	)
	(gr_arc
		(start 14.99997 -5.500116)
		(mid 14.707081 -4.79301)
		(end 13.999972 -4.500118)
		(stroke
			(width 0.05)
			(type default)
		)
		(layer "Edge.Cuts")
	)
	(gr_line
		(start 14.99997 -5.500116)
		(end 14.99997 -11.75004)
		(stroke
			(width 0.05)
			(type default)
		)
		(layer "Edge.Cuts")
	)
	(gr_line
		(start 15.999968 -12.750038)
		(end 32.349948 -12.750038)
		(stroke
			(width 0.05)
			(type default)
		)
		(layer "Edge.Cuts")
	)
	(gr_arc
		(start 32.349948 -12.750038)
		(mid 33.057053 -12.457145)
		(end 33.349946 -11.75004)
		(stroke
			(width 0.05)
			(type default)
		)
		(layer "Edge.Cuts")
	)
	(gr_line
		(start 33.349946 -11.75004)
		(end 33.349946 -5.500116)
		(stroke
			(width 0.05)
			(type default)
		)
		(layer "Edge.Cuts")
	)
	(gr_arc
		(start 34.349944 -4.500118)
		(mid 33.642816 -4.792996)
		(end 33.349946 -5.500116)
		(stroke
			(width 0.05)
			(type default)
		)
		(layer "Edge.Cuts")
	)
	(gr_line
		(start 34.349944 -4.500118)
		(end 40.349932 -4.500118)
		(stroke
			(width 0.05)
			(type default)
		)
		(layer "Edge.Cuts")
	)
	(gr_arc
		(start 41.34993 -10.925048)
		(mid 43.17492 -12.750038)
		(end 44.99991 -10.925048)
		(stroke
			(width 0.05)
			(type default)
		)
		(layer "Edge.Cuts")
	)
	(gr_arc
		(start 41.34993 -5.500116)
		(mid 41.057045 -4.792989)
		(end 40.349932 -4.500118)
		(stroke
			(width 0.05)
			(type default)
		)
		(layer "Edge.Cuts")
	)
	(gr_line
		(start 41.34993 -5.500116)
		(end 41.34993 -10.925048)
		(stroke
			(width 0.05)
			(type default)
		)
		(layer "Edge.Cuts")
	)
	(gr_line
		(start 44.99991 -10.925048)
		(end 44.99991 -0.500126)
		(stroke
			(width 0.05)
			(type default)
		)
		(layer "Edge.Cuts")
	)
	(gr_line
		(start 44.99991 -0.500126)
		(end 45.500036 0)
		(stroke
			(width 0.05)
			(type default)
		)
		(layer "Edge.Cuts")
	)
	(gr_line
		(start 45.500036 0)
		(end 55.699914 0)
		(stroke
			(width 0.05)
			(type default)
		)
		(layer "Edge.Cuts")
	)
	(gr_line
		(start 55.699914 0)
		(end 56.20004 -0.500126)
		(stroke
			(width 0.05)
			(type default)
		)
		(layer "Edge.Cuts")
	)
	(gr_arc
		(start 56.20004 -7.450074)
		(mid 57.15 -8.400034)
		(end 58.09996 -7.450074)
		(stroke
			(width 0.05)
			(type default)
		)
		(layer "Edge.Cuts")
	)
	(gr_line
		(start 56.20004 -0.500126)
		(end 56.20004 -7.450074)
		(stroke
			(width 0.05)
			(type default)
		)
		(layer "Edge.Cuts")
	)
	(gr_line
		(start 58.09996 -7.450074)
		(end 58.09996 -0.500126)
		(stroke
			(width 0.05)
			(type default)
		)
		(layer "Edge.Cuts")
	)
	(gr_line
		(start 58.09996 -0.500126)
		(end 58.600086 0)
		(stroke
			(width 0.05)
			(type default)
		)
		(layer "Edge.Cuts")
	)
	(gr_line
		(start 58.600086 0)
		(end 78.799944 0)
		(stroke
			(width 0.05)
			(type default)
		)
		(layer "Edge.Cuts")
	)
	(gr_line
		(start 78.799944 0)
		(end 79.30007 -0.500126)
		(stroke
			(width 0.05)
			(type default)
		)
		(layer "Edge.Cuts")
	)
	(gr_arc
		(start 79.30007 -11.75004)
		(mid 79.592963 -12.457145)
		(end 80.300068 -12.750038)
		(stroke
			(width 0.05)
			(type default)
		)
		(layer "Edge.Cuts")
	)
	(gr_line
		(start 79.30007 -0.500126)
		(end 79.30007 -11.75004)
		(stroke
			(width 0.05)
			(type default)
		)
		(layer "Edge.Cuts")
	)
	(gr_line
		(start 80.300068 -12.750038)
		(end 166.649908 -12.750038)
		(stroke
			(width 0.05)
			(type default)
		)
		(layer "Edge.Cuts")
	)
	(gr_arc
		(start 166.431722 -71.799958)
		(mid 166.578026 -72.153675)
		(end 166.931594 -72.300084)
		(stroke
			(width 0.05)
			(type default)
		)
		(layer "Edge.Cuts")
	)
	(gr_line
		(start 166.431722 -61.324998)
		(end 166.431722 -71.799958)
		(stroke
			(width 0.05)
			(type default)
		)
		(layer "Edge.Cuts")
	)
	(gr_line
		(start 166.649908 -111.149892)
		(end 0.999998 -111.149892)
		(stroke
			(width 0.05)
			(type default)
		)
		(layer "Edge.Cuts")
	)
	(gr_arc
		(start 166.649908 -111.149892)
		(mid 167.357006 -110.856996)
		(end 167.649906 -110.149894)
		(stroke
			(width 0.05)
			(type default)
		)
		(layer "Edge.Cuts")
	)
	(gr_line
		(start 166.931594 -72.300084)
		(end 167.150034 -72.300084)
		(stroke
			(width 0.05)
			(type default)
		)
		(layer "Edge.Cuts")
	)
	(gr_arc
		(start 166.931594 -60.825126)
		(mid 166.578131 -60.971535)
		(end 166.431722 -61.324998)
		(stroke
			(width 0.05)
			(type default)
		)
		(layer "Edge.Cuts")
	)
	(gr_line
		(start 167.150034 -60.825126)
		(end 166.931594 -60.825126)
		(stroke
			(width 0.05)
			(type default)
		)
		(layer "Edge.Cuts")
	)
	(gr_arc
		(start 167.150034 -60.825126)
		(mid 167.503548 -60.678612)
		(end 167.649906 -60.325)
		(stroke
			(width 0.05)
			(type default)
		)
		(layer "Edge.Cuts")
	)
	(gr_arc
		(start 167.649906 -72.799956)
		(mid 167.503483 -72.44651)
		(end 167.150034 -72.300084)
		(stroke
			(width 0.05)
			(type default)
		)
		(layer "Edge.Cuts")
	)
	(gr_line
		(start 167.649906 -72.799956)
		(end 167.649906 -110.149894)
		(stroke
			(width 0.05)
			(type default)
		)
		(layer "Edge.Cuts")
	)
	(gr_arc
		(start 167.649906 -13.750036)
		(mid 167.357027 -13.042905)
		(end 166.649908 -12.750038)
		(stroke
			(width 0.05)
			(type default)
		)
		(layer "Edge.Cuts")
	)
	(gr_line
		(start 167.649906 -13.750036)
		(end 167.649906 -60.325)
		(stroke
			(width 0.05)
			(type default)
		)
		(layer "Edge.Cuts")
	)
	(gr_text "R4006-B0001-02_R01"
		(at 21.0185 -108.479082 0)
		(layer "F.Cu")
		(effects
			(font
				(size 1.27 0.9652)
				(thickness 0.000001)
			)
			(justify left)
		)
	)
	(gr_text "2022-02-25"
		(at 45.1231 -108.5215 0)
		(layer "F.Cu")
		(effects
			(font
				(size 1.27 0.9652)
				(thickness 0.000001)
			)
			(justify left)
		)
	)
	(gr_text "TOP"
		(at 96.52 32.8676 0)
		(layer "F.Cu")
		(effects
			(font
				(size 2.032 1.524)
				(thickness 0.000001)
			)
			(justify left)
		)
	)
	(gr_text "BOTTOM"
		(at 96.52 32.8676 0)
		(layer "B.Cu")
		(effects
			(font
				(size 2.032 1.524)
				(thickness 0.000001)
			)
			(justify left)
		)
	)
	(gr_text "L02_GND1"
		(at 96.52 32.8676 0)
		(layer "In1.Cu")
		(effects
			(font
				(size 2.032 1.524)
				(thickness 0.000001)
			)
			(justify left)
		)
	)
	(gr_text "L03_SIG1"
		(at 96.52 32.8676 0)
		(layer "In2.Cu")
		(effects
			(font
				(size 2.032 1.524)
				(thickness 0.000001)
			)
			(justify left)
		)
	)
	(gr_text "L04_GND2"
		(at 96.52 32.8676 0)
		(layer "In3.Cu")
		(effects
			(font
				(size 2.032 1.524)
				(thickness 0.000001)
			)
			(justify left)
		)
	)
	(gr_text "L05_VCC1"
		(at 96.52 32.8676 0)
		(layer "In4.Cu")
		(effects
			(font
				(size 2.032 1.524)
				(thickness 0.000001)
			)
			(justify left)
		)
	)
	(gr_text "L06_VCC2"
		(at 96.52 32.8676 0)
		(layer "In5.Cu")
		(effects
			(font
				(size 2.032 1.524)
				(thickness 0.000001)
			)
			(justify left)
		)
	)
	(gr_text "L07_GND3"
		(at 96.52 32.8676 0)
		(layer "In6.Cu")
		(effects
			(font
				(size 2.032 1.524)
				(thickness 0.000001)
			)
			(justify left)
		)
	)
	(gr_text "L08_SIG2"
		(at 96.52 32.8676 0)
		(layer "In7.Cu")
		(effects
			(font
				(size 2.032 1.524)
				(thickness 0.000001)
			)
			(justify left)
		)
	)
	(gr_text "L09_GND4"
		(at 96.52 32.8676 0)
		(layer "In8.Cu")
		(effects
			(font
				(size 2.032 1.524)
				(thickness 0.000001)
			)
			(justify left)
		)
	)
	(segment
		(start 109.474 -102.5906)
		(end 109.280198 -102.396798)
		(width 0.11938)
		(layer "F.Cu")
		(net "R_RGB_LED_I2C_SDA")
	)
	(segment
		(start 110.5916 -103.251)
		(end 109.474 -103.251)
		(width 0.11938)
		(layer "F.Cu")
		(net "R_RGB_LED_I2C_SDA")
	)
	(segment
		(start 109.280198 -102.396798)
		(end 107.67314 -102.396798)
		(width 0.11938)
		(layer "F.Cu")
		(net "R_RGB_LED_I2C_SDA")
	)
	(segment
		(start 109.474 -103.251)
		(end 109.474 -102.5906)
		(width 0.11938)
		(layer "F.Cu")
		(net "R_RGB_LED_I2C_SDA")
	)
	(via
		(at 109.474 -103.251)
		(size 0.508)
		(drill 0.254)
		(layers "F.Cu" "B.Cu")
		(net "R_RGB_LED_I2C_SDA")
	)
	(segment
		(start 110.5916 -103.251)
		(end 109.474 -103.251)
		(width 0.11938)
		(layer "B.Cu")
		(net "R_RGB_LED_I2C_SDA")
	)
	(segment
		(start 108.3564 -103.251)
		(end 109.474 -103.251)
		(width 0.11938)
		(layer "B.Cu")
		(net "R_RGB_LED_I2C_SDA")
	)
	(segment
		(start 108.230924 -102.896924)
		(end 107.71124 -102.896924)
		(width 0.11938)
		(layer "F.Cu")
		(net "R_RGB_LED_I2C_SCL")
	)
	(segment
		(start 108.712 -103.759)
		(end 108.712 -103.378)
		(width 0.11938)
		(layer "F.Cu")
		(net "R_RGB_LED_I2C_SCL")
	)
	(segment
		(start 108.712 -103.378)
		(end 108.230924 -102.896924)
		(width 0.11938)
		(layer "F.Cu")
		(net "R_RGB_LED_I2C_SCL")
	)
	(segment
		(start 109.474 -104.521)
		(end 108.712 -103.759)
		(width 0.11938)
		(layer "F.Cu")
		(net "R_RGB_LED_I2C_SCL")
	)
	(segment
		(start 110.5916 -104.521)
		(end 109.474 -104.521)
		(width 0.11938)
		(layer "F.Cu")
		(net "R_RGB_LED_I2C_SCL")
	)
	(via
		(at 109.474 -104.521)
		(size 0.508)
		(drill 0.254)
		(layers "F.Cu" "B.Cu")
		(net "R_RGB_LED_I2C_SCL")
	)
	(segment
		(start 110.5916 -104.521)
		(end 109.474 -104.521)
		(width 0.11938)
		(layer "B.Cu")
		(net "R_RGB_LED_I2C_SCL")
	)
	(segment
		(start 108.3564 -104.521)
		(end 109.474 -104.521)
		(width 0.11938)
		(layer "B.Cu")
		(net "R_RGB_LED_I2C_SCL")
	)
	(segment
		(start 117.094 -58.42)
		(end 118.0846 -58.42)
		(width 0.11938)
		(layer "F.Cu")
		(net "FPGA_FCS_B")
	)
	(segment
		(start 113.847118 -51.823112)
		(end 114.34699 -52.322984)
		(width 0.11938)
		(layer "F.Cu")
		(net "FPGA_FCS_B")
	)
	(segment
		(start 118.0846 -58.42)
		(end 118.11 -58.3946)
		(width 0.11938)
		(layer "F.Cu")
		(net "FPGA_FCS_B")
	)
	(via
		(at 117.094 -58.42)
		(size 0.508)
		(drill 0.254)
		(layers "F.Cu" "B.Cu")
		(net "FPGA_FCS_B")
	)
	(via
		(at 114.34699 -52.322984)
		(size 0.4572)
		(drill 0.2032)
		(layers "F.Cu" "B.Cu")
		(net "FPGA_FCS_B")
	)
	(segment
		(start 113.919 -52.750974)
		(end 114.34699 -52.322984)
		(width 0.127)
		(layer "In7.Cu")
		(net "FPGA_FCS_B")
	)
	(segment
		(start 116.205 -58.547)
		(end 113.919 -56.261)
		(width 0.127)
		(layer "In7.Cu")
		(net "FPGA_FCS_B")
	)
	(segment
		(start 116.967 -58.547)
		(end 116.205 -58.547)
		(width 0.127)
		(layer "In7.Cu")
		(net "FPGA_FCS_B")
	)
	(segment
		(start 113.919 -56.261)
		(end 113.919 -52.750974)
		(width 0.127)
		(layer "In7.Cu")
		(net "FPGA_FCS_B")
	)
	(segment
		(start 117.094 -58.42)
		(end 116.967 -58.547)
		(width 0.127)
		(layer "In7.Cu")
		(net "FPGA_FCS_B")
	)
	(segment
		(start 115.951 -58.547)
		(end 115.951 -59.242706)
		(width 0.11938)
		(layer "F.Cu")
		(net "FPGA_D03")
	)
	(segment
		(start 115.189 -57.785)
		(end 115.951 -58.547)
		(width 0.11938)
		(layer "F.Cu")
		(net "FPGA_D03")
	)
	(segment
		(start 114.046 -56.642)
		(end 114.046 -57.785)
		(width 0.11938)
		(layer "F.Cu")
		(net "FPGA_D03")
	)
	(segment
		(start 117.348 -61.341254)
		(end 117.348 -61.4426)
		(width 0.11938)
		(layer "F.Cu")
		(net "FPGA_D03")
	)
	(segment
		(start 113.284 -54.259988)
		(end 113.284 -55.88)
		(width 0.11938)
		(layer "F.Cu")
		(net "FPGA_D03")
	)
	(segment
		(start 116.77269 -60.765944)
		(end 117.348 -61.341254)
		(width 0.11938)
		(layer "F.Cu")
		(net "FPGA_D03")
	)
	(segment
		(start 113.284 -55.88)
		(end 114.046 -56.642)
		(width 0.11938)
		(layer "F.Cu")
		(net "FPGA_D03")
	)
	(segment
		(start 114.046 -57.785)
		(end 115.189 -57.785)
		(width 0.11938)
		(layer "F.Cu")
		(net "FPGA_D03")
	)
	(segment
		(start 116.77269 -60.064396)
		(end 116.77269 -60.765944)
		(width 0.11938)
		(layer "F.Cu")
		(net "FPGA_D03")
	)
	(segment
		(start 115.951 -59.242706)
		(end 116.77269 -60.064396)
		(width 0.11938)
		(layer "F.Cu")
		(net "FPGA_D03")
	)
	(segment
		(start 112.84712 -53.823108)
		(end 113.284 -54.259988)
		(width 0.11938)
		(layer "F.Cu")
		(net "FPGA_D03")
	)
	(via
		(at 114.046 -57.785)
		(size 0.508)
		(drill 0.254)
		(layers "F.Cu" "B.Cu")
		(net "FPGA_D03")
	)
	(segment
		(start 112.268 -54.243986)
		(end 112.268 -58.293)
		(width 0.11938)
		(layer "F.Cu")
		(net "FPGA_D02")
	)
	(segment
		(start 112.649 -58.674)
		(end 112.649 -58.801)
		(width 0.11938)
		(layer "F.Cu")
		(net "FPGA_D02")
	)
	(segment
		(start 114.427 -59.69)
		(end 114.554 -59.817)
		(width 0.11938)
		(layer "F.Cu")
		(net "FPGA_D02")
	)
	(segment
		(start 112.649 -58.801)
		(end 113.538 -59.69)
		(width 0.11938)
		(layer "F.Cu")
		(net "FPGA_D02")
	)
	(segment
		(start 112.268 -58.293)
		(end 112.649 -58.674)
		(width 0.11938)
		(layer "F.Cu")
		(net "FPGA_D02")
	)
	(segment
		(start 114.554 -60.9346)
		(end 115.062 -61.4426)
		(width 0.11938)
		(layer "F.Cu")
		(net "FPGA_D02")
	)
	(segment
		(start 111.847122 -53.823108)
		(end 112.268 -54.243986)
		(width 0.11938)
		(layer "F.Cu")
		(net "FPGA_D02")
	)
	(segment
		(start 114.554 -59.817)
		(end 114.554 -60.9346)
		(width 0.11938)
		(layer "F.Cu")
		(net "FPGA_D02")
	)
	(segment
		(start 113.538 -59.69)
		(end 114.427 -59.69)
		(width 0.11938)
		(layer "F.Cu")
		(net "FPGA_D02")
	)
	(via
		(at 112.649 -58.801)
		(size 0.508)
		(drill 0.254)
		(layers "F.Cu" "B.Cu")
		(net "FPGA_D02")
	)
	(segment
		(start 113.284 -56.69788)
		(end 112.84712 -56.261)
		(width 0.11938)
		(layer "F.Cu")
		(net "FPGA_D01")
	)
	(segment
		(start 114.046 -59.055)
		(end 115.1636 -59.055)
		(width 0.11938)
		(layer "F.Cu")
		(net "FPGA_D01")
	)
	(segment
		(start 114.046 -59.055)
		(end 113.284 -58.293)
		(width 0.11938)
		(layer "F.Cu")
		(net "FPGA_D01")
	)
	(segment
		(start 115.1636 -59.055)
		(end 115.189 -59.0296)
		(width 0.11938)
		(layer "F.Cu")
		(net "FPGA_D01")
	)
	(segment
		(start 112.84712 -56.261)
		(end 112.84712 -54.823106)
		(width 0.11938)
		(layer "F.Cu")
		(net "FPGA_D01")
	)
	(segment
		(start 113.284 -58.293)
		(end 113.284 -56.69788)
		(width 0.11938)
		(layer "F.Cu")
		(net "FPGA_D01")
	)
	(via
		(at 114.046 -59.055)
		(size 0.508)
		(drill 0.254)
		(layers "F.Cu" "B.Cu")
		(net "FPGA_D01")
	)
	(segment
		(start 111.633 -59.055)
		(end 112.649 -60.071)
		(width 0.11938)
		(layer "F.Cu")
		(net "FPGA_D00_MOSI")
	)
	(segment
		(start 112.649 -60.071)
		(end 112.776 -60.071)
		(width 0.11938)
		(layer "F.Cu")
		(net "FPGA_D00_MOSI")
	)
	(segment
		(start 113.411 -60.706)
		(end 113.411 -60.9346)
		(width 0.11938)
		(layer "F.Cu")
		(net "FPGA_D00_MOSI")
	)
	(segment
		(start 112.776 -60.071)
		(end 113.411 -60.706)
		(width 0.11938)
		(layer "F.Cu")
		(net "FPGA_D00_MOSI")
	)
	(segment
		(start 113.411 -60.9346)
		(end 113.919 -61.4426)
		(width 0.11938)
		(layer "F.Cu")
		(net "FPGA_D00_MOSI")
	)
	(segment
		(start 111.633 -57.070244)
		(end 111.633 -59.055)
		(width 0.11938)
		(layer "F.Cu")
		(net "FPGA_D00_MOSI")
	)
	(segment
		(start 111.847122 -54.823106)
		(end 111.847122 -56.856122)
		(width 0.11938)
		(layer "F.Cu")
		(net "FPGA_D00_MOSI")
	)
	(segment
		(start 111.847122 -56.856122)
		(end 111.633 -57.070244)
		(width 0.11938)
		(layer "F.Cu")
		(net "FPGA_D00_MOSI")
	)
	(via
		(at 112.649 -60.071)
		(size 0.508)
		(drill 0.254)
		(layers "F.Cu" "B.Cu")
		(net "FPGA_D00_MOSI")
	)
	(segment
		(start 94.107 -61.6204)
		(end 95.504 -61.6204)
		(width 0.11938)
		(layer "F.Cu")
		(net "UNNAMED_3_RESISTOR_I151_2")
	)
	(segment
		(start 92.837 -62.611)
		(end 92.837 -62.865)
		(width 0.11938)
		(layer "F.Cu")
		(net "UNNAMED_3_RESISTOR_I151_2")
	)
	(segment
		(start 92.837 -62.865)
		(end 92.90304 -62.93104)
		(width 0.11938)
		(layer "F.Cu")
		(net "UNNAMED_3_RESISTOR_I151_2")
	)
	(segment
		(start 93.1164 -62.611)
		(end 92.837 -62.611)
		(width 0.11938)
		(layer "F.Cu")
		(net "UNNAMED_3_RESISTOR_I151_2")
	)
	(segment
		(start 94.107 -61.6204)
		(end 93.1164 -62.611)
		(width 0.11938)
		(layer "F.Cu")
		(net "UNNAMED_3_RESISTOR_I151_2")
	)
	(segment
		(start 92.90304 -62.93104)
		(end 92.90304 -63.8429)
		(width 0.11938)
		(layer "F.Cu")
		(net "UNNAMED_3_RESISTOR_I151_2")
	)
	(via
		(at 92.837 -62.611)
		(size 0.508)
		(drill 0.254)
		(layers "F.Cu" "B.Cu")
		(net "UNNAMED_3_RESISTOR_I151_2")
	)
	(segment
		(start 76.1238 -15.7734)
		(end 76.1238 -14.615414)
		(width 0.11938)
		(layer "F.Cu")
		(net "PCIE_PERST_N")
	)
	(segment
		(start 82.042 -30.099)
		(end 82.042 -21.717)
		(width 0.11938)
		(layer "F.Cu")
		(net "PCIE_PERST_N")
	)
	(segment
		(start 92.71 -68.072)
		(end 92.90304 -67.87896)
		(width 0.11938)
		(layer "F.Cu")
		(net "PCIE_PERST_N")
	)
	(segment
		(start 76.1238 -14.615414)
		(end 76.0984 -14.590014)
		(width 0.11938)
		(layer "F.Cu")
		(net "PCIE_PERST_N")
	)
	(segment
		(start 82.042 -21.717)
		(end 76.1238 -15.7988)
		(width 0.11938)
		(layer "F.Cu")
		(net "PCIE_PERST_N")
	)
	(segment
		(start 92.90304 -67.87896)
		(end 92.90304 -66.7131)
		(width 0.11938)
		(layer "F.Cu")
		(net "PCIE_PERST_N")
	)
	(segment
		(start 76.1238 -15.7988)
		(end 76.1238 -15.7734)
		(width 0.11938)
		(layer "F.Cu")
		(net "PCIE_PERST_N")
	)
	(segment
		(start 81.407 -30.734)
		(end 82.042 -30.099)
		(width 0.11938)
		(layer "F.Cu")
		(net "PCIE_PERST_N")
	)
	(segment
		(start 81.407 -38.735)
		(end 81.407 -30.734)
		(width 0.11938)
		(layer "F.Cu")
		(net "PCIE_PERST_N")
	)
	(segment
		(start 79.375 -40.767)
		(end 81.407 -38.735)
		(width 0.11938)
		(layer "F.Cu")
		(net "PCIE_PERST_N")
	)
	(via
		(at 92.71 -68.072)
		(size 0.508)
		(drill 0.254)
		(layers "F.Cu" "B.Cu")
		(net "PCIE_PERST_N")
	)
	(via
		(at 79.375 -40.767)
		(size 0.508)
		(drill 0.254)
		(layers "F.Cu" "B.Cu")
		(net "PCIE_PERST_N")
	)
	(via
		(at 79.248 -67.183)
		(size 0.508)
		(drill 0.254)
		(layers "F.Cu" "B.Cu")
		(net "PCIE_PERST_N")
	)
	(segment
		(start 77.906118 -51.336194)
		(end 78.4225 -50.819812)
		(width 0.127)
		(layer "In2.Cu")
		(net "PCIE_PERST_N")
	)
	(segment
		(start 78.4225 -50.819812)
		(end 78.4225 -44.5135)
		(width 0.127)
		(layer "In2.Cu")
		(net "PCIE_PERST_N")
	)
	(segment
		(start 79.248 -67.183)
		(end 77.906118 -65.841118)
		(width 0.127)
		(layer "In2.Cu")
		(net "PCIE_PERST_N")
	)
	(segment
		(start 78.4225 -44.5135)
		(end 79.375 -43.561)
		(width 0.127)
		(layer "In2.Cu")
		(net "PCIE_PERST_N")
	)
	(segment
		(start 79.375 -43.561)
		(end 79.375 -40.767)
		(width 0.127)
		(layer "In2.Cu")
		(net "PCIE_PERST_N")
	)
	(segment
		(start 77.906118 -65.841118)
		(end 77.906118 -51.336194)
		(width 0.127)
		(layer "In2.Cu")
		(net "PCIE_PERST_N")
	)
	(segment
		(start 84.836 -68.315332)
		(end 84.836 -66.929)
		(width 0.127)
		(layer "In7.Cu")
		(net "PCIE_PERST_N")
	)
	(segment
		(start 90.33764 -68.326)
		(end 90.02014 -68.6435)
		(width 0.127)
		(layer "In7.Cu")
		(net "PCIE_PERST_N")
	)
	(segment
		(start 85.164168 -68.6435)
		(end 84.836 -68.315332)
		(width 0.127)
		(layer "In7.Cu")
		(net "PCIE_PERST_N")
	)
	(segment
		(start 90.02014 -68.6435)
		(end 85.164168 -68.6435)
		(width 0.127)
		(layer "In7.Cu")
		(net "PCIE_PERST_N")
	)
	(segment
		(start 92.456 -68.326)
		(end 90.33764 -68.326)
		(width 0.127)
		(layer "In7.Cu")
		(net "PCIE_PERST_N")
	)
	(segment
		(start 84.455 -66.548)
		(end 82.90306 -66.548)
		(width 0.127)
		(layer "In7.Cu")
		(net "PCIE_PERST_N")
	)
	(segment
		(start 80.391 -66.04)
		(end 79.248 -67.183)
		(width 0.127)
		(layer "In7.Cu")
		(net "PCIE_PERST_N")
	)
	(segment
		(start 82.39506 -66.04)
		(end 80.391 -66.04)
		(width 0.127)
		(layer "In7.Cu")
		(net "PCIE_PERST_N")
	)
	(segment
		(start 84.836 -66.929)
		(end 84.455 -66.548)
		(width 0.127)
		(layer "In7.Cu")
		(net "PCIE_PERST_N")
	)
	(segment
		(start 82.90306 -66.548)
		(end 82.39506 -66.04)
		(width 0.127)
		(layer "In7.Cu")
		(net "PCIE_PERST_N")
	)
	(segment
		(start 92.71 -68.072)
		(end 92.456 -68.326)
		(width 0.127)
		(layer "In7.Cu")
		(net "PCIE_PERST_N")
	)
	(segment
		(start 94.80296 -68.79844)
		(end 94.7674 -68.834)
		(width 0.11938)
		(layer "F.Cu")
		(net "FPGA_IN_RST_DLY_N")
	)
	(segment
		(start 94.80296 -66.7131)
		(end 94.80296 -68.79844)
		(width 0.11938)
		(layer "F.Cu")
		(net "FPGA_IN_RST_DLY_N")
	)
	(segment
		(start 106.847132 -52.82311)
		(end 106.34726 -53.322982)
		(width 0.11938)
		(layer "F.Cu")
		(net "FPGA_IN_RST_DLY_N")
	)
	(segment
		(start 95.123 -68.834)
		(end 94.7674 -68.834)
		(width 0.11938)
		(layer "F.Cu")
		(net "FPGA_IN_RST_DLY_N")
	)
	(segment
		(start 95.631 -68.326)
		(end 95.123 -68.834)
		(width 0.11938)
		(layer "F.Cu")
		(net "FPGA_IN_RST_DLY_N")
	)
	(via
		(at 106.34726 -53.322982)
		(size 0.4572)
		(drill 0.2032)
		(layers "F.Cu" "B.Cu")
		(net "FPGA_IN_RST_DLY_N")
	)
	(via
		(at 95.631 -68.326)
		(size 0.508)
		(drill 0.254)
		(layers "F.Cu" "B.Cu")
		(net "FPGA_IN_RST_DLY_N")
	)
	(segment
		(start 106.34726 -53.322982)
		(end 106.807 -53.782722)
		(width 0.127)
		(layer "In7.Cu")
		(net "FPGA_IN_RST_DLY_N")
	)
	(segment
		(start 106.807 -56.09336)
		(end 104.4575 -58.44286)
		(width 0.127)
		(layer "In7.Cu")
		(net "FPGA_IN_RST_DLY_N")
	)
	(segment
		(start 99.822254 -68.326)
		(end 95.631 -68.326)
		(width 0.127)
		(layer "In7.Cu")
		(net "FPGA_IN_RST_DLY_N")
	)
	(segment
		(start 102.900734 -66.4337)
		(end 101.714554 -66.4337)
		(width 0.127)
		(layer "In7.Cu")
		(net "FPGA_IN_RST_DLY_N")
	)
	(segment
		(start 106.807 -53.782722)
		(end 106.807 -56.09336)
		(width 0.127)
		(layer "In7.Cu")
		(net "FPGA_IN_RST_DLY_N")
	)
	(segment
		(start 104.4575 -64.876934)
		(end 102.900734 -66.4337)
		(width 0.127)
		(layer "In7.Cu")
		(net "FPGA_IN_RST_DLY_N")
	)
	(segment
		(start 104.4575 -58.44286)
		(end 104.4575 -64.876934)
		(width 0.127)
		(layer "In7.Cu")
		(net "FPGA_IN_RST_DLY_N")
	)
	(segment
		(start 101.714554 -66.4337)
		(end 99.822254 -68.326)
		(width 0.127)
		(layer "In7.Cu")
		(net "FPGA_IN_RST_DLY_N")
	)
	(segment
		(start 113.847118 -38.823138)
		(end 114.34699 -38.323266)
		(width 0.11938)
		(layer "F.Cu")
		(net "Net_14")
	)
	(via
		(at 114.34699 -38.323266)
		(size 0.4572)
		(drill 0.2032)
		(layers "F.Cu" "B.Cu")
		(net "Net_14")
	)
	(segment
		(start 108.408724 -99.896676)
		(end 107.71124 -99.896676)
		(width 0.11938)
		(layer "F.Cu")
		(net "RGB_LED_SHUTDOWN_N")
	)
	(segment
		(start 109.22 -98.171)
		(end 108.7882 -98.6028)
		(width 0.11938)
		(layer "F.Cu")
		(net "RGB_LED_SHUTDOWN_N")
	)
	(segment
		(start 110.5916 -98.171)
		(end 109.22 -98.171)
		(width 0.11938)
		(layer "F.Cu")
		(net "RGB_LED_SHUTDOWN_N")
	)
	(segment
		(start 108.7882 -99.5172)
		(end 108.408724 -99.896676)
		(width 0.11938)
		(layer "F.Cu")
		(net "RGB_LED_SHUTDOWN_N")
	)
	(segment
		(start 108.7882 -98.6028)
		(end 108.7882 -99.5172)
		(width 0.11938)
		(layer "F.Cu")
		(net "RGB_LED_SHUTDOWN_N")
	)
	(segment
		(start 110.5916 -98.171)
		(end 109.22 -98.171)
		(width 0.11938)
		(layer "B.Cu")
		(net "RGB_LED_SHUTDOWN_N")
	)
	(segment
		(start 108.5342 -98.8568)
		(end 108.5342 -99.2632)
		(width 0.11938)
		(layer "B.Cu")
		(net "RGB_LED_SHUTDOWN_N")
	)
	(segment
		(start 108.5342 -99.2632)
		(end 107.696 -100.1014)
		(width 0.11938)
		(layer "B.Cu")
		(net "RGB_LED_SHUTDOWN_N")
	)
	(segment
		(start 109.22 -98.171)
		(end 108.5342 -98.8568)
		(width 0.11938)
		(layer "B.Cu")
		(net "RGB_LED_SHUTDOWN_N")
	)
	(segment
		(start 85.47735 -83.4771)
		(end 85.226144 -83.225894)
		(width 0.11938)
		(layer "F.Cu")
		(net "PCA9546_RST_N")
	)
	(segment
		(start 85.226144 -83.225894)
		(end 83.3501 -83.225894)
		(width 0.11938)
		(layer "F.Cu")
		(net "PCA9546_RST_N")
	)
	(segment
		(start 85.47735 -83.947)
		(end 85.47735 -83.4771)
		(width 0.11938)
		(layer "F.Cu")
		(net "PCA9546_RST_N")
	)
	(via
		(at 85.47735 -83.947)
		(size 0.4572)
		(drill 0.2032)
		(layers "F.Cu" "B.Cu")
		(net "PCA9546_RST_N")
	)
	(segment
		(start 83.7692 -88.265)
		(end 83.7692 -87.122)
		(width 0.11938)
		(layer "B.Cu")
		(net "PCA9546_RST_N")
	)
	(segment
		(start 84.709 -88.265)
		(end 85.598 -87.376)
		(width 0.11938)
		(layer "B.Cu")
		(net "PCA9546_RST_N")
	)
	(segment
		(start 83.7692 -88.265)
		(end 84.709 -88.265)
		(width 0.11938)
		(layer "B.Cu")
		(net "PCA9546_RST_N")
	)
	(segment
		(start 85.598 -84.06765)
		(end 85.47735 -83.947)
		(width 0.11938)
		(layer "B.Cu")
		(net "PCA9546_RST_N")
	)
	(segment
		(start 85.598 -87.376)
		(end 85.598 -84.06765)
		(width 0.11938)
		(layer "B.Cu")
		(net "PCA9546_RST_N")
	)
	(segment
		(start 83.7692 -87.122)
		(end 83.7692 -85.979)
		(width 0.11938)
		(layer "B.Cu")
		(net "PCA9546_RST_N")
	)
	(segment
		(start 122.852434 -23.495)
		(end 122.990356 -23.357078)
		(width 0.11938)
		(layer "F.Cu")
		(net "MUX3_SEL")
	)
	(segment
		(start 120.963944 -23.241)
		(end 120.2944 -23.241)
		(width 0.11938)
		(layer "F.Cu")
		(net "MUX3_SEL")
	)
	(segment
		(start 120.2944 -23.241)
		(end 120.2944 -24.511)
		(width 0.11938)
		(layer "F.Cu")
		(net "MUX3_SEL")
	)
	(segment
		(start 121.793 -23.495)
		(end 122.852434 -23.495)
		(width 0.11938)
		(layer "F.Cu")
		(net "MUX3_SEL")
	)
	(segment
		(start 122.990356 -23.357078)
		(end 124.0917 -23.357078)
		(width 0.11938)
		(layer "F.Cu")
		(net "MUX3_SEL")
	)
	(segment
		(start 121.217944 -23.495)
		(end 120.963944 -23.241)
		(width 0.11938)
		(layer "F.Cu")
		(net "MUX3_SEL")
	)
	(segment
		(start 121.793 -23.495)
		(end 121.217944 -23.495)
		(width 0.11938)
		(layer "F.Cu")
		(net "MUX3_SEL")
	)
	(segment
		(start 121.793 -23.495)
		(end 121.539 -23.241)
		(width 0.11938)
		(layer "B.Cu")
		(net "MUX3_SEL")
	)
	(segment
		(start 121.539 -23.241)
		(end 120.2944 -23.241)
		(width 0.11938)
		(layer "B.Cu")
		(net "MUX3_SEL")
	)
	(segment
		(start 120.2944 -23.241)
		(end 120.2944 -24.511)
		(width 0.11938)
		(layer "B.Cu")
		(net "MUX3_SEL")
	)
	(segment
		(start 102.997 -82.296)
		(end 101.981 -82.296)
		(width 0.11938)
		(layer "F.Cu")
		(net "MUX2_SEL")
	)
	(segment
		(start 101.741986 -86.34476)
		(end 101.981 -86.105746)
		(width 0.11938)
		(layer "F.Cu")
		(net "MUX2_SEL")
	)
	(segment
		(start 104.267 -83.058)
		(end 104.887522 -82.437478)
		(width 0.11938)
		(layer "F.Cu")
		(net "MUX2_SEL")
	)
	(segment
		(start 101.981 -86.105746)
		(end 101.981 -83.5914)
		(width 0.11938)
		(layer "F.Cu")
		(net "MUX2_SEL")
	)
	(segment
		(start 103.632 -82.931)
		(end 102.997 -82.296)
		(width 0.11938)
		(layer "F.Cu")
		(net "MUX2_SEL")
	)
	(segment
		(start 101.981 -82.2706)
		(end 101.981 -82.296)
		(width 0.11938)
		(layer "F.Cu")
		(net "MUX2_SEL")
	)
	(segment
		(start 106.694986 -84.977986)
		(end 106.694986 -86.55304)
		(width 0.11938)
		(layer "F.Cu")
		(net "MUX2_SEL")
	)
	(segment
		(start 101.981 -82.296)
		(end 101.981 -83.5914)
		(width 0.11938)
		(layer "F.Cu")
		(net "MUX2_SEL")
	)
	(segment
		(start 103.886 -84.582)
		(end 106.299 -84.582)
		(width 0.11938)
		(layer "F.Cu")
		(net "MUX2_SEL")
	)
	(segment
		(start 104.887522 -82.437478)
		(end 105.9053 -82.437478)
		(width 0.11938)
		(layer "F.Cu")
		(net "MUX2_SEL")
	)
	(segment
		(start 103.632 -83.058)
		(end 104.267 -83.058)
		(width 0.11938)
		(layer "F.Cu")
		(net "MUX2_SEL")
	)
	(segment
		(start 103.632 -83.058)
		(end 103.632 -84.328)
		(width 0.11938)
		(layer "F.Cu")
		(net "MUX2_SEL")
	)
	(segment
		(start 101.741986 -86.50224)
		(end 101.741986 -86.34476)
		(width 0.11938)
		(layer "F.Cu")
		(net "MUX2_SEL")
	)
	(segment
		(start 103.632 -83.058)
		(end 103.632 -82.931)
		(width 0.11938)
		(layer "F.Cu")
		(net "MUX2_SEL")
	)
	(segment
		(start 103.632 -84.328)
		(end 103.886 -84.582)
		(width 0.11938)
		(layer "F.Cu")
		(net "MUX2_SEL")
	)
	(segment
		(start 106.299 -84.582)
		(end 106.694986 -84.977986)
		(width 0.11938)
		(layer "F.Cu")
		(net "MUX2_SEL")
	)
	(segment
		(start 101.981 -83.5914)
		(end 103.0986 -83.5914)
		(width 0.11938)
		(layer "B.Cu")
		(net "MUX2_SEL")
	)
	(segment
		(start 103.0986 -83.5914)
		(end 103.632 -83.058)
		(width 0.11938)
		(layer "B.Cu")
		(net "MUX2_SEL")
	)
	(segment
		(start 101.981 -82.2706)
		(end 101.981 -83.5914)
		(width 0.11938)
		(layer "B.Cu")
		(net "MUX2_SEL")
	)
	(segment
		(start 100.076 -96.774)
		(end 98.5774 -96.774)
		(width 0.11938)
		(layer "F.Cu")
		(net "MUX1_SEL")
	)
	(segment
		(start 101.737922 -95.620078)
		(end 100.33 -97.028)
		(width 0.11938)
		(layer "F.Cu")
		(net "MUX1_SEL")
	)
	(segment
		(start 98.5774 -95.4532)
		(end 98.5774 -96.774)
		(width 0.11938)
		(layer "F.Cu")
		(net "MUX1_SEL")
	)
	(segment
		(start 102.5017 -95.620078)
		(end 101.737922 -95.620078)
		(width 0.11938)
		(layer "F.Cu")
		(net "MUX1_SEL")
	)
	(segment
		(start 100.33 -97.028)
		(end 100.076 -96.774)
		(width 0.11938)
		(layer "F.Cu")
		(net "MUX1_SEL")
	)
	(segment
		(start 100.076 -96.774)
		(end 100.33 -97.028)
		(width 0.11938)
		(layer "B.Cu")
		(net "MUX1_SEL")
	)
	(segment
		(start 98.5774 -95.4532)
		(end 98.5774 -96.774)
		(width 0.11938)
		(layer "B.Cu")
		(net "MUX1_SEL")
	)
	(segment
		(start 98.5774 -96.774)
		(end 100.076 -96.774)
		(width 0.11938)
		(layer "B.Cu")
		(net "MUX1_SEL")
	)
	(segment
		(start 103.847138 -40.823134)
		(end 103.347266 -40.323262)
		(width 0.11938)
		(layer "F.Cu")
		(net "FPGA_MGTRREF")
	)
	(via
		(at 103.347266 -40.323262)
		(size 0.4572)
		(drill 0.2032)
		(layers "F.Cu" "B.Cu")
		(net "FPGA_MGTRREF")
	)
	(segment
		(start 95.1484 -43.688)
		(end 95.1484 -45.2628)
		(width 0.11938)
		(layer "B.Cu")
		(net "FPGA_MGTRREF")
	)
	(segment
		(start 104.343962 -40.716962)
		(end 104.902 -41.275)
		(width 0.127)
		(layer "In2.Cu")
		(net "FPGA_MGTRREF")
	)
	(segment
		(start 100.203 -44.577)
		(end 99.695 -44.069)
		(width 0.127)
		(layer "In2.Cu")
		(net "FPGA_MGTRREF")
	)
	(segment
		(start 99.695 -44.069)
		(end 96.012 -44.069)
		(width 0.127)
		(layer "In2.Cu")
		(net "FPGA_MGTRREF")
	)
	(segment
		(start 104.902 -41.275)
		(end 104.902 -43.942)
		(width 0.127)
		(layer "In2.Cu")
		(net "FPGA_MGTRREF")
	)
	(segment
		(start 103.740966 -40.716962)
		(end 104.343962 -40.716962)
		(width 0.127)
		(layer "In2.Cu")
		(net "FPGA_MGTRREF")
	)
	(segment
		(start 95.1484 -44.9326)
		(end 95.1484 -45.2628)
		(width 0.127)
		(layer "In2.Cu")
		(net "FPGA_MGTRREF")
	)
	(segment
		(start 103.347266 -40.323262)
		(end 103.740966 -40.716962)
		(width 0.127)
		(layer "In2.Cu")
		(net "FPGA_MGTRREF")
	)
	(segment
		(start 104.267 -44.577)
		(end 100.203 -44.577)
		(width 0.127)
		(layer "In2.Cu")
		(net "FPGA_MGTRREF")
	)
	(segment
		(start 96.012 -44.069)
		(end 95.1484 -44.9326)
		(width 0.127)
		(layer "In2.Cu")
		(net "FPGA_MGTRREF")
	)
	(segment
		(start 104.902 -43.942)
		(end 104.267 -44.577)
		(width 0.127)
		(layer "In2.Cu")
		(net "FPGA_MGTRREF")
	)
	(segment
		(start 108.204 -20.828)
		(end 106.807 -20.828)
		(width 0.11938)
		(layer "F.Cu")
		(net "CLK_200M_OE")
	)
	(segment
		(start 109.5756 -20.920964)
		(end 108.296964 -20.920964)
		(width 0.11938)
		(layer "F.Cu")
		(net "CLK_200M_OE")
	)
	(segment
		(start 108.296964 -20.920964)
		(end 108.204 -20.828)
		(width 0.11938)
		(layer "F.Cu")
		(net "CLK_200M_OE")
	)
	(segment
		(start 106.807 -22.3266)
		(end 106.807 -20.828)
		(width 0.11938)
		(layer "F.Cu")
		(net "CLK_200M_OE")
	)
	(segment
		(start 97.100644 -21.898356)
		(end 96.7994 -22.1996)
		(width 0.11938)
		(layer "F.Cu")
		(net "CLK_125M_OE")
	)
	(segment
		(start 94.9706 -22.1996)
		(end 94.107 -21.336)
		(width 0.11938)
		(layer "F.Cu")
		(net "CLK_125M_OE")
	)
	(segment
		(start 96.7994 -22.1996)
		(end 95.758 -22.1996)
		(width 0.11938)
		(layer "F.Cu")
		(net "CLK_125M_OE")
	)
	(segment
		(start 95.758 -22.1996)
		(end 94.9706 -22.1996)
		(width 0.11938)
		(layer "F.Cu")
		(net "CLK_125M_OE")
	)
	(segment
		(start 98.552 -20.447)
		(end 97.100644 -21.898356)
		(width 0.11938)
		(layer "F.Cu")
		(net "CLK_125M_OE")
	)
	(segment
		(start 98.552 -19.105118)
		(end 98.552 -20.447)
		(width 0.11938)
		(layer "F.Cu")
		(net "CLK_125M_OE")
	)
	(via
		(at 97.100644 -21.898356)
		(size 0.508)
		(drill 0.254)
		(layers "F.Cu" "B.Cu")
		(net "CLK_125M_OE")
	)
	(segment
		(start 12.5984 -55.005478)
		(end 12.587478 -55.0164)
		(width 0.11938)
		(layer "F.Cu")
		(net "UNNAMED_12_CAPACITOR_I332_2")
	)
	(segment
		(start 12.5984 -54.21757)
		(end 12.5984 -55.005478)
		(width 0.11938)
		(layer "F.Cu")
		(net "UNNAMED_12_CAPACITOR_I332_2")
	)
	(via
		(at 12.5984 -54.21757)
		(size 0.508)
		(drill 0.254)
		(layers "F.Cu" "B.Cu")
		(net "UNNAMED_12_CAPACITOR_I332_2")
	)
	(segment
		(start 12.5984 -53.356256)
		(end 12.843256 -53.1114)
		(width 0.11938)
		(layer "B.Cu")
		(net "UNNAMED_12_CAPACITOR_I332_2")
	)
	(segment
		(start 12.843256 -53.1114)
		(end 13.462 -53.1114)
		(width 0.11938)
		(layer "B.Cu")
		(net "UNNAMED_12_CAPACITOR_I332_2")
	)
	(segment
		(start 12.5984 -54.21757)
		(end 12.5984 -53.356256)
		(width 0.11938)
		(layer "B.Cu")
		(net "UNNAMED_12_CAPACITOR_I332_2")
	)
	(segment
		(start 13.142722 -68.819522)
		(end 13.142722 -68.072)
		(width 0.11938)
		(layer "F.Cu")
		(net "UNNAMED_12_CAPACITOR_I328_2")
	)
	(segment
		(start 13.4112 -69.088)
		(end 13.142722 -68.819522)
		(width 0.11938)
		(layer "F.Cu")
		(net "UNNAMED_12_CAPACITOR_I328_2")
	)
	(via
		(at 13.4112 -69.088)
		(size 0.508)
		(drill 0.254)
		(layers "F.Cu" "B.Cu")
		(net "UNNAMED_12_CAPACITOR_I328_2")
	)
	(segment
		(start 13.17752 -68.85432)
		(end 13.4112 -69.088)
		(width 0.11938)
		(layer "B.Cu")
		(net "UNNAMED_12_CAPACITOR_I328_2")
	)
	(segment
		(start 13.17752 -66.98488)
		(end 13.17752 -68.85432)
		(width 0.11938)
		(layer "B.Cu")
		(net "UNNAMED_12_CAPACITOR_I328_2")
	)
	(segment
		(start 13.462 -66.7004)
		(end 13.17752 -66.98488)
		(width 0.11938)
		(layer "B.Cu")
		(net "UNNAMED_12_CAPACITOR_I328_2")
	)
	(segment
		(start 14.224 -25.4)
		(end 13.320522 -25.4)
		(width 0.11938)
		(layer "F.Cu")
		(net "UNNAMED_12_CAPACITOR_I321_2")
	)
	(segment
		(start 14.605 -25.781)
		(end 14.224 -25.4)
		(width 0.11938)
		(layer "F.Cu")
		(net "UNNAMED_12_CAPACITOR_I321_2")
	)
	(via
		(at 14.605 -25.781)
		(size 0.508)
		(drill 0.254)
		(layers "F.Cu" "B.Cu")
		(net "UNNAMED_12_CAPACITOR_I321_2")
	)
	(segment
		(start 14.097 -24.0284)
		(end 13.589 -23.5204)
		(width 0.11938)
		(layer "B.Cu")
		(net "UNNAMED_12_CAPACITOR_I321_2")
	)
	(segment
		(start 14.097 -25.273)
		(end 14.097 -24.0284)
		(width 0.11938)
		(layer "B.Cu")
		(net "UNNAMED_12_CAPACITOR_I321_2")
	)
	(segment
		(start 14.605 -25.781)
		(end 14.097 -25.273)
		(width 0.11938)
		(layer "B.Cu")
		(net "UNNAMED_12_CAPACITOR_I321_2")
	)
	(segment
		(start 12.435078 -39.019226)
		(end 12.435078 -39.878)
		(width 0.11938)
		(layer "F.Cu")
		(net "UNNAMED_12_CAPACITOR_I318_2")
	)
	(via
		(at 12.435078 -39.019226)
		(size 0.508)
		(drill 0.254)
		(layers "F.Cu" "B.Cu")
		(net "UNNAMED_12_CAPACITOR_I318_2")
	)
	(segment
		(start 12.435078 -38.771322)
		(end 13.462 -37.7444)
		(width 0.11938)
		(layer "B.Cu")
		(net "UNNAMED_12_CAPACITOR_I318_2")
	)
	(segment
		(start 12.435078 -39.019226)
		(end 12.435078 -38.771322)
		(width 0.11938)
		(layer "B.Cu")
		(net "UNNAMED_12_CAPACITOR_I318_2")
	)
	(segment
		(start 117.84711 -49.823116)
		(end 118.346982 -50.322988)
		(width 0.11938)
		(layer "F.Cu")
		(net "Net_27")
	)
	(via
		(at 118.346982 -50.322988)
		(size 0.4572)
		(drill 0.2032)
		(layers "F.Cu" "B.Cu")
		(net "Net_27")
	)
	(segment
		(start 103.847138 -47.82312)
		(end 103.347266 -48.322992)
		(width 0.11938)
		(layer "F.Cu")
		(net "Net_28")
	)
	(via
		(at 103.347266 -48.322992)
		(size 0.4572)
		(drill 0.2032)
		(layers "F.Cu" "B.Cu")
		(net "Net_28")
	)
	(segment
		(start 113.847118 -35.82289)
		(end 114.34699 -35.323018)
		(width 0.11938)
		(layer "F.Cu")
		(net "Net_29")
	)
	(via
		(at 114.34699 -35.323018)
		(size 0.4572)
		(drill 0.2032)
		(layers "F.Cu" "B.Cu")
		(net "Net_29")
	)
	(segment
		(start 103.847138 -53.823108)
		(end 103.347266 -54.32298)
		(width 0.11938)
		(layer "F.Cu")
		(net "Net_30")
	)
	(via
		(at 103.347266 -54.32298)
		(size 0.4572)
		(drill 0.2032)
		(layers "F.Cu" "B.Cu")
		(net "Net_30")
	)
	(segment
		(start 107.84713 -51.823112)
		(end 107.347258 -52.322984)
		(width 0.11938)
		(layer "F.Cu")
		(net "Net_33")
	)
	(via
		(at 107.347258 -52.322984)
		(size 0.4572)
		(drill 0.2032)
		(layers "F.Cu" "B.Cu")
		(net "Net_33")
	)
	(segment
		(start 100.84689 -51.823112)
		(end 100.347018 -52.322984)
		(width 0.11938)
		(layer "F.Cu")
		(net "Net_34")
	)
	(via
		(at 100.347018 -52.322984)
		(size 0.4572)
		(drill 0.2032)
		(layers "F.Cu" "B.Cu")
		(net "Net_34")
	)
	(segment
		(start 107.84713 -50.823114)
		(end 107.347258 -51.322986)
		(width 0.11938)
		(layer "F.Cu")
		(net "Net_35")
	)
	(via
		(at 107.347258 -51.322986)
		(size 0.4572)
		(drill 0.2032)
		(layers "F.Cu" "B.Cu")
		(net "Net_35")
	)
	(segment
		(start 108.847128 -52.82311)
		(end 108.347256 -53.322982)
		(width 0.11938)
		(layer "F.Cu")
		(net "Net_36")
	)
	(via
		(at 108.347256 -53.322982)
		(size 0.4572)
		(drill 0.2032)
		(layers "F.Cu" "B.Cu")
		(net "Net_36")
	)
	(segment
		(start 108.847128 -51.823112)
		(end 108.347256 -52.322984)
		(width 0.11938)
		(layer "F.Cu")
		(net "Net_37")
	)
	(via
		(at 108.347256 -52.322984)
		(size 0.4572)
		(drill 0.2032)
		(layers "F.Cu" "B.Cu")
		(net "Net_37")
	)
	(segment
		(start 114.34699 -48.322992)
		(end 113.847118 -47.82312)
		(width 0.11938)
		(layer "F.Cu")
		(net "Net_38")
	)
	(via
		(at 114.34699 -48.322992)
		(size 0.4572)
		(drill 0.2032)
		(layers "F.Cu" "B.Cu")
		(net "Net_38")
	)
	(segment
		(start 119.847106 -52.82311)
		(end 120.346978 -53.322982)
		(width 0.11938)
		(layer "F.Cu")
		(net "Net_39")
	)
	(via
		(at 120.346978 -53.322982)
		(size 0.4572)
		(drill 0.2032)
		(layers "F.Cu" "B.Cu")
		(net "Net_39")
	)
	(segment
		(start 102.84714 -50.823114)
		(end 102.347268 -51.322986)
		(width 0.11938)
		(layer "F.Cu")
		(net "Net_40")
	)
	(via
		(at 102.347268 -51.322986)
		(size 0.4572)
		(drill 0.2032)
		(layers "F.Cu" "B.Cu")
		(net "Net_40")
	)
	(segment
		(start 113.847118 -46.823122)
		(end 114.34699 -47.322994)
		(width 0.11938)
		(layer "F.Cu")
		(net "Net_41")
	)
	(via
		(at 114.34699 -47.322994)
		(size 0.4572)
		(drill 0.2032)
		(layers "F.Cu" "B.Cu")
		(net "Net_41")
	)
	(segment
		(start 118.847108 -51.823112)
		(end 119.34698 -52.322984)
		(width 0.11938)
		(layer "F.Cu")
		(net "Net_42")
	)
	(via
		(at 119.34698 -52.322984)
		(size 0.4572)
		(drill 0.2032)
		(layers "F.Cu" "B.Cu")
		(net "Net_42")
	)
	(segment
		(start 116.847112 -48.823118)
		(end 117.346984 -49.32299)
		(width 0.11938)
		(layer "F.Cu")
		(net "Net_43")
	)
	(via
		(at 117.346984 -49.32299)
		(size 0.4572)
		(drill 0.2032)
		(layers "F.Cu" "B.Cu")
		(net "Net_43")
	)
	(segment
		(start 116.847112 -49.823116)
		(end 117.346984 -50.322988)
		(width 0.11938)
		(layer "F.Cu")
		(net "Net_44")
	)
	(via
		(at 117.346984 -50.322988)
		(size 0.4572)
		(drill 0.2032)
		(layers "F.Cu" "B.Cu")
		(net "Net_44")
	)
	(segment
		(start 108.847128 -50.823114)
		(end 108.347256 -51.322986)
		(width 0.11938)
		(layer "F.Cu")
		(net "Net_45")
	)
	(via
		(at 108.347256 -51.322986)
		(size 0.4572)
		(drill 0.2032)
		(layers "F.Cu" "B.Cu")
		(net "Net_45")
	)
	(segment
		(start 116.847112 -47.82312)
		(end 117.346984 -48.322992)
		(width 0.11938)
		(layer "F.Cu")
		(net "Net_46")
	)
	(via
		(at 117.346984 -48.322992)
		(size 0.4572)
		(drill 0.2032)
		(layers "F.Cu" "B.Cu")
		(net "Net_46")
	)
	(segment
		(start 115.847114 -49.823116)
		(end 116.346986 -50.322988)
		(width 0.11938)
		(layer "F.Cu")
		(net "Net_47")
	)
	(via
		(at 116.346986 -50.322988)
		(size 0.4572)
		(drill 0.2032)
		(layers "F.Cu" "B.Cu")
		(net "Net_47")
	)
	(segment
		(start 114.847116 -50.823114)
		(end 115.346988 -51.322986)
		(width 0.11938)
		(layer "F.Cu")
		(net "Net_49")
	)
	(via
		(at 115.346988 -51.322986)
		(size 0.4572)
		(drill 0.2032)
		(layers "F.Cu" "B.Cu")
		(net "Net_49")
	)
	(segment
		(start 109.847126 -52.82311)
		(end 110.346998 -53.322982)
		(width 0.11938)
		(layer "F.Cu")
		(net "Net_50")
	)
	(via
		(at 110.346998 -53.322982)
		(size 0.4572)
		(drill 0.2032)
		(layers "F.Cu" "B.Cu")
		(net "Net_50")
	)
	(segment
		(start 103.847138 -52.82311)
		(end 103.347266 -53.322982)
		(width 0.11938)
		(layer "F.Cu")
		(net "Net_51")
	)
	(via
		(at 103.347266 -53.322982)
		(size 0.4572)
		(drill 0.2032)
		(layers "F.Cu" "B.Cu")
		(net "Net_51")
	)
	(segment
		(start 118.847108 -38.823138)
		(end 119.34698 -38.323266)
		(width 0.11938)
		(layer "F.Cu")
		(net "Net_52")
	)
	(via
		(at 119.34698 -38.323266)
		(size 0.4572)
		(drill 0.2032)
		(layers "F.Cu" "B.Cu")
		(net "Net_52")
	)
	(segment
		(start 114.847116 -49.823116)
		(end 115.346988 -50.322988)
		(width 0.11938)
		(layer "F.Cu")
		(net "Net_53")
	)
	(via
		(at 115.346988 -50.322988)
		(size 0.4572)
		(drill 0.2032)
		(layers "F.Cu" "B.Cu")
		(net "Net_53")
	)
	(segment
		(start 103.847138 -51.823112)
		(end 103.347266 -52.322984)
		(width 0.11938)
		(layer "F.Cu")
		(net "Net_54")
	)
	(via
		(at 103.347266 -52.322984)
		(size 0.4572)
		(drill 0.2032)
		(layers "F.Cu" "B.Cu")
		(net "Net_54")
	)
	(segment
		(start 117.84711 -38.823138)
		(end 118.346982 -38.323266)
		(width 0.11938)
		(layer "F.Cu")
		(net "Net_55")
	)
	(via
		(at 118.346982 -38.323266)
		(size 0.4572)
		(drill 0.2032)
		(layers "F.Cu" "B.Cu")
		(net "Net_55")
	)
	(segment
		(start 100.84689 -52.82311)
		(end 100.347018 -53.322982)
		(width 0.11938)
		(layer "F.Cu")
		(net "Net_56")
	)
	(via
		(at 100.347018 -53.322982)
		(size 0.4572)
		(drill 0.2032)
		(layers "F.Cu" "B.Cu")
		(net "Net_56")
	)
	(segment
		(start 116.847112 -39.823136)
		(end 117.346984 -39.323264)
		(width 0.11938)
		(layer "F.Cu")
		(net "Net_57")
	)
	(via
		(at 117.346984 -39.323264)
		(size 0.4572)
		(drill 0.2032)
		(layers "F.Cu" "B.Cu")
		(net "Net_57")
	)
	(segment
		(start 101.847142 -52.82311)
		(end 101.34727 -53.322982)
		(width 0.11938)
		(layer "F.Cu")
		(net "Net_58")
	)
	(via
		(at 101.34727 -53.322982)
		(size 0.4572)
		(drill 0.2032)
		(layers "F.Cu" "B.Cu")
		(net "Net_58")
	)
	(segment
		(start 115.847114 -39.823136)
		(end 116.346986 -39.323264)
		(width 0.11938)
		(layer "F.Cu")
		(net "Net_59")
	)
	(via
		(at 116.346986 -39.323264)
		(size 0.4572)
		(drill 0.2032)
		(layers "F.Cu" "B.Cu")
		(net "Net_59")
	)
	(segment
		(start 118.847108 -48.823118)
		(end 119.34698 -49.32299)
		(width 0.11938)
		(layer "F.Cu")
		(net "Net_60")
	)
	(via
		(at 119.34698 -49.32299)
		(size 0.4572)
		(drill 0.2032)
		(layers "F.Cu" "B.Cu")
		(net "Net_60")
	)
	(segment
		(start 113.847118 -50.823114)
		(end 114.34699 -51.322986)
		(width 0.11938)
		(layer "F.Cu")
		(net "Net_61")
	)
	(via
		(at 114.34699 -51.322986)
		(size 0.4572)
		(drill 0.2032)
		(layers "F.Cu" "B.Cu")
		(net "Net_61")
	)
	(segment
		(start 112.84712 -50.823114)
		(end 113.346992 -51.322986)
		(width 0.11938)
		(layer "F.Cu")
		(net "Net_62")
	)
	(via
		(at 113.346992 -51.322986)
		(size 0.4572)
		(drill 0.2032)
		(layers "F.Cu" "B.Cu")
		(net "Net_62")
	)
	(segment
		(start 111.847122 -49.823116)
		(end 112.346994 -50.322988)
		(width 0.11938)
		(layer "F.Cu")
		(net "Net_63")
	)
	(via
		(at 112.346994 -50.322988)
		(size 0.4572)
		(drill 0.2032)
		(layers "F.Cu" "B.Cu")
		(net "Net_63")
	)
	(segment
		(start 112.84712 -48.823118)
		(end 113.346992 -49.32299)
		(width 0.11938)
		(layer "F.Cu")
		(net "Net_64")
	)
	(via
		(at 113.346992 -49.32299)
		(size 0.4572)
		(drill 0.2032)
		(layers "F.Cu" "B.Cu")
		(net "Net_64")
	)
	(segment
		(start 110.847124 -46.823122)
		(end 111.346996 -47.322994)
		(width 0.11938)
		(layer "F.Cu")
		(net "Net_65")
	)
	(via
		(at 111.346996 -47.322994)
		(size 0.4572)
		(drill 0.2032)
		(layers "F.Cu" "B.Cu")
		(net "Net_65")
	)
	(segment
		(start 110.847124 -45.823124)
		(end 111.346996 -46.322996)
		(width 0.11938)
		(layer "F.Cu")
		(net "Net_66")
	)
	(via
		(at 111.346996 -46.322996)
		(size 0.4572)
		(drill 0.2032)
		(layers "F.Cu" "B.Cu")
		(net "Net_66")
	)
	(segment
		(start 112.84712 -49.823116)
		(end 113.346992 -50.322988)
		(width 0.11938)
		(layer "F.Cu")
		(net "Net_67")
	)
	(via
		(at 113.346992 -50.322988)
		(size 0.4572)
		(drill 0.2032)
		(layers "F.Cu" "B.Cu")
		(net "Net_67")
	)
	(segment
		(start 104.847136 -48.823118)
		(end 104.347264 -49.32299)
		(width 0.11938)
		(layer "F.Cu")
		(net "Net_68")
	)
	(via
		(at 104.347264 -49.32299)
		(size 0.4572)
		(drill 0.2032)
		(layers "F.Cu" "B.Cu")
		(net "Net_68")
	)
	(segment
		(start 102.84714 -49.823116)
		(end 102.347268 -50.322988)
		(width 0.11938)
		(layer "F.Cu")
		(net "Net_69")
	)
	(via
		(at 102.347268 -50.322988)
		(size 0.4572)
		(drill 0.2032)
		(layers "F.Cu" "B.Cu")
		(net "Net_69")
	)
	(segment
		(start 115.847114 -54.823106)
		(end 116.346986 -55.322978)
		(width 0.11938)
		(layer "F.Cu")
		(net "Net_70")
	)
	(via
		(at 116.346986 -55.322978)
		(size 0.4572)
		(drill 0.2032)
		(layers "F.Cu" "B.Cu")
		(net "Net_70")
	)
	(segment
		(start 119.847106 -47.82312)
		(end 120.346978 -48.322992)
		(width 0.11938)
		(layer "F.Cu")
		(net "Net_71")
	)
	(via
		(at 120.346978 -48.322992)
		(size 0.4572)
		(drill 0.2032)
		(layers "F.Cu" "B.Cu")
		(net "Net_71")
	)
	(segment
		(start 114.847116 -53.823108)
		(end 115.346988 -54.32298)
		(width 0.11938)
		(layer "F.Cu")
		(net "Net_72")
	)
	(via
		(at 115.346988 -54.32298)
		(size 0.4572)
		(drill 0.2032)
		(layers "F.Cu" "B.Cu")
		(net "Net_72")
	)
	(segment
		(start 104.847136 -50.823114)
		(end 104.347264 -51.322986)
		(width 0.11938)
		(layer "F.Cu")
		(net "Net_73")
	)
	(via
		(at 104.347264 -51.322986)
		(size 0.4572)
		(drill 0.2032)
		(layers "F.Cu" "B.Cu")
		(net "Net_73")
	)
	(segment
		(start 113.847118 -53.823108)
		(end 114.34699 -54.32298)
		(width 0.11938)
		(layer "F.Cu")
		(net "Net_74")
	)
	(via
		(at 114.34699 -54.32298)
		(size 0.4572)
		(drill 0.2032)
		(layers "F.Cu" "B.Cu")
		(net "Net_74")
	)
	(segment
		(start 101.847142 -48.823118)
		(end 101.34727 -49.32299)
		(width 0.11938)
		(layer "F.Cu")
		(net "Net_75")
	)
	(via
		(at 101.34727 -49.32299)
		(size 0.4572)
		(drill 0.2032)
		(layers "F.Cu" "B.Cu")
		(net "Net_75")
	)
	(segment
		(start 102.84714 -48.823118)
		(end 102.347268 -49.32299)
		(width 0.11938)
		(layer "F.Cu")
		(net "Net_76")
	)
	(via
		(at 102.347268 -49.32299)
		(size 0.4572)
		(drill 0.2032)
		(layers "F.Cu" "B.Cu")
		(net "Net_76")
	)
	(segment
		(start 113.847118 -52.82311)
		(end 114.34699 -53.322982)
		(width 0.11938)
		(layer "F.Cu")
		(net "Net_77")
	)
	(via
		(at 114.34699 -53.322982)
		(size 0.4572)
		(drill 0.2032)
		(layers "F.Cu" "B.Cu")
		(net "Net_77")
	)
	(segment
		(start 105.847134 -50.823114)
		(end 105.347262 -51.322986)
		(width 0.11938)
		(layer "F.Cu")
		(net "Net_78")
	)
	(via
		(at 105.347262 -51.322986)
		(size 0.4572)
		(drill 0.2032)
		(layers "F.Cu" "B.Cu")
		(net "Net_78")
	)
	(segment
		(start 116.847112 -54.823106)
		(end 117.346984 -55.322978)
		(width 0.11938)
		(layer "F.Cu")
		(net "Net_79")
	)
	(via
		(at 117.346984 -55.322978)
		(size 0.4572)
		(drill 0.2032)
		(layers "F.Cu" "B.Cu")
		(net "Net_79")
	)
	(segment
		(start 102.84714 -46.823122)
		(end 102.347268 -47.322994)
		(width 0.11938)
		(layer "F.Cu")
		(net "Net_86")
	)
	(via
		(at 102.347268 -47.322994)
		(size 0.4572)
		(drill 0.2032)
		(layers "F.Cu" "B.Cu")
		(net "Net_86")
	)
	(segment
		(start 103.847138 -36.823142)
		(end 103.347266 -36.32327)
		(width 0.11938)
		(layer "F.Cu")
		(net "Net_87")
	)
	(via
		(at 103.347266 -36.32327)
		(size 0.4572)
		(drill 0.2032)
		(layers "F.Cu" "B.Cu")
		(net "Net_87")
	)
	(segment
		(start 114.847116 -39.823136)
		(end 115.346988 -39.323264)
		(width 0.11938)
		(layer "F.Cu")
		(net "Net_88")
	)
	(via
		(at 115.346988 -39.323264)
		(size 0.4572)
		(drill 0.2032)
		(layers "F.Cu" "B.Cu")
		(net "Net_88")
	)
	(segment
		(start 108.847128 -38.823138)
		(end 108.347256 -38.323266)
		(width 0.11938)
		(layer "F.Cu")
		(net "Net_89")
	)
	(via
		(at 108.347256 -38.323266)
		(size 0.4572)
		(drill 0.2032)
		(layers "F.Cu" "B.Cu")
		(net "Net_89")
	)
	(segment
		(start 106.847132 -48.823118)
		(end 106.34726 -49.32299)
		(width 0.11938)
		(layer "F.Cu")
		(net "Net_90")
	)
	(via
		(at 106.34726 -49.32299)
		(size 0.4572)
		(drill 0.2032)
		(layers "F.Cu" "B.Cu")
		(net "Net_90")
	)
	(segment
		(start 105.847134 -37.82314)
		(end 105.347262 -37.323268)
		(width 0.11938)
		(layer "F.Cu")
		(net "Net_91")
	)
	(via
		(at 105.347262 -37.323268)
		(size 0.4572)
		(drill 0.2032)
		(layers "F.Cu" "B.Cu")
		(net "Net_91")
	)
	(segment
		(start 106.847132 -37.82314)
		(end 106.34726 -37.323268)
		(width 0.11938)
		(layer "F.Cu")
		(net "Net_92")
	)
	(via
		(at 106.34726 -37.323268)
		(size 0.4572)
		(drill 0.2032)
		(layers "F.Cu" "B.Cu")
		(net "Net_92")
	)
	(segment
		(start 106.847132 -53.823108)
		(end 106.34726 -54.32298)
		(width 0.11938)
		(layer "F.Cu")
		(net "Net_93")
	)
	(via
		(at 106.34726 -54.32298)
		(size 0.4572)
		(drill 0.2032)
		(layers "F.Cu" "B.Cu")
		(net "Net_93")
	)
	(segment
		(start 118.847108 -36.823142)
		(end 119.34698 -36.32327)
		(width 0.11938)
		(layer "F.Cu")
		(net "Net_94")
	)
	(via
		(at 119.34698 -36.32327)
		(size 0.4572)
		(drill 0.2032)
		(layers "F.Cu" "B.Cu")
		(net "Net_94")
	)
	(segment
		(start 104.847136 -35.82289)
		(end 104.347264 -35.323018)
		(width 0.11938)
		(layer "F.Cu")
		(net "Net_95")
	)
	(via
		(at 104.347264 -35.323018)
		(size 0.4572)
		(drill 0.2032)
		(layers "F.Cu" "B.Cu")
		(net "Net_95")
	)
	(segment
		(start 117.84711 -36.823142)
		(end 118.346982 -36.32327)
		(width 0.11938)
		(layer "F.Cu")
		(net "Net_96")
	)
	(via
		(at 118.346982 -36.32327)
		(size 0.4572)
		(drill 0.2032)
		(layers "F.Cu" "B.Cu")
		(net "Net_96")
	)
	(segment
		(start 105.847134 -35.82289)
		(end 105.347262 -35.323018)
		(width 0.11938)
		(layer "F.Cu")
		(net "Net_97")
	)
	(via
		(at 105.347262 -35.323018)
		(size 0.4572)
		(drill 0.2032)
		(layers "F.Cu" "B.Cu")
		(net "Net_97")
	)
	(segment
		(start 116.847112 -36.823142)
		(end 117.346984 -36.32327)
		(width 0.11938)
		(layer "F.Cu")
		(net "Net_98")
	)
	(via
		(at 117.346984 -36.32327)
		(size 0.4572)
		(drill 0.2032)
		(layers "F.Cu" "B.Cu")
		(net "Net_98")
	)
	(segment
		(start 104.847136 -36.823142)
		(end 104.347264 -36.32327)
		(width 0.11938)
		(layer "F.Cu")
		(net "Net_99")
	)
	(via
		(at 104.347264 -36.32327)
		(size 0.4572)
		(drill 0.2032)
		(layers "F.Cu" "B.Cu")
		(net "Net_99")
	)
	(segment
		(start 115.847114 -36.823142)
		(end 116.346986 -36.32327)
		(width 0.11938)
		(layer "F.Cu")
		(net "Net_100")
	)
	(via
		(at 116.346986 -36.32327)
		(size 0.4572)
		(drill 0.2032)
		(layers "F.Cu" "B.Cu")
		(net "Net_100")
	)
	(segment
		(start 105.847134 -36.823142)
		(end 105.347262 -36.32327)
		(width 0.11938)
		(layer "F.Cu")
		(net "Net_101")
	)
	(via
		(at 105.347262 -36.32327)
		(size 0.4572)
		(drill 0.2032)
		(layers "F.Cu" "B.Cu")
		(net "Net_101")
	)
	(segment
		(start 106.847132 -36.823142)
		(end 106.34726 -36.32327)
		(width 0.11938)
		(layer "F.Cu")
		(net "Net_102")
	)
	(via
		(at 106.34726 -36.32327)
		(size 0.4572)
		(drill 0.2032)
		(layers "F.Cu" "B.Cu")
		(net "Net_102")
	)
	(segment
		(start 107.84713 -36.823142)
		(end 107.347258 -36.32327)
		(width 0.11938)
		(layer "F.Cu")
		(net "Net_103")
	)
	(via
		(at 107.347258 -36.32327)
		(size 0.4572)
		(drill 0.2032)
		(layers "F.Cu" "B.Cu")
		(net "Net_103")
	)
	(segment
		(start 114.847116 -37.82314)
		(end 115.346988 -37.323268)
		(width 0.11938)
		(layer "F.Cu")
		(net "Net_104")
	)
	(via
		(at 115.346988 -37.323268)
		(size 0.4572)
		(drill 0.2032)
		(layers "F.Cu" "B.Cu")
		(net "Net_104")
	)
	(segment
		(start 107.84713 -35.82289)
		(end 107.347258 -35.323018)
		(width 0.11938)
		(layer "F.Cu")
		(net "Net_105")
	)
	(via
		(at 107.347258 -35.323018)
		(size 0.4572)
		(drill 0.2032)
		(layers "F.Cu" "B.Cu")
		(net "Net_105")
	)
	(segment
		(start 113.847118 -37.82314)
		(end 114.34699 -37.323268)
		(width 0.11938)
		(layer "F.Cu")
		(net "Net_106")
	)
	(via
		(at 114.34699 -37.323268)
		(size 0.4572)
		(drill 0.2032)
		(layers "F.Cu" "B.Cu")
		(net "Net_106")
	)
	(segment
		(start 108.847128 -35.82289)
		(end 108.347256 -35.323018)
		(width 0.11938)
		(layer "F.Cu")
		(net "Net_107")
	)
	(via
		(at 108.347256 -35.323018)
		(size 0.4572)
		(drill 0.2032)
		(layers "F.Cu" "B.Cu")
		(net "Net_107")
	)
	(segment
		(start 116.847112 -37.82314)
		(end 117.346984 -37.323268)
		(width 0.11938)
		(layer "F.Cu")
		(net "Net_108")
	)
	(via
		(at 117.346984 -37.323268)
		(size 0.4572)
		(drill 0.2032)
		(layers "F.Cu" "B.Cu")
		(net "Net_108")
	)
	(segment
		(start 108.847128 -33.822894)
		(end 108.347256 -33.323022)
		(width 0.11938)
		(layer "F.Cu")
		(net "Net_109")
	)
	(via
		(at 108.347256 -33.323022)
		(size 0.4572)
		(drill 0.2032)
		(layers "F.Cu" "B.Cu")
		(net "Net_109")
	)
	(segment
		(start 116.847112 -38.823138)
		(end 117.346984 -38.323266)
		(width 0.11938)
		(layer "F.Cu")
		(net "Net_110")
	)
	(via
		(at 117.346984 -38.323266)
		(size 0.4572)
		(drill 0.2032)
		(layers "F.Cu" "B.Cu")
		(net "Net_110")
	)
	(segment
		(start 110.346998 -33.323022)
		(end 109.847126 -33.822894)
		(width 0.11938)
		(layer "F.Cu")
		(net "Net_111")
	)
	(via
		(at 110.346998 -33.323022)
		(size 0.4572)
		(drill 0.2032)
		(layers "F.Cu" "B.Cu")
		(net "Net_111")
	)
	(segment
		(start 115.847114 -37.82314)
		(end 116.346986 -37.323268)
		(width 0.11938)
		(layer "F.Cu")
		(net "Net_112")
	)
	(via
		(at 116.346986 -37.323268)
		(size 0.4572)
		(drill 0.2032)
		(layers "F.Cu" "B.Cu")
		(net "Net_112")
	)
	(segment
		(start 110.346998 -34.32302)
		(end 109.847126 -34.822892)
		(width 0.11938)
		(layer "F.Cu")
		(net "Net_113")
	)
	(via
		(at 110.346998 -34.32302)
		(size 0.4572)
		(drill 0.2032)
		(layers "F.Cu" "B.Cu")
		(net "Net_113")
	)
	(segment
		(start 114.847116 -38.823138)
		(end 115.346988 -38.323266)
		(width 0.11938)
		(layer "F.Cu")
		(net "Net_114")
	)
	(via
		(at 115.346988 -38.323266)
		(size 0.4572)
		(drill 0.2032)
		(layers "F.Cu" "B.Cu")
		(net "Net_114")
	)
	(segment
		(start 110.346998 -35.323018)
		(end 109.847126 -35.82289)
		(width 0.11938)
		(layer "F.Cu")
		(net "Net_115")
	)
	(via
		(at 110.346998 -35.323018)
		(size 0.4572)
		(drill 0.2032)
		(layers "F.Cu" "B.Cu")
		(net "Net_115")
	)
	(segment
		(start 106.847132 -38.823138)
		(end 106.34726 -38.323266)
		(width 0.11938)
		(layer "F.Cu")
		(net "Net_116")
	)
	(via
		(at 106.34726 -38.323266)
		(size 0.4572)
		(drill 0.2032)
		(layers "F.Cu" "B.Cu")
		(net "Net_116")
	)
	(segment
		(start 112.84712 -38.823138)
		(end 113.346992 -38.323266)
		(width 0.11938)
		(layer "F.Cu")
		(net "Net_117")
	)
	(via
		(at 113.346992 -38.323266)
		(size 0.4572)
		(drill 0.2032)
		(layers "F.Cu" "B.Cu")
		(net "Net_117")
	)
	(segment
		(start 107.84713 -38.823138)
		(end 107.347258 -38.323266)
		(width 0.11938)
		(layer "F.Cu")
		(net "Net_118")
	)
	(via
		(at 107.347258 -38.323266)
		(size 0.4572)
		(drill 0.2032)
		(layers "F.Cu" "B.Cu")
		(net "Net_118")
	)
	(segment
		(start 108.847128 -36.823142)
		(end 108.347256 -36.32327)
		(width 0.11938)
		(layer "F.Cu")
		(net "Net_119")
	)
	(via
		(at 108.347256 -36.32327)
		(size 0.4572)
		(drill 0.2032)
		(layers "F.Cu" "B.Cu")
		(net "Net_119")
	)
	(segment
		(start 108.847128 -37.82314)
		(end 108.347256 -37.323268)
		(width 0.11938)
		(layer "F.Cu")
		(net "Net_120")
	)
	(via
		(at 108.347256 -37.323268)
		(size 0.4572)
		(drill 0.2032)
		(layers "F.Cu" "B.Cu")
		(net "Net_120")
	)
	(segment
		(start 110.847124 -35.82289)
		(end 111.346996 -35.323018)
		(width 0.11938)
		(layer "F.Cu")
		(net "Net_121")
	)
	(via
		(at 111.346996 -35.323018)
		(size 0.4572)
		(drill 0.2032)
		(layers "F.Cu" "B.Cu")
		(net "Net_121")
	)
	(segment
		(start 110.847124 -36.823142)
		(end 111.346996 -36.32327)
		(width 0.11938)
		(layer "F.Cu")
		(net "Net_122")
	)
	(via
		(at 111.346996 -36.32327)
		(size 0.4572)
		(drill 0.2032)
		(layers "F.Cu" "B.Cu")
		(net "Net_122")
	)
	(segment
		(start 114.847116 -33.822894)
		(end 115.346988 -33.323022)
		(width 0.11938)
		(layer "F.Cu")
		(net "Net_123")
	)
	(via
		(at 115.346988 -33.323022)
		(size 0.4572)
		(drill 0.2032)
		(layers "F.Cu" "B.Cu")
		(net "Net_123")
	)
	(segment
		(start 114.268504 -33.401508)
		(end 113.847118 -33.822894)
		(width 0.11938)
		(layer "F.Cu")
		(net "Net_125")
	)
	(via
		(at 114.268504 -33.401508)
		(size 0.4572)
		(drill 0.2032)
		(layers "F.Cu" "B.Cu")
		(net "Net_125")
	)
	(segment
		(start 109.847126 -49.823116)
		(end 110.346998 -50.322988)
		(width 0.11938)
		(layer "F.Cu")
		(net "Net_127")
	)
	(via
		(at 110.346998 -50.322988)
		(size 0.4572)
		(drill 0.2032)
		(layers "F.Cu" "B.Cu")
		(net "Net_127")
	)
	(segment
		(start 116.292376 -34.37763)
		(end 115.847114 -34.822892)
		(width 0.11938)
		(layer "F.Cu")
		(net "Net_128")
	)
	(via
		(at 116.292376 -34.37763)
		(size 0.4572)
		(drill 0.2032)
		(layers "F.Cu" "B.Cu")
		(net "Net_128")
	)
	(segment
		(start 99.846892 -34.822892)
		(end 99.34702 -34.32302)
		(width 0.11938)
		(layer "F.Cu")
		(net "Net_129")
	)
	(via
		(at 99.34702 -34.32302)
		(size 0.4572)
		(drill 0.2032)
		(layers "F.Cu" "B.Cu")
		(net "Net_129")
	)
	(segment
		(start 114.847116 -34.822892)
		(end 115.346988 -34.32302)
		(width 0.11938)
		(layer "F.Cu")
		(net "Net_130")
	)
	(via
		(at 115.346988 -34.32302)
		(size 0.4572)
		(drill 0.2032)
		(layers "F.Cu" "B.Cu")
		(net "Net_130")
	)
	(segment
		(start 100.347018 -34.32302)
		(end 100.84689 -34.822892)
		(width 0.11938)
		(layer "F.Cu")
		(net "Net_131")
	)
	(via
		(at 100.347018 -34.32302)
		(size 0.4572)
		(drill 0.2032)
		(layers "F.Cu" "B.Cu")
		(net "Net_131")
	)
	(segment
		(start 113.268506 -34.401506)
		(end 112.84712 -34.822892)
		(width 0.11938)
		(layer "F.Cu")
		(net "Net_132")
	)
	(via
		(at 113.268506 -34.401506)
		(size 0.4572)
		(drill 0.2032)
		(layers "F.Cu" "B.Cu")
		(net "Net_132")
	)
	(segment
		(start 101.346 -33.321752)
		(end 101.847142 -33.822894)
		(width 0.11938)
		(layer "F.Cu")
		(net "Net_133")
	)
	(via
		(at 101.346 -33.321752)
		(size 0.4572)
		(drill 0.2032)
		(layers "F.Cu" "B.Cu")
		(net "Net_133")
	)
	(segment
		(start 112.84712 -35.82289)
		(end 113.346992 -35.323018)
		(width 0.11938)
		(layer "F.Cu")
		(net "Net_134")
	)
	(via
		(at 113.346992 -35.323018)
		(size 0.4572)
		(drill 0.2032)
		(layers "F.Cu" "B.Cu")
		(net "Net_134")
	)
	(segment
		(start 117.84711 -34.822892)
		(end 118.346982 -34.32302)
		(width 0.11938)
		(layer "F.Cu")
		(net "Net_136")
	)
	(via
		(at 118.346982 -34.32302)
		(size 0.4572)
		(drill 0.2032)
		(layers "F.Cu" "B.Cu")
		(net "Net_136")
	)
	(segment
		(start 101.346 -34.32175)
		(end 101.847142 -34.822892)
		(width 0.11938)
		(layer "F.Cu")
		(net "Net_137")
	)
	(via
		(at 101.346 -34.32175)
		(size 0.4572)
		(drill 0.2032)
		(layers "F.Cu" "B.Cu")
		(net "Net_137")
	)
	(segment
		(start 116.847112 -34.822892)
		(end 117.346984 -34.32302)
		(width 0.11938)
		(layer "F.Cu")
		(net "Net_138")
	)
	(via
		(at 117.346984 -34.32302)
		(size 0.4572)
		(drill 0.2032)
		(layers "F.Cu" "B.Cu")
		(net "Net_138")
	)
	(segment
		(start 118.847108 -46.823122)
		(end 119.34698 -47.322994)
		(width 0.11938)
		(layer "F.Cu")
		(net "Net_140")
	)
	(via
		(at 119.34698 -47.322994)
		(size 0.4572)
		(drill 0.2032)
		(layers "F.Cu" "B.Cu")
		(net "Net_140")
	)
	(segment
		(start 112.84712 -51.823112)
		(end 113.346992 -52.322984)
		(width 0.11938)
		(layer "F.Cu")
		(net "Net_141")
	)
	(via
		(at 113.346992 -52.322984)
		(size 0.4572)
		(drill 0.2032)
		(layers "F.Cu" "B.Cu")
		(net "Net_141")
	)
	(segment
		(start 103.345996 -33.321752)
		(end 103.847138 -33.822894)
		(width 0.11938)
		(layer "F.Cu")
		(net "Net_142")
	)
	(via
		(at 103.345996 -33.321752)
		(size 0.4572)
		(drill 0.2032)
		(layers "F.Cu" "B.Cu")
		(net "Net_142")
	)
	(segment
		(start 117.84711 -45.823124)
		(end 118.346982 -46.322996)
		(width 0.11938)
		(layer "F.Cu")
		(net "Net_143")
	)
	(via
		(at 118.346982 -46.322996)
		(size 0.4572)
		(drill 0.2032)
		(layers "F.Cu" "B.Cu")
		(net "Net_143")
	)
	(segment
		(start 111.847122 -51.823112)
		(end 112.346994 -52.322984)
		(width 0.11938)
		(layer "F.Cu")
		(net "Net_144")
	)
	(via
		(at 112.346994 -52.322984)
		(size 0.4572)
		(drill 0.2032)
		(layers "F.Cu" "B.Cu")
		(net "Net_144")
	)
	(segment
		(start 104.345994 -33.321752)
		(end 104.847136 -33.822894)
		(width 0.11938)
		(layer "F.Cu")
		(net "Net_145")
	)
	(via
		(at 104.345994 -33.321752)
		(size 0.4572)
		(drill 0.2032)
		(layers "F.Cu" "B.Cu")
		(net "Net_145")
	)
	(segment
		(start 115.847114 -35.82289)
		(end 116.346986 -35.323018)
		(width 0.11938)
		(layer "F.Cu")
		(net "Net_146")
	)
	(via
		(at 116.346986 -35.323018)
		(size 0.4572)
		(drill 0.2032)
		(layers "F.Cu" "B.Cu")
		(net "Net_146")
	)
	(segment
		(start 102.84714 -35.82289)
		(end 102.347268 -35.323018)
		(width 0.11938)
		(layer "F.Cu")
		(net "Net_147")
	)
	(via
		(at 102.347268 -35.323018)
		(size 0.4572)
		(drill 0.2032)
		(layers "F.Cu" "B.Cu")
		(net "Net_147")
	)
	(segment
		(start 114.847116 -35.82289)
		(end 115.346988 -35.323018)
		(width 0.11938)
		(layer "F.Cu")
		(net "Net_148")
	)
	(via
		(at 115.346988 -35.323018)
		(size 0.4572)
		(drill 0.2032)
		(layers "F.Cu" "B.Cu")
		(net "Net_148")
	)
	(segment
		(start 103.847138 -35.82289)
		(end 103.347266 -35.323018)
		(width 0.11938)
		(layer "F.Cu")
		(net "Net_149")
	)
	(via
		(at 103.347266 -35.323018)
		(size 0.4572)
		(drill 0.2032)
		(layers "F.Cu" "B.Cu")
		(net "Net_149")
	)
	(segment
		(start 119.847106 -44.823126)
		(end 120.346978 -45.322998)
		(width 0.11938)
		(layer "F.Cu")
		(net "Net_150")
	)
	(via
		(at 120.346978 -45.322998)
		(size 0.4572)
		(drill 0.2032)
		(layers "F.Cu" "B.Cu")
		(net "Net_150")
	)
	(segment
		(start 119.847106 -33.822894)
		(end 120.346978 -33.323022)
		(width 0.11938)
		(layer "F.Cu")
		(net "Net_151")
	)
	(via
		(at 120.346978 -33.323022)
		(size 0.4572)
		(drill 0.2032)
		(layers "F.Cu" "B.Cu")
		(net "Net_151")
	)
	(segment
		(start 106.847132 -33.822894)
		(end 106.34726 -33.323022)
		(width 0.11938)
		(layer "F.Cu")
		(net "Net_152")
	)
	(via
		(at 106.34726 -33.323022)
		(size 0.4572)
		(drill 0.2032)
		(layers "F.Cu" "B.Cu")
		(net "Net_152")
	)
	(segment
		(start 119.847106 -43.823128)
		(end 120.346978 -43.323256)
		(width 0.11938)
		(layer "F.Cu")
		(net "Net_153")
	)
	(via
		(at 120.346978 -43.323256)
		(size 0.4572)
		(drill 0.2032)
		(layers "F.Cu" "B.Cu")
		(net "Net_153")
	)
	(segment
		(start 118.847108 -33.822894)
		(end 119.34698 -33.323022)
		(width 0.11938)
		(layer "F.Cu")
		(net "Net_154")
	)
	(via
		(at 119.34698 -33.323022)
		(size 0.4572)
		(drill 0.2032)
		(layers "F.Cu" "B.Cu")
		(net "Net_154")
	)
	(segment
		(start 107.84713 -33.822894)
		(end 107.347258 -33.323022)
		(width 0.11938)
		(layer "F.Cu")
		(net "Net_155")
	)
	(via
		(at 107.347258 -33.323022)
		(size 0.4572)
		(drill 0.2032)
		(layers "F.Cu" "B.Cu")
		(net "Net_155")
	)
	(segment
		(start 104.847136 -34.822892)
		(end 104.347264 -34.32302)
		(width 0.11938)
		(layer "F.Cu")
		(net "Net_156")
	)
	(via
		(at 104.347264 -34.32302)
		(size 0.4572)
		(drill 0.2032)
		(layers "F.Cu" "B.Cu")
		(net "Net_156")
	)
	(segment
		(start 105.847134 -34.822892)
		(end 105.347262 -34.32302)
		(width 0.11938)
		(layer "F.Cu")
		(net "Net_157")
	)
	(via
		(at 105.347262 -34.32302)
		(size 0.4572)
		(drill 0.2032)
		(layers "F.Cu" "B.Cu")
		(net "Net_157")
	)
	(segment
		(start 118.847108 -35.82289)
		(end 119.34698 -35.323018)
		(width 0.11938)
		(layer "F.Cu")
		(net "Net_158")
	)
	(via
		(at 119.34698 -35.323018)
		(size 0.4572)
		(drill 0.2032)
		(layers "F.Cu" "B.Cu")
		(net "Net_158")
	)
	(segment
		(start 106.847132 -34.822892)
		(end 106.34726 -34.32302)
		(width 0.11938)
		(layer "F.Cu")
		(net "Net_159")
	)
	(via
		(at 106.34726 -34.32302)
		(size 0.4572)
		(drill 0.2032)
		(layers "F.Cu" "B.Cu")
		(net "Net_159")
	)
	(segment
		(start 117.84711 -35.82289)
		(end 118.346982 -35.323018)
		(width 0.11938)
		(layer "F.Cu")
		(net "Net_160")
	)
	(via
		(at 118.346982 -35.323018)
		(size 0.4572)
		(drill 0.2032)
		(layers "F.Cu" "B.Cu")
		(net "Net_160")
	)
	(segment
		(start 107.84713 -34.822892)
		(end 107.347258 -34.32302)
		(width 0.11938)
		(layer "F.Cu")
		(net "Net_161")
	)
	(via
		(at 107.347258 -34.32302)
		(size 0.4572)
		(drill 0.2032)
		(layers "F.Cu" "B.Cu")
		(net "Net_161")
	)
	(segment
		(start 119.847106 -54.823106)
		(end 120.346978 -55.322978)
		(width 0.11938)
		(layer "F.Cu")
		(net "Net_162")
	)
	(via
		(at 120.346978 -55.322978)
		(size 0.4572)
		(drill 0.2032)
		(layers "F.Cu" "B.Cu")
		(net "Net_162")
	)
	(segment
		(start 119.847106 -53.823108)
		(end 120.346978 -54.32298)
		(width 0.11938)
		(layer "F.Cu")
		(net "Net_163")
	)
	(via
		(at 120.346978 -54.32298)
		(size 0.4572)
		(drill 0.2032)
		(layers "F.Cu" "B.Cu")
		(net "Net_163")
	)
	(segment
		(start 115.847114 -52.82311)
		(end 116.346986 -53.322982)
		(width 0.11938)
		(layer "F.Cu")
		(net "Net_164")
	)
	(via
		(at 116.346986 -53.322982)
		(size 0.4572)
		(drill 0.2032)
		(layers "F.Cu" "B.Cu")
		(net "Net_164")
	)
	(segment
		(start 114.847116 -52.82311)
		(end 115.346988 -53.322982)
		(width 0.11938)
		(layer "F.Cu")
		(net "Net_165")
	)
	(via
		(at 115.346988 -53.322982)
		(size 0.4572)
		(drill 0.2032)
		(layers "F.Cu" "B.Cu")
		(net "Net_165")
	)
	(segment
		(start 115.847114 -46.823122)
		(end 116.346986 -47.322994)
		(width 0.11938)
		(layer "F.Cu")
		(net "Net_166")
	)
	(via
		(at 116.346986 -47.322994)
		(size 0.4572)
		(drill 0.2032)
		(layers "F.Cu" "B.Cu")
		(net "Net_166")
	)
	(segment
		(start 117.84711 -51.823112)
		(end 118.346982 -52.322984)
		(width 0.11938)
		(layer "F.Cu")
		(net "Net_167")
	)
	(via
		(at 118.346982 -52.322984)
		(size 0.4572)
		(drill 0.2032)
		(layers "F.Cu" "B.Cu")
		(net "Net_167")
	)
	(segment
		(start 115.847114 -51.823112)
		(end 116.346986 -52.322984)
		(width 0.11938)
		(layer "F.Cu")
		(net "Net_168")
	)
	(via
		(at 116.346986 -52.322984)
		(size 0.4572)
		(drill 0.2032)
		(layers "F.Cu" "B.Cu")
		(net "Net_168")
	)
	(segment
		(start 114.847116 -47.82312)
		(end 115.346988 -48.322992)
		(width 0.11938)
		(layer "F.Cu")
		(net "Net_169")
	)
	(via
		(at 115.346988 -48.322992)
		(size 0.4572)
		(drill 0.2032)
		(layers "F.Cu" "B.Cu")
		(net "Net_169")
	)
	(segment
		(start 115.847114 -50.823114)
		(end 116.346986 -51.322986)
		(width 0.11938)
		(layer "F.Cu")
		(net "Net_170")
	)
	(via
		(at 116.346986 -51.322986)
		(size 0.4572)
		(drill 0.2032)
		(layers "F.Cu" "B.Cu")
		(net "Net_170")
	)
	(segment
		(start 107.84713 -49.823116)
		(end 107.347258 -50.322988)
		(width 0.11938)
		(layer "F.Cu")
		(net "Net_171")
	)
	(via
		(at 107.347258 -50.322988)
		(size 0.4572)
		(drill 0.2032)
		(layers "F.Cu" "B.Cu")
		(net "Net_171")
	)
	(segment
		(start 108.847128 -48.823118)
		(end 108.347256 -49.32299)
		(width 0.11938)
		(layer "F.Cu")
		(net "Net_172")
	)
	(via
		(at 108.347256 -49.32299)
		(size 0.4572)
		(drill 0.2032)
		(layers "F.Cu" "B.Cu")
		(net "Net_172")
	)
	(segment
		(start 104.847136 -49.823116)
		(end 104.347264 -50.322988)
		(width 0.11938)
		(layer "F.Cu")
		(net "Net_173")
	)
	(via
		(at 104.347264 -50.322988)
		(size 0.4572)
		(drill 0.2032)
		(layers "F.Cu" "B.Cu")
		(net "Net_173")
	)
	(segment
		(start 105.847134 -49.823116)
		(end 105.347262 -50.322988)
		(width 0.11938)
		(layer "F.Cu")
		(net "Net_174")
	)
	(via
		(at 105.347262 -50.322988)
		(size 0.4572)
		(drill 0.2032)
		(layers "F.Cu" "B.Cu")
		(net "Net_174")
	)
	(segment
		(start 116.847112 -53.823108)
		(end 117.346984 -54.32298)
		(width 0.11938)
		(layer "F.Cu")
		(net "Net_175")
	)
	(via
		(at 117.346984 -54.32298)
		(size 0.4572)
		(drill 0.2032)
		(layers "F.Cu" "B.Cu")
		(net "Net_175")
	)
	(segment
		(start 118.847108 -43.823128)
		(end 119.34698 -43.323256)
		(width 0.11938)
		(layer "F.Cu")
		(net "Net_176")
	)
	(via
		(at 119.34698 -43.323256)
		(size 0.4572)
		(drill 0.2032)
		(layers "F.Cu" "B.Cu")
		(net "Net_176")
	)
	(segment
		(start 119.34698 -42.323258)
		(end 118.847108 -42.82313)
		(width 0.11938)
		(layer "F.Cu")
		(net "Net_177")
	)
	(via
		(at 119.34698 -42.323258)
		(size 0.4572)
		(drill 0.2032)
		(layers "F.Cu" "B.Cu")
		(net "Net_177")
	)
	(segment
		(start 18.288 -89.0651)
		(end 18.288 -87.9602)
		(width 0.381)
		(layer "F.Cu")
		(net "XP5R0V_FT4232")
	)
	(via
		(at 39.624 -80.391)
		(size 0.508)
		(drill 0.254)
		(layers "F.Cu" "B.Cu")
		(net "XP5R0V_FT4232")
	)
	(via
		(at 39.624 -81.407)
		(size 0.508)
		(drill 0.254)
		(layers "F.Cu" "B.Cu")
		(net "XP5R0V_FT4232")
	)
	(via
		(at 36.83 -91.186)
		(size 0.508)
		(drill 0.254)
		(layers "F.Cu" "B.Cu")
		(net "XP5R0V_FT4232")
	)
	(via
		(at 18.288 -87.9602)
		(size 0.508)
		(drill 0.254)
		(layers "F.Cu" "B.Cu")
		(net "XP5R0V_FT4232")
	)
	(segment
		(start 36.83 -92.329)
		(end 35.7505 -93.4085)
		(width 0.381)
		(layer "B.Cu")
		(net "XP5R0V_FT4232")
	)
	(segment
		(start 29.2354 -94.7674)
		(end 26.797 -94.7674)
		(width 0.381)
		(layer "B.Cu")
		(net "XP5R0V_FT4232")
	)
	(segment
		(start 31.623 -94.615)
		(end 31.115 -95.123)
		(width 0.381)
		(layer "B.Cu")
		(net "XP5R0V_FT4232")
	)
	(segment
		(start 31.115 -95.123)
		(end 29.591 -95.123)
		(width 0.381)
		(layer "B.Cu")
		(net "XP5R0V_FT4232")
	)
	(segment
		(start 35.7505 -93.4085)
		(end 32.47644 -93.4085)
		(width 0.381)
		(layer "B.Cu")
		(net "XP5R0V_FT4232")
	)
	(segment
		(start 32.47644 -93.4085)
		(end 31.623 -94.26194)
		(width 0.381)
		(layer "B.Cu")
		(net "XP5R0V_FT4232")
	)
	(segment
		(start 36.83 -91.186)
		(end 36.83 -92.329)
		(width 0.381)
		(layer "B.Cu")
		(net "XP5R0V_FT4232")
	)
	(segment
		(start 29.591 -95.123)
		(end 29.2354 -94.7674)
		(width 0.381)
		(layer "B.Cu")
		(net "XP5R0V_FT4232")
	)
	(segment
		(start 17.78 -87.0204)
		(end 17.78 -87.4522)
		(width 0.381)
		(layer "B.Cu")
		(net "XP5R0V_FT4232")
	)
	(segment
		(start 17.78 -87.4522)
		(end 18.288 -87.9602)
		(width 0.381)
		(layer "B.Cu")
		(net "XP5R0V_FT4232")
	)
	(segment
		(start 31.623 -94.26194)
		(end 31.623 -94.615)
		(width 0.381)
		(layer "B.Cu")
		(net "XP5R0V_FT4232")
	)
	(segment
		(start 28.956 -89.408)
		(end 28.702 -89.408)
		(width 0.254)
		(layer "F.Cu")
		(net "XP3R3V_VPLL")
	)
	(segment
		(start 28.702 -89.408)
		(end 28.274264 -89.835736)
		(width 0.254)
		(layer "F.Cu")
		(net "XP3R3V_VPLL")
	)
	(segment
		(start 28.274264 -89.835736)
		(end 28.274264 -90.8812)
		(width 0.254)
		(layer "F.Cu")
		(net "XP3R3V_VPLL")
	)
	(via
		(at 28.956 -89.408)
		(size 0.508)
		(drill 0.254)
		(layers "F.Cu" "B.Cu")
		(net "XP3R3V_VPLL")
	)
	(segment
		(start 31.623 -89.408)
		(end 31.115254 -89.408)
		(width 0.254)
		(layer "F.Cu")
		(net "XP3R3V_VPHY")
	)
	(segment
		(start 31.115254 -89.408)
		(end 30.774132 -89.749122)
		(width 0.254)
		(layer "F.Cu")
		(net "XP3R3V_VPHY")
	)
	(segment
		(start 30.774132 -89.749122)
		(end 30.774132 -90.8812)
		(width 0.254)
		(layer "F.Cu")
		(net "XP3R3V_VPHY")
	)
	(via
		(at 31.623 -89.408)
		(size 0.508)
		(drill 0.254)
		(layers "F.Cu" "B.Cu")
		(net "XP3R3V_VPHY")
	)
	(segment
		(start 32.131 -90.5256)
		(end 32.131 -90.5002)
		(width 0.381)
		(layer "B.Cu")
		(net "XP3R3V_VPHY")
	)
	(segment
		(start 32.512 -90.1192)
		(end 33.528 -90.1192)
		(width 0.381)
		(layer "B.Cu")
		(net "XP3R3V_VPHY")
	)
	(segment
		(start 30.988 -90.5256)
		(end 32.131 -90.5256)
		(width 0.381)
		(layer "B.Cu")
		(net "XP3R3V_VPHY")
	)
	(segment
		(start 30.988 -90.043)
		(end 30.988 -90.5256)
		(width 0.381)
		(layer "B.Cu")
		(net "XP3R3V_VPHY")
	)
	(segment
		(start 32.131 -90.5002)
		(end 32.512 -90.1192)
		(width 0.381)
		(layer "B.Cu")
		(net "XP3R3V_VPHY")
	)
	(segment
		(start 31.623 -89.408)
		(end 30.988 -90.043)
		(width 0.381)
		(layer "B.Cu")
		(net "XP3R3V_VPHY")
	)
	(via
		(at 119.507 -100.33)
		(size 0.4572)
		(drill 0.2032)
		(layers "F.Cu" "B.Cu")
		(net "XP3R3V_GPS")
	)
	(via
		(at 119.507 -99.314)
		(size 0.508)
		(drill 0.254)
		(layers "F.Cu" "B.Cu")
		(net "XP3R3V_GPS")
	)
	(segment
		(start 121.3612 -90.1954)
		(end 121.3612 -97.4598)
		(width 0.254)
		(layer "B.Cu")
		(net "XP3R3V_GPS")
	)
	(segment
		(start 121.3612 -97.4598)
		(end 119.507 -99.314)
		(width 0.254)
		(layer "B.Cu")
		(net "XP3R3V_GPS")
	)
	(segment
		(start 26.797 -94.7674)
		(end 26.543 -95.0214)
		(width 0.11938)
		(layer "F.Cu")
		(net "XP3R3V_FT_PG")
	)
	(segment
		(start 40.266874 -76.080874)
		(end 39.7764 -75.5904)
		(width 0.11938)
		(layer "F.Cu")
		(net "XP3R3V_FT_PG")
	)
	(segment
		(start 39.7764 -75.5904)
		(end 39.7764 -74.93)
		(width 0.11938)
		(layer "F.Cu")
		(net "XP3R3V_FT_PG")
	)
	(segment
		(start 26.543 -95.0214)
		(end 26.543 -95.758)
		(width 0.11938)
		(layer "F.Cu")
		(net "XP3R3V_FT_PG")
	)
	(segment
		(start 41.156382 -76.080874)
		(end 40.266874 -76.080874)
		(width 0.11938)
		(layer "F.Cu")
		(net "XP3R3V_FT_PG")
	)
	(via
		(at 39.7764 -74.93)
		(size 0.508)
		(drill 0.254)
		(layers "F.Cu" "B.Cu")
		(net "XP3R3V_FT_PG")
	)
	(via
		(at 26.543 -95.758)
		(size 0.508)
		(drill 0.254)
		(layers "F.Cu" "B.Cu")
		(net "XP3R3V_FT_PG")
	)
	(segment
		(start 34.671 -95.25)
		(end 36.068 -95.25)
		(width 0.11938)
		(layer "B.Cu")
		(net "XP3R3V_FT_PG")
	)
	(segment
		(start 36.957 -93.472)
		(end 37.211 -93.472)
		(width 0.11938)
		(layer "B.Cu")
		(net "XP3R3V_FT_PG")
	)
	(segment
		(start 37.211 -93.472)
		(end 37.592 -93.091)
		(width 0.11938)
		(layer "B.Cu")
		(net "XP3R3V_FT_PG")
	)
	(segment
		(start 36.068 -95.25)
		(end 36.449 -94.869)
		(width 0.11938)
		(layer "B.Cu")
		(net "XP3R3V_FT_PG")
	)
	(segment
		(start 39.624 -85.471)
		(end 40.767 -84.328)
		(width 0.11938)
		(layer "B.Cu")
		(net "XP3R3V_FT_PG")
	)
	(segment
		(start 37.592 -93.091)
		(end 38.608 -93.091)
		(width 0.11938)
		(layer "B.Cu")
		(net "XP3R3V_FT_PG")
	)
	(segment
		(start 40.767 -84.328)
		(end 40.767 -75.9206)
		(width 0.11938)
		(layer "B.Cu")
		(net "XP3R3V_FT_PG")
	)
	(segment
		(start 39.624 -92.075)
		(end 39.624 -85.471)
		(width 0.11938)
		(layer "B.Cu")
		(net "XP3R3V_FT_PG")
	)
	(segment
		(start 36.449 -93.98)
		(end 36.957 -93.472)
		(width 0.11938)
		(layer "B.Cu")
		(net "XP3R3V_FT_PG")
	)
	(segment
		(start 34.23031 -94.80931)
		(end 34.671 -95.25)
		(width 0.11938)
		(layer "B.Cu")
		(net "XP3R3V_FT_PG")
	)
	(segment
		(start 32.403796 -95.69831)
		(end 33.292796 -94.80931)
		(width 0.11938)
		(layer "B.Cu")
		(net "XP3R3V_FT_PG")
	)
	(segment
		(start 26.543 -95.758)
		(end 26.60269 -95.69831)
		(width 0.11938)
		(layer "B.Cu")
		(net "XP3R3V_FT_PG")
	)
	(segment
		(start 36.449 -94.869)
		(end 36.449 -93.98)
		(width 0.11938)
		(layer "B.Cu")
		(net "XP3R3V_FT_PG")
	)
	(segment
		(start 26.60269 -95.69831)
		(end 32.403796 -95.69831)
		(width 0.11938)
		(layer "B.Cu")
		(net "XP3R3V_FT_PG")
	)
	(segment
		(start 40.767 -75.9206)
		(end 39.7764 -74.93)
		(width 0.11938)
		(layer "B.Cu")
		(net "XP3R3V_FT_PG")
	)
	(segment
		(start 38.608 -93.091)
		(end 39.624 -92.075)
		(width 0.11938)
		(layer "B.Cu")
		(net "XP3R3V_FT_PG")
	)
	(segment
		(start 33.292796 -94.80931)
		(end 34.23031 -94.80931)
		(width 0.11938)
		(layer "B.Cu")
		(net "XP3R3V_FT_PG")
	)
	(segment
		(start 22.7076 -87.314532)
		(end 23.941532 -87.314532)
		(width 0.254)
		(layer "F.Cu")
		(net "XP3R3V_FT4232")
	)
	(segment
		(start 29.845 -74.6506)
		(end 29.845 -73.66)
		(width 0.381)
		(layer "F.Cu")
		(net "XP3R3V_FT4232")
	)
	(segment
		(start 22.7076 -81.81467)
		(end 23.97633 -81.81467)
		(width 0.254)
		(layer "F.Cu")
		(net "XP3R3V_FT4232")
	)
	(segment
		(start 35.20313 -81.81467)
		(end 35.7378 -81.28)
		(width 0.254)
		(layer "F.Cu")
		(net "XP3R3V_FT4232")
	)
	(segment
		(start 34.3408 -81.81467)
		(end 35.20313 -81.81467)
		(width 0.254)
		(layer "F.Cu")
		(net "XP3R3V_FT4232")
	)
	(segment
		(start 29.274262 -79.248)
		(end 29.274262 -77.786738)
		(width 0.254)
		(layer "F.Cu")
		(net "XP3R3V_FT4232")
	)
	(segment
		(start 26.035 -75.7174)
		(end 26.035 -76.708)
		(width 0.381)
		(layer "F.Cu")
		(net "XP3R3V_FT4232")
	)
	(segment
		(start 23.97633 -81.81467)
		(end 24.13 -81.661)
		(width 0.254)
		(layer "F.Cu")
		(net "XP3R3V_FT4232")
	)
	(segment
		(start 34.3408 -84.814664)
		(end 36.046664 -84.814664)
		(width 0.254)
		(layer "F.Cu")
		(net "XP3R3V_FT4232")
	)
	(segment
		(start 23.941532 -87.314532)
		(end 24.13 -87.503)
		(width 0.254)
		(layer "F.Cu")
		(net "XP3R3V_FT4232")
	)
	(via
		(at 55.6768 -86.0552)
		(size 0.508)
		(drill 0.254)
		(layers "F.Cu" "B.Cu")
		(net "XP3R3V_FT4232")
	)
	(via
		(at 24.003 -79.375)
		(size 0.508)
		(drill 0.254)
		(layers "F.Cu" "B.Cu")
		(net "XP3R3V_FT4232")
	)
	(via
		(at 38.481 -90.932)
		(size 0.508)
		(drill 0.254)
		(layers "F.Cu" "B.Cu")
		(net "XP3R3V_FT4232")
	)
	(via
		(at 156.083 -102.489)
		(size 0.508)
		(drill 0.254)
		(layers "F.Cu" "B.Cu")
		(net "XP3R3V_FT4232")
	)
	(via
		(at 36.046664 -84.814664)
		(size 0.508)
		(drill 0.254)
		(layers "F.Cu" "B.Cu")
		(net "XP3R3V_FT4232")
	)
	(via
		(at 26.035 -76.708)
		(size 0.508)
		(drill 0.254)
		(layers "F.Cu" "B.Cu")
		(net "XP3R3V_FT4232")
	)
	(via
		(at 42.3418 -87.3252)
		(size 0.508)
		(drill 0.254)
		(layers "F.Cu" "B.Cu")
		(net "XP3R3V_FT4232")
	)
	(via
		(at 37.973 -79.002636)
		(size 0.508)
		(drill 0.254)
		(layers "F.Cu" "B.Cu")
		(net "XP3R3V_FT4232")
	)
	(via
		(at 24.13 -87.503)
		(size 0.508)
		(drill 0.254)
		(layers "F.Cu" "B.Cu")
		(net "XP3R3V_FT4232")
	)
	(via
		(at 55.626 -88.5952)
		(size 0.508)
		(drill 0.254)
		(layers "F.Cu" "B.Cu")
		(net "XP3R3V_FT4232")
	)
	(via
		(at 35.7378 -81.28)
		(size 0.508)
		(drill 0.254)
		(layers "F.Cu" "B.Cu")
		(net "XP3R3V_FT4232")
	)
	(via
		(at 24.13 -81.661)
		(size 0.508)
		(drill 0.254)
		(layers "F.Cu" "B.Cu")
		(net "XP3R3V_FT4232")
	)
	(via
		(at 40.4114 -90.0684)
		(size 0.508)
		(drill 0.254)
		(layers "F.Cu" "B.Cu")
		(net "XP3R3V_FT4232")
	)
	(via
		(at 34.798 -92.456)
		(size 0.508)
		(drill 0.254)
		(layers "F.Cu" "B.Cu")
		(net "XP3R3V_FT4232")
	)
	(via
		(at 28.702 -87.503)
		(size 0.508)
		(drill 0.254)
		(layers "F.Cu" "B.Cu")
		(net "XP3R3V_FT4232")
	)
	(via
		(at 29.274262 -77.786738)
		(size 0.508)
		(drill 0.254)
		(layers "F.Cu" "B.Cu")
		(net "XP3R3V_FT4232")
	)
	(via
		(at 29.845 -73.66)
		(size 0.508)
		(drill 0.254)
		(layers "F.Cu" "B.Cu")
		(net "XP3R3V_FT4232")
	)
	(segment
		(start 34.925 -92.329)
		(end 34.925 -91.4654)
		(width 0.381)
		(layer "B.Cu")
		(net "XP3R3V_FT4232")
	)
	(segment
		(start 23.1394 -87.757)
		(end 23.876 -87.757)
		(width 0.381)
		(layer "B.Cu")
		(net "XP3R3V_FT4232")
	)
	(segment
		(start 22.098 -81.28)
		(end 24.003 -79.375)
		(width 0.4572)
		(layer "B.Cu")
		(net "XP3R3V_FT4232")
	)
	(segment
		(start 54.61 -89.0016)
		(end 54.61 -90.0684)
		(width 0.381)
		(layer "B.Cu")
		(net "XP3R3V_FT4232")
	)
	(segment
		(start 18.9484 -81.28)
		(end 18.9484 -82.423)
		(width 0.4572)
		(layer "B.Cu")
		(net "XP3R3V_FT4232")
	)
	(segment
		(start 44.4119 -87.3252)
		(end 42.3418 -87.3252)
		(width 0.381)
		(layer "B.Cu")
		(net "XP3R3V_FT4232")
	)
	(segment
		(start 41.6052 -89.8652)
		(end 41.402 -90.0684)
		(width 0.381)
		(layer "B.Cu")
		(net "XP3R3V_FT4232")
	)
	(segment
		(start 55.626 -88.5952)
		(end 54.8132 -88.5952)
		(width 0.381)
		(layer "B.Cu")
		(net "XP3R3V_FT4232")
	)
	(segment
		(start 54.5084 -85.344)
		(end 54.9656 -85.344)
		(width 0.381)
		(layer "B.Cu")
		(net "XP3R3V_FT4232")
	)
	(segment
		(start 35.0774 -82.169)
		(end 35.7378 -81.5086)
		(width 0.381)
		(layer "B.Cu")
		(net "XP3R3V_FT4232")
	)
	(segment
		(start 54.5084 -88.9)
		(end 54.61 -89.0016)
		(width 0.381)
		(layer "B.Cu")
		(net "XP3R3V_FT4232")
	)
	(segment
		(start 44.4119 -89.8652)
		(end 41.6052 -89.8652)
		(width 0.381)
		(layer "B.Cu")
		(net "XP3R3V_FT4232")
	)
	(segment
		(start 54.9656 -85.344)
		(end 55.6768 -86.0552)
		(width 0.381)
		(layer "B.Cu")
		(net "XP3R3V_FT4232")
	)
	(segment
		(start 33.5534 -91.4654)
		(end 34.925 -91.4654)
		(width 0.381)
		(layer "B.Cu")
		(net "XP3R3V_FT4232")
	)
	(segment
		(start 54.8132 -88.5952)
		(end 54.5084 -88.9)
		(width 0.381)
		(layer "B.Cu")
		(net "XP3R3V_FT4232")
	)
	(segment
		(start 156.083 -103.9876)
		(end 156.083 -102.489)
		(width 0.381)
		(layer "B.Cu")
		(net "XP3R3V_FT4232")
	)
	(segment
		(start 35.7378 -81.5086)
		(end 35.7378 -81.28)
		(width 0.381)
		(layer "B.Cu")
		(net "XP3R3V_FT4232")
	)
	(segment
		(start 23.876 -87.757)
		(end 24.13 -87.503)
		(width 0.381)
		(layer "B.Cu")
		(net "XP3R3V_FT4232")
	)
	(segment
		(start 41.402 -90.0684)
		(end 40.4114 -90.0684)
		(width 0.381)
		(layer "B.Cu")
		(net "XP3R3V_FT4232")
	)
	(segment
		(start 54.61 -90.0684)
		(end 54.5084 -90.17)
		(width 0.381)
		(layer "B.Cu")
		(net "XP3R3V_FT4232")
	)
	(segment
		(start 33.528 -91.4908)
		(end 33.5534 -91.4654)
		(width 0.381)
		(layer "B.Cu")
		(net "XP3R3V_FT4232")
	)
	(segment
		(start 34.798 -92.456)
		(end 34.925 -92.329)
		(width 0.381)
		(layer "B.Cu")
		(net "XP3R3V_FT4232")
	)
	(segment
		(start 18.9484 -81.28)
		(end 22.098 -81.28)
		(width 0.4572)
		(layer "B.Cu")
		(net "XP3R3V_FT4232")
	)
	(segment
		(start 55.626 -88.5952)
		(end 55.626 -86.106)
		(width 0.381)
		(layer "In7.Cu")
		(net "XP3R3V_FT4232")
	)
	(segment
		(start 154.305 -107.696)
		(end 154.305 -106.68)
		(width 0.381)
		(layer "In7.Cu")
		(net "XP3R3V_FT4232")
	)
	(segment
		(start 55.626 -86.106)
		(end 55.6768 -86.0552)
		(width 0.381)
		(layer "In7.Cu")
		(net "XP3R3V_FT4232")
	)
	(segment
		(start 71.374 -96.774)
		(end 71.374 -104.902)
		(width 0.381)
		(layer "In7.Cu")
		(net "XP3R3V_FT4232")
	)
	(segment
		(start 154.305 -106.68)
		(end 156.083 -104.902)
		(width 0.381)
		(layer "In7.Cu")
		(net "XP3R3V_FT4232")
	)
	(segment
		(start 40.259 -92.71)
		(end 43.91406 -92.71)
		(width 0.381)
		(layer "In7.Cu")
		(net "XP3R3V_FT4232")
	)
	(segment
		(start 38.481 -90.932)
		(end 40.259 -92.71)
		(width 0.381)
		(layer "In7.Cu")
		(net "XP3R3V_FT4232")
	)
	(segment
		(start 45.69206 -94.488)
		(end 69.088 -94.488)
		(width 0.381)
		(layer "In7.Cu")
		(net "XP3R3V_FT4232")
	)
	(segment
		(start 71.374 -104.902)
		(end 75.819 -109.347)
		(width 0.381)
		(layer "In7.Cu")
		(net "XP3R3V_FT4232")
	)
	(segment
		(start 152.654 -109.347)
		(end 154.305 -107.696)
		(width 0.381)
		(layer "In7.Cu")
		(net "XP3R3V_FT4232")
	)
	(segment
		(start 69.088 -94.488)
		(end 71.374 -96.774)
		(width 0.381)
		(layer "In7.Cu")
		(net "XP3R3V_FT4232")
	)
	(segment
		(start 75.819 -109.347)
		(end 152.654 -109.347)
		(width 0.381)
		(layer "In7.Cu")
		(net "XP3R3V_FT4232")
	)
	(segment
		(start 156.083 -104.902)
		(end 156.083 -102.489)
		(width 0.381)
		(layer "In7.Cu")
		(net "XP3R3V_FT4232")
	)
	(segment
		(start 43.91406 -92.71)
		(end 45.69206 -94.488)
		(width 0.381)
		(layer "In7.Cu")
		(net "XP3R3V_FT4232")
	)
	(segment
		(start 146.3548 -88.0618)
		(end 146.3548 -86.995)
		(width 0.381)
		(layer "F.Cu")
		(net "XP12R0V_IN")
	)
	(via
		(at 140.208 -93.369638)
		(size 0.4572)
		(drill 0.2032)
		(layers "F.Cu" "B.Cu")
		(net "XP12R0V_IN")
	)
	(via
		(at 141.0208 -95.169736)
		(size 0.4572)
		(drill 0.2032)
		(layers "F.Cu" "B.Cu")
		(net "XP12R0V_IN")
	)
	(via
		(at 21.6916 -101.3968)
		(size 0.508)
		(drill 0.254)
		(layers "F.Cu" "B.Cu")
		(net "XP12R0V_IN")
	)
	(via
		(at 19.304 -103.9368)
		(size 0.508)
		(drill 0.254)
		(layers "F.Cu" "B.Cu")
		(net "XP12R0V_IN")
	)
	(via
		(at 16.3322 -103.5304)
		(size 0.508)
		(drill 0.254)
		(layers "F.Cu" "B.Cu")
		(net "XP12R0V_IN")
	)
	(via
		(at 142.875 -82.8294)
		(size 0.508)
		(drill 0.254)
		(layers "F.Cu" "B.Cu")
		(net "XP12R0V_IN")
	)
	(via
		(at 23.5712 -100.6094)
		(size 0.508)
		(drill 0.254)
		(layers "F.Cu" "B.Cu")
		(net "XP12R0V_IN")
	)
	(via
		(at 140.208 -96.069658)
		(size 0.4572)
		(drill 0.2032)
		(layers "F.Cu" "B.Cu")
		(net "XP12R0V_IN")
	)
	(via
		(at 146.3548 -86.995)
		(size 0.4572)
		(drill 0.2032)
		(layers "F.Cu" "B.Cu")
		(net "XP12R0V_IN")
	)
	(via
		(at 19.304 -100.1268)
		(size 0.508)
		(drill 0.254)
		(layers "F.Cu" "B.Cu")
		(net "XP12R0V_IN")
	)
	(via
		(at 135.1534 -101.346)
		(size 0.508)
		(drill 0.254)
		(layers "F.Cu" "B.Cu")
		(net "XP12R0V_IN")
	)
	(via
		(at 15.3162 -101.8794)
		(size 0.508)
		(drill 0.254)
		(layers "F.Cu" "B.Cu")
		(net "XP12R0V_IN")
	)
	(via
		(at 24.5872 -103.6574)
		(size 0.508)
		(drill 0.254)
		(layers "F.Cu" "B.Cu")
		(net "XP12R0V_IN")
	)
	(via
		(at 18.1102 -100.1268)
		(size 0.508)
		(drill 0.254)
		(layers "F.Cu" "B.Cu")
		(net "XP12R0V_IN")
	)
	(via
		(at 20.4978 -100.1268)
		(size 0.508)
		(drill 0.254)
		(layers "F.Cu" "B.Cu")
		(net "XP12R0V_IN")
	)
	(via
		(at 21.6916 -100.1268)
		(size 0.508)
		(drill 0.254)
		(layers "F.Cu" "B.Cu")
		(net "XP12R0V_IN")
	)
	(via
		(at 142.875 -85.3694)
		(size 0.508)
		(drill 0.254)
		(layers "F.Cu" "B.Cu")
		(net "XP12R0V_IN")
	)
	(via
		(at 15.3162 -103.4034)
		(size 0.508)
		(drill 0.254)
		(layers "F.Cu" "B.Cu")
		(net "XP12R0V_IN")
	)
	(via
		(at 142.24 -86.8934)
		(size 0.508)
		(drill 0.254)
		(layers "F.Cu" "B.Cu")
		(net "XP12R0V_IN")
	)
	(via
		(at 23.5712 -102.1334)
		(size 0.508)
		(drill 0.254)
		(layers "F.Cu" "B.Cu")
		(net "XP12R0V_IN")
	)
	(via
		(at 15.3162 -100.3554)
		(size 0.508)
		(drill 0.254)
		(layers "F.Cu" "B.Cu")
		(net "XP12R0V_IN")
	)
	(via
		(at 142.748 -84.2264)
		(size 0.508)
		(drill 0.254)
		(layers "F.Cu" "B.Cu")
		(net "XP12R0V_IN")
	)
	(via
		(at 133.985 -100.8634)
		(size 0.508)
		(drill 0.254)
		(layers "F.Cu" "B.Cu")
		(net "XP12R0V_IN")
	)
	(via
		(at 23.5712 -103.6574)
		(size 0.508)
		(drill 0.254)
		(layers "F.Cu" "B.Cu")
		(net "XP12R0V_IN")
	)
	(via
		(at 141.0208 -94.269814)
		(size 0.4572)
		(drill 0.2032)
		(layers "F.Cu" "B.Cu")
		(net "XP12R0V_IN")
	)
	(via
		(at 141.4018 -81.3562)
		(size 0.508)
		(drill 0.254)
		(layers "F.Cu" "B.Cu")
		(net "XP12R0V_IN")
	)
	(via
		(at 18.1102 -102.6668)
		(size 0.508)
		(drill 0.254)
		(layers "F.Cu" "B.Cu")
		(net "XP12R0V_IN")
	)
	(via
		(at 20.4978 -101.3968)
		(size 0.508)
		(drill 0.254)
		(layers "F.Cu" "B.Cu")
		(net "XP12R0V_IN")
	)
	(via
		(at 16.3322 -102.0064)
		(size 0.508)
		(drill 0.254)
		(layers "F.Cu" "B.Cu")
		(net "XP12R0V_IN")
	)
	(via
		(at 21.6916 -102.6668)
		(size 0.508)
		(drill 0.254)
		(layers "F.Cu" "B.Cu")
		(net "XP12R0V_IN")
	)
	(via
		(at 23.5712 -105.1814)
		(size 0.508)
		(drill 0.254)
		(layers "F.Cu" "B.Cu")
		(net "XP12R0V_IN")
	)
	(via
		(at 15.3162 -104.9274)
		(size 0.508)
		(drill 0.254)
		(layers "F.Cu" "B.Cu")
		(net "XP12R0V_IN")
	)
	(via
		(at 16.3322 -100.4824)
		(size 0.508)
		(drill 0.254)
		(layers "F.Cu" "B.Cu")
		(net "XP12R0V_IN")
	)
	(via
		(at 140.208 -94.269814)
		(size 0.4572)
		(drill 0.2032)
		(layers "F.Cu" "B.Cu")
		(net "XP12R0V_IN")
	)
	(via
		(at 142.6718 -81.3562)
		(size 0.508)
		(drill 0.254)
		(layers "F.Cu" "B.Cu")
		(net "XP12R0V_IN")
	)
	(via
		(at 18.1102 -101.3968)
		(size 0.508)
		(drill 0.254)
		(layers "F.Cu" "B.Cu")
		(net "XP12R0V_IN")
	)
	(via
		(at 21.6916 -103.9368)
		(size 0.508)
		(drill 0.254)
		(layers "F.Cu" "B.Cu")
		(net "XP12R0V_IN")
	)
	(via
		(at 141.0208 -93.369638)
		(size 0.4572)
		(drill 0.2032)
		(layers "F.Cu" "B.Cu")
		(net "XP12R0V_IN")
	)
	(via
		(at 24.5872 -105.1814)
		(size 0.508)
		(drill 0.254)
		(layers "F.Cu" "B.Cu")
		(net "XP12R0V_IN")
	)
	(via
		(at 24.5872 -100.6094)
		(size 0.508)
		(drill 0.254)
		(layers "F.Cu" "B.Cu")
		(net "XP12R0V_IN")
	)
	(via
		(at 16.3322 -105.0544)
		(size 0.508)
		(drill 0.254)
		(layers "F.Cu" "B.Cu")
		(net "XP12R0V_IN")
	)
	(via
		(at 141.0208 -96.069658)
		(size 0.4572)
		(drill 0.2032)
		(layers "F.Cu" "B.Cu")
		(net "XP12R0V_IN")
	)
	(via
		(at 20.4978 -102.6668)
		(size 0.508)
		(drill 0.254)
		(layers "F.Cu" "B.Cu")
		(net "XP12R0V_IN")
	)
	(via
		(at 19.304 -102.6668)
		(size 0.508)
		(drill 0.254)
		(layers "F.Cu" "B.Cu")
		(net "XP12R0V_IN")
	)
	(via
		(at 133.985 -98.8314)
		(size 0.508)
		(drill 0.254)
		(layers "F.Cu" "B.Cu")
		(net "XP12R0V_IN")
	)
	(via
		(at 20.4978 -103.9368)
		(size 0.508)
		(drill 0.254)
		(layers "F.Cu" "B.Cu")
		(net "XP12R0V_IN")
	)
	(via
		(at 140.208 -95.169736)
		(size 0.4572)
		(drill 0.2032)
		(layers "F.Cu" "B.Cu")
		(net "XP12R0V_IN")
	)
	(via
		(at 24.5872 -102.1334)
		(size 0.508)
		(drill 0.254)
		(layers "F.Cu" "B.Cu")
		(net "XP12R0V_IN")
	)
	(via
		(at 19.304 -101.3968)
		(size 0.508)
		(drill 0.254)
		(layers "F.Cu" "B.Cu")
		(net "XP12R0V_IN")
	)
	(via
		(at 133.985 -99.8474)
		(size 0.508)
		(drill 0.254)
		(layers "F.Cu" "B.Cu")
		(net "XP12R0V_IN")
	)
	(via
		(at 18.1102 -103.9368)
		(size 0.508)
		(drill 0.254)
		(layers "F.Cu" "B.Cu")
		(net "XP12R0V_IN")
	)
	(segment
		(start 142.24 -86.8934)
		(end 142.3416 -86.995)
		(width 0.381)
		(layer "In2.Cu")
		(net "XP12R0V_IN")
	)
	(segment
		(start 142.3416 -86.995)
		(end 146.3548 -86.995)
		(width 0.381)
		(layer "In2.Cu")
		(net "XP12R0V_IN")
	)
	(segment
		(start 18.796 -25.527)
		(end 19.2024 -25.527)
		(width 0.11938)
		(layer "F.Cu")
		(net "UNNAMED_5_24LC16BTISTTSSOP8_I_2")
	)
	(segment
		(start 19.2024 -25.527)
		(end 19.360134 -25.369266)
		(width 0.11938)
		(layer "F.Cu")
		(net "UNNAMED_5_24LC16BTISTTSSOP8_I_2")
	)
	(segment
		(start 19.360134 -25.369266)
		(end 19.360134 -24.0665)
		(width 0.11938)
		(layer "F.Cu")
		(net "UNNAMED_5_24LC16BTISTTSSOP8_I_2")
	)
	(via
		(at 18.796 -25.527)
		(size 0.508)
		(drill 0.254)
		(layers "F.Cu" "B.Cu")
		(net "UNNAMED_5_24LC16BTISTTSSOP8_I_2")
	)
	(segment
		(start 18.796 -25.527)
		(end 18.8722 -25.4508)
		(width 0.11938)
		(layer "B.Cu")
		(net "UNNAMED_5_24LC16BTISTTSSOP8_I_2")
	)
	(segment
		(start 18.8722 -24.2062)
		(end 17.7292 -24.2062)
		(width 0.11938)
		(layer "B.Cu")
		(net "UNNAMED_5_24LC16BTISTTSSOP8_I_2")
	)
	(segment
		(start 18.8722 -25.4508)
		(end 18.8722 -24.2062)
		(width 0.11938)
		(layer "B.Cu")
		(net "UNNAMED_5_24LC16BTISTTSSOP8_I_2")
	)
	(segment
		(start 20.01012 -25.39492)
		(end 20.01012 -24.0665)
		(width 0.11938)
		(layer "F.Cu")
		(net "UNNAMED_5_24LC16BTISTTSSOP8_I_1")
	)
	(segment
		(start 20.0152 -25.4)
		(end 20.01012 -25.39492)
		(width 0.11938)
		(layer "F.Cu")
		(net "UNNAMED_5_24LC16BTISTTSSOP8_I_1")
	)
	(segment
		(start 20.066 -25.527)
		(end 20.0152 -25.4762)
		(width 0.11938)
		(layer "F.Cu")
		(net "UNNAMED_5_24LC16BTISTTSSOP8_I_1")
	)
	(segment
		(start 20.0152 -25.4762)
		(end 20.0152 -25.4)
		(width 0.11938)
		(layer "F.Cu")
		(net "UNNAMED_5_24LC16BTISTTSSOP8_I_1")
	)
	(via
		(at 20.066 -25.527)
		(size 0.508)
		(drill 0.254)
		(layers "F.Cu" "B.Cu")
		(net "UNNAMED_5_24LC16BTISTTSSOP8_I_1")
	)
	(segment
		(start 20.066 -25.527)
		(end 20.0152 -25.4762)
		(width 0.11938)
		(layer "B.Cu")
		(net "UNNAMED_5_24LC16BTISTTSSOP8_I_1")
	)
	(segment
		(start 20.0152 -25.4762)
		(end 20.0152 -24.2062)
		(width 0.11938)
		(layer "B.Cu")
		(net "UNNAMED_5_24LC16BTISTTSSOP8_I_1")
	)
	(segment
		(start 21.1582 -24.2062)
		(end 20.0152 -24.2062)
		(width 0.11938)
		(layer "B.Cu")
		(net "UNNAMED_5_24LC16BTISTTSSOP8_I_1")
	)
	(segment
		(start 21.336 -25.527)
		(end 20.955 -25.527)
		(width 0.11938)
		(layer "F.Cu")
		(net "UNNAMED_5_24LC16BTISTTSSOP8_I15")
	)
	(segment
		(start 20.660106 -25.232106)
		(end 20.660106 -24.0665)
		(width 0.11938)
		(layer "F.Cu")
		(net "UNNAMED_5_24LC16BTISTTSSOP8_I15")
	)
	(segment
		(start 20.955 -25.527)
		(end 20.660106 -25.232106)
		(width 0.11938)
		(layer "F.Cu")
		(net "UNNAMED_5_24LC16BTISTTSSOP8_I15")
	)
	(via
		(at 21.336 -25.527)
		(size 0.508)
		(drill 0.254)
		(layers "F.Cu" "B.Cu")
		(net "UNNAMED_5_24LC16BTISTTSSOP8_I15")
	)
	(segment
		(start 22.3012 -25.1206)
		(end 22.3012 -24.2062)
		(width 0.11938)
		(layer "B.Cu")
		(net "UNNAMED_5_24LC16BTISTTSSOP8_I15")
	)
	(segment
		(start 22.3012 -24.2062)
		(end 23.0378 -24.2062)
		(width 0.11938)
		(layer "B.Cu")
		(net "UNNAMED_5_24LC16BTISTTSSOP8_I15")
	)
	(segment
		(start 28.35402 -21.1328)
		(end 29.42082 -20.066)
		(width 0.11938)
		(layer "B.Cu")
		(net "UNNAMED_5_24LC16BTISTTSSOP8_I15")
	)
	(segment
		(start 34.06902 -20.066)
		(end 34.3154 -19.81962)
		(width 0.11938)
		(layer "B.Cu")
		(net "UNNAMED_5_24LC16BTISTTSSOP8_I15")
	)
	(segment
		(start 23.876 -23.368)
		(end 26.289 -23.368)
		(width 0.11938)
		(layer "B.Cu")
		(net "UNNAMED_5_24LC16BTISTTSSOP8_I15")
	)
	(segment
		(start 28.35402 -21.30298)
		(end 28.35402 -21.1328)
		(width 0.11938)
		(layer "B.Cu")
		(net "UNNAMED_5_24LC16BTISTTSSOP8_I15")
	)
	(segment
		(start 21.8948 -25.527)
		(end 22.3012 -25.1206)
		(width 0.11938)
		(layer "B.Cu")
		(net "UNNAMED_5_24LC16BTISTTSSOP8_I15")
	)
	(segment
		(start 21.336 -25.527)
		(end 21.8948 -25.527)
		(width 0.11938)
		(layer "B.Cu")
		(net "UNNAMED_5_24LC16BTISTTSSOP8_I15")
	)
	(segment
		(start 26.289 -23.368)
		(end 28.35402 -21.30298)
		(width 0.11938)
		(layer "B.Cu")
		(net "UNNAMED_5_24LC16BTISTTSSOP8_I15")
	)
	(segment
		(start 23.0378 -24.2062)
		(end 23.876 -23.368)
		(width 0.11938)
		(layer "B.Cu")
		(net "UNNAMED_5_24LC16BTISTTSSOP8_I15")
	)
	(segment
		(start 34.3154 -19.81962)
		(end 34.3154 -19.1262)
		(width 0.11938)
		(layer "B.Cu")
		(net "UNNAMED_5_24LC16BTISTTSSOP8_I15")
	)
	(segment
		(start 29.42082 -20.066)
		(end 34.06902 -20.066)
		(width 0.11938)
		(layer "B.Cu")
		(net "UNNAMED_5_24LC16BTISTTSSOP8_I15")
	)
	(segment
		(start 39.6494 -76.3016)
		(end 38.862 -76.3016)
		(width 0.11938)
		(layer "F.Cu")
		(net "UNNAMED_525_ISL80101IRAJZDFN10_")
	)
	(segment
		(start 39.8272 -76.4794)
		(end 39.6494 -76.3016)
		(width 0.11938)
		(layer "F.Cu")
		(net "UNNAMED_525_ISL80101IRAJZDFN10_")
	)
	(segment
		(start 38.7604 -74.93)
		(end 38.862 -75.0316)
		(width 0.11938)
		(layer "F.Cu")
		(net "UNNAMED_525_ISL80101IRAJZDFN10_")
	)
	(segment
		(start 38.862 -75.0316)
		(end 38.862 -76.3016)
		(width 0.11938)
		(layer "F.Cu")
		(net "UNNAMED_525_ISL80101IRAJZDFN10_")
	)
	(segment
		(start 39.9288 -76.581)
		(end 39.8272 -76.4794)
		(width 0.11938)
		(layer "F.Cu")
		(net "UNNAMED_525_ISL80101IRAJZDFN10_")
	)
	(segment
		(start 41.156382 -76.581)
		(end 39.9288 -76.581)
		(width 0.11938)
		(layer "F.Cu")
		(net "UNNAMED_525_ISL80101IRAJZDFN10_")
	)
	(via
		(at 39.8272 -76.4794)
		(size 0.508)
		(drill 0.254)
		(layers "F.Cu" "B.Cu")
		(net "UNNAMED_525_ISL80101IRAJZDFN10_")
	)
	(segment
		(start 39.5478 -76.2)
		(end 39.8272 -76.4794)
		(width 0.11938)
		(layer "B.Cu")
		(net "UNNAMED_525_ISL80101IRAJZDFN10_")
	)
	(segment
		(start 38.6334 -76.2)
		(end 39.5478 -76.2)
		(width 0.11938)
		(layer "B.Cu")
		(net "UNNAMED_525_ISL80101IRAJZDFN10_")
	)
	(via
		(at 44.1452 -82.3214)
		(size 0.508)
		(drill 0.254)
		(layers "F.Cu" "B.Cu")
		(net "UNNAMED_525_CAPACITOR_I7_1")
	)
	(segment
		(start 44.187618 -74.377804)
		(end 44.079922 -74.270108)
		(width 0.254)
		(layer "F.Cu")
		(net "UNNAMED_525_CAPACITOR_I18_1")
	)
	(segment
		(start 44.187618 -75.580748)
		(end 44.187618 -74.377804)
		(width 0.254)
		(layer "F.Cu")
		(net "UNNAMED_525_CAPACITOR_I18_1")
	)
	(segment
		(start 44.079922 -74.270108)
		(end 44.079922 -73.66)
		(width 0.254)
		(layer "F.Cu")
		(net "UNNAMED_525_CAPACITOR_I18_1")
	)
	(segment
		(start 44.079922 -73.66)
		(end 44.831 -73.66)
		(width 0.254)
		(layer "F.Cu")
		(net "UNNAMED_525_CAPACITOR_I18_1")
	)
	(via
		(at 44.831 -73.66)
		(size 0.508)
		(drill 0.254)
		(layers "F.Cu" "B.Cu")
		(net "UNNAMED_525_CAPACITOR_I18_1")
	)
	(via
		(at 45.212 -78.613)
		(size 0.508)
		(drill 0.254)
		(layers "F.Cu" "B.Cu")
		(net "UNNAMED_525_CAPACITOR_I16_1")
	)
	(segment
		(start 45.593 -75.692)
		(end 45.593 -74.8284)
		(width 0.11938)
		(layer "F.Cu")
		(net "UNNAMED_525_CAPACITOR_I14_1")
	)
	(segment
		(start 45.204126 -76.080874)
		(end 45.593 -75.692)
		(width 0.11938)
		(layer "F.Cu")
		(net "UNNAMED_525_CAPACITOR_I14_1")
	)
	(segment
		(start 47.879 -74.6506)
		(end 46.609 -74.6506)
		(width 0.11938)
		(layer "F.Cu")
		(net "UNNAMED_525_CAPACITOR_I14_1")
	)
	(segment
		(start 45.7708 -74.6506)
		(end 46.609 -74.6506)
		(width 0.11938)
		(layer "F.Cu")
		(net "UNNAMED_525_CAPACITOR_I14_1")
	)
	(segment
		(start 45.593 -74.8284)
		(end 45.7708 -74.6506)
		(width 0.11938)
		(layer "F.Cu")
		(net "UNNAMED_525_CAPACITOR_I14_1")
	)
	(segment
		(start 44.187618 -76.080874)
		(end 45.204126 -76.080874)
		(width 0.11938)
		(layer "F.Cu")
		(net "UNNAMED_525_CAPACITOR_I14_1")
	)
	(via
		(at 45.593 -74.8284)
		(size 0.508)
		(drill 0.254)
		(layers "F.Cu" "B.Cu")
		(net "UNNAMED_525_CAPACITOR_I14_1")
	)
	(segment
		(start 47.879 -74.6506)
		(end 45.7708 -74.6506)
		(width 0.11938)
		(layer "B.Cu")
		(net "UNNAMED_525_CAPACITOR_I14_1")
	)
	(segment
		(start 45.7708 -74.6506)
		(end 45.593 -74.8284)
		(width 0.11938)
		(layer "B.Cu")
		(net "UNNAMED_525_CAPACITOR_I14_1")
	)
	(segment
		(start 133.3246 -22.098)
		(end 132.08 -22.098)
		(width 0.11938)
		(layer "F.Cu")
		(net "UNNAMED_524_RESISTOR_I463_2")
	)
	(segment
		(start 131.851908 -22.707092)
		(end 132.08 -22.479)
		(width 0.11938)
		(layer "F.Cu")
		(net "UNNAMED_524_RESISTOR_I463_2")
	)
	(segment
		(start 130.1623 -22.707092)
		(end 131.851908 -22.707092)
		(width 0.11938)
		(layer "F.Cu")
		(net "UNNAMED_524_RESISTOR_I463_2")
	)
	(segment
		(start 132.08 -22.479)
		(end 132.08 -22.098)
		(width 0.11938)
		(layer "F.Cu")
		(net "UNNAMED_524_RESISTOR_I463_2")
	)
	(via
		(at 132.08 -22.098)
		(size 0.508)
		(drill 0.254)
		(layers "F.Cu" "B.Cu")
		(net "UNNAMED_524_RESISTOR_I463_2")
	)
	(segment
		(start 114.604292 -81.787492)
		(end 114.6048 -81.788)
		(width 0.11938)
		(layer "F.Cu")
		(net "UNNAMED_524_RESISTOR_I432_2")
	)
	(segment
		(start 113.538 -81.787492)
		(end 114.604292 -81.787492)
		(width 0.11938)
		(layer "F.Cu")
		(net "UNNAMED_524_RESISTOR_I432_2")
	)
	(segment
		(start 111.9759 -81.787492)
		(end 113.538 -81.787492)
		(width 0.11938)
		(layer "F.Cu")
		(net "UNNAMED_524_RESISTOR_I432_2")
	)
	(via
		(at 113.538 -81.787492)
		(size 0.508)
		(drill 0.254)
		(layers "F.Cu" "B.Cu")
		(net "UNNAMED_524_RESISTOR_I432_2")
	)
	(segment
		(start 111.379 -92.583)
		(end 111.3536 -92.6084)
		(width 0.11938)
		(layer "F.Cu")
		(net "UNNAMED_524_POWERMOS3PNCHV1_I44")
	)
	(segment
		(start 111.3536 -93.98)
		(end 111.3536 -95.123)
		(width 0.11938)
		(layer "F.Cu")
		(net "UNNAMED_524_POWERMOS3PNCHV1_I44")
	)
	(segment
		(start 109.956092 -94.970092)
		(end 110.109 -95.123)
		(width 0.11938)
		(layer "F.Cu")
		(net "UNNAMED_524_POWERMOS3PNCHV1_I44")
	)
	(segment
		(start 111.3536 -92.6084)
		(end 111.3536 -93.98)
		(width 0.11938)
		(layer "F.Cu")
		(net "UNNAMED_524_POWERMOS3PNCHV1_I44")
	)
	(segment
		(start 110.109 -95.123)
		(end 111.3536 -95.123)
		(width 0.11938)
		(layer "F.Cu")
		(net "UNNAMED_524_POWERMOS3PNCHV1_I44")
	)
	(segment
		(start 108.5723 -94.970092)
		(end 109.956092 -94.970092)
		(width 0.11938)
		(layer "F.Cu")
		(net "UNNAMED_524_POWERMOS3PNCHV1_I44")
	)
	(segment
		(start 112.0521 -91.9099)
		(end 111.379 -92.583)
		(width 0.11938)
		(layer "F.Cu")
		(net "UNNAMED_524_POWERMOS3PNCHV1_I44")
	)
	(segment
		(start 112.649 -91.9099)
		(end 112.0521 -91.9099)
		(width 0.11938)
		(layer "F.Cu")
		(net "UNNAMED_524_POWERMOS3PNCHV1_I44")
	)
	(via
		(at 111.379 -92.583)
		(size 0.508)
		(drill 0.254)
		(layers "F.Cu" "B.Cu")
		(net "UNNAMED_524_POWERMOS3PNCHV1_I44")
	)
	(segment
		(start 21.238464 -84.836)
		(end 21.717 -85.314536)
		(width 0.11938)
		(layer "F.Cu")
		(net "UNNAMED_524_FT4232HLREELQFP64_I")
	)
	(segment
		(start 19.812 -84.328)
		(end 20.32 -84.836)
		(width 0.11938)
		(layer "F.Cu")
		(net "UNNAMED_524_FT4232HLREELQFP64_I")
	)
	(segment
		(start 21.717 -85.314536)
		(end 22.7076 -85.314536)
		(width 0.11938)
		(layer "F.Cu")
		(net "UNNAMED_524_FT4232HLREELQFP64_I")
	)
	(segment
		(start 20.32 -84.836)
		(end 21.238464 -84.836)
		(width 0.11938)
		(layer "F.Cu")
		(net "UNNAMED_524_FT4232HLREELQFP64_I")
	)
	(segment
		(start 19.812 -83.947)
		(end 19.812 -84.328)
		(width 0.11938)
		(layer "F.Cu")
		(net "UNNAMED_524_FT4232HLREELQFP64_I")
	)
	(segment
		(start 26.162 -89.281)
		(end 25.774142 -89.668858)
		(width 0.11938)
		(layer "F.Cu")
		(net "UNNAMED_524_FT4232HLREELQFP64_7")
	)
	(segment
		(start 25.774142 -89.668858)
		(end 25.774142 -90.8812)
		(width 0.11938)
		(layer "F.Cu")
		(net "UNNAMED_524_FT4232HLREELQFP64_7")
	)
	(via
		(at 26.162 -89.281)
		(size 0.508)
		(drill 0.254)
		(layers "F.Cu" "B.Cu")
		(net "UNNAMED_524_FT4232HLREELQFP64_7")
	)
	(segment
		(start 26.416 -89.535)
		(end 26.416 -90.5256)
		(width 0.11938)
		(layer "B.Cu")
		(net "UNNAMED_524_FT4232HLREELQFP64_7")
	)
	(segment
		(start 26.162 -89.281)
		(end 26.416 -89.535)
		(width 0.11938)
		(layer "B.Cu")
		(net "UNNAMED_524_FT4232HLREELQFP64_7")
	)
	(segment
		(start 30.226 -89.408)
		(end 29.774134 -89.859866)
		(width 0.11938)
		(layer "F.Cu")
		(net "UNNAMED_524_FT4232HLREELQFP64_6")
	)
	(segment
		(start 29.774134 -89.859866)
		(end 29.774134 -90.8812)
		(width 0.11938)
		(layer "F.Cu")
		(net "UNNAMED_524_FT4232HLREELQFP64_6")
	)
	(via
		(at 30.226 -89.408)
		(size 0.508)
		(drill 0.254)
		(layers "F.Cu" "B.Cu")
		(net "UNNAMED_524_FT4232HLREELQFP64_6")
	)
	(segment
		(start 29.845 -89.789)
		(end 29.845 -90.5256)
		(width 0.11938)
		(layer "B.Cu")
		(net "UNNAMED_524_FT4232HLREELQFP64_6")
	)
	(segment
		(start 30.226 -89.408)
		(end 29.845 -89.789)
		(width 0.11938)
		(layer "B.Cu")
		(net "UNNAMED_524_FT4232HLREELQFP64_6")
	)
	(segment
		(start 25.27427 -75.18527)
		(end 24.13 -74.041)
		(width 0.11938)
		(layer "F.Cu")
		(net "UNNAMED_524_FT4232HLREELQFP64_5")
	)
	(segment
		(start 25.27427 -79.248)
		(end 25.27427 -75.18527)
		(width 0.11938)
		(layer "F.Cu")
		(net "UNNAMED_524_FT4232HLREELQFP64_5")
	)
	(segment
		(start 24.774144 -76.717144)
		(end 24.003 -75.946)
		(width 0.11938)
		(layer "F.Cu")
		(net "UNNAMED_524_FT4232HLREELQFP64_4")
	)
	(segment
		(start 24.774144 -79.248)
		(end 24.774144 -76.717144)
		(width 0.11938)
		(layer "F.Cu")
		(net "UNNAMED_524_FT4232HLREELQFP64_4")
	)
	(segment
		(start 22.7076 -77.1906)
		(end 22.479 -76.962)
		(width 0.11938)
		(layer "F.Cu")
		(net "UNNAMED_524_FT4232HLREELQFP64_3")
	)
	(segment
		(start 22.7076 -81.314544)
		(end 22.7076 -77.1906)
		(width 0.11938)
		(layer "F.Cu")
		(net "UNNAMED_524_FT4232HLREELQFP64_3")
	)
	(segment
		(start 24.765 -81.28)
		(end 24.765 -82.042)
		(width 0.11938)
		(layer "F.Cu")
		(net "UNNAMED_524_FT4232HLREELQFP64_2")
	)
	(segment
		(start 23.368 -76.708)
		(end 23.368 -79.883)
		(width 0.11938)
		(layer "F.Cu")
		(net "UNNAMED_524_FT4232HLREELQFP64_2")
	)
	(segment
		(start 24.492458 -82.314542)
		(end 22.7076 -82.314542)
		(width 0.11938)
		(layer "F.Cu")
		(net "UNNAMED_524_FT4232HLREELQFP64_2")
	)
	(segment
		(start 23.368 -79.883)
		(end 24.765 -81.28)
		(width 0.11938)
		(layer "F.Cu")
		(net "UNNAMED_524_FT4232HLREELQFP64_2")
	)
	(segment
		(start 22.225 -75.565)
		(end 23.368 -76.708)
		(width 0.11938)
		(layer "F.Cu")
		(net "UNNAMED_524_FT4232HLREELQFP64_2")
	)
	(segment
		(start 22.225 -75.057)
		(end 22.225 -75.565)
		(width 0.11938)
		(layer "F.Cu")
		(net "UNNAMED_524_FT4232HLREELQFP64_2")
	)
	(segment
		(start 24.765 -82.042)
		(end 24.492458 -82.314542)
		(width 0.11938)
		(layer "F.Cu")
		(net "UNNAMED_524_FT4232HLREELQFP64_2")
	)
	(segment
		(start 21.981668 -82.814668)
		(end 22.7076 -82.814668)
		(width 0.11938)
		(layer "F.Cu")
		(net "UNNAMED_524_FT4232HLREELQFP64_1")
	)
	(segment
		(start 20.193 -78.359)
		(end 21.463 -79.629)
		(width 0.11938)
		(layer "F.Cu")
		(net "UNNAMED_524_FT4232HLREELQFP64_1")
	)
	(segment
		(start 21.463 -79.629)
		(end 21.463 -82.296)
		(width 0.11938)
		(layer "F.Cu")
		(net "UNNAMED_524_FT4232HLREELQFP64_1")
	)
	(segment
		(start 21.463 -82.296)
		(end 21.981668 -82.814668)
		(width 0.11938)
		(layer "F.Cu")
		(net "UNNAMED_524_FT4232HLREELQFP64_1")
	)
	(segment
		(start 9.40054 -86.38032)
		(end 9.40054 -85.72246)
		(width 0.11938)
		(layer "F.Cu")
		(net "UNNAMED_524_CONNUSB14PGH4FRAT_1")
	)
	(segment
		(start 13.97 -84.5566)
		(end 14.9606 -83.566)
		(width 0.11938)
		(layer "F.Cu")
		(net "UNNAMED_524_CONNUSB14PGH4FRAT_1")
	)
	(segment
		(start 9.40054 -85.72246)
		(end 9.779 -85.344)
		(width 0.11938)
		(layer "F.Cu")
		(net "UNNAMED_524_CONNUSB14PGH4FRAT_1")
	)
	(segment
		(start 13.97 -85.344)
		(end 13.97 -84.5566)
		(width 0.11938)
		(layer "F.Cu")
		(net "UNNAMED_524_CONNUSB14PGH4FRAT_1")
	)
	(segment
		(start 9.779 -85.344)
		(end 13.97 -85.344)
		(width 0.11938)
		(layer "F.Cu")
		(net "UNNAMED_524_CONNUSB14PGH4FRAT_1")
	)
	(via
		(at 13.97 -85.344)
		(size 0.508)
		(drill 0.254)
		(layers "F.Cu" "B.Cu")
		(net "UNNAMED_524_CONNUSB14PGH4FRAT_1")
	)
	(segment
		(start 15.113 -90.2716)
		(end 13.97 -90.2716)
		(width 0.11938)
		(layer "F.Cu")
		(net "UNNAMED_524_CONNUSB14PGH4FRATH_")
	)
	(via
		(at 13.97 -90.2716)
		(size 0.508)
		(drill 0.254)
		(layers "F.Cu" "B.Cu")
		(net "UNNAMED_524_CONNUSB14PGH4FRATH_")
	)
	(segment
		(start 8.050276 -87.425276)
		(end 8.050276 -87.1601)
		(width 0.1016)
		(layer "B.Cu")
		(net "UNNAMED_524_CONNUSB14PGH4FRATH_")
	)
	(segment
		(start 13.97 -89.4588)
		(end 12.6492 -88.138)
		(width 0.1016)
		(layer "B.Cu")
		(net "UNNAMED_524_CONNUSB14PGH4FRATH_")
	)
	(segment
		(start 12.6492 -88.138)
		(end 8.763 -88.138)
		(width 0.1016)
		(layer "B.Cu")
		(net "UNNAMED_524_CONNUSB14PGH4FRATH_")
	)
	(segment
		(start 13.97 -90.2716)
		(end 13.97 -89.4588)
		(width 0.1016)
		(layer "B.Cu")
		(net "UNNAMED_524_CONNUSB14PGH4FRATH_")
	)
	(segment
		(start 8.763 -88.138)
		(end 8.050276 -87.425276)
		(width 0.1016)
		(layer "B.Cu")
		(net "UNNAMED_524_CONNUSB14PGH4FRATH_")
	)
	(segment
		(start 31.877 -98.551746)
		(end 32.854138 -99.528884)
		(width 0.11938)
		(layer "F.Cu")
		(net "UNNAMED_524_CAPACITOR_I7_2")
	)
	(segment
		(start 31.877 -96.636078)
		(end 31.877 -98.551746)
		(width 0.11938)
		(layer "F.Cu")
		(net "UNNAMED_524_CAPACITOR_I7_2")
	)
	(segment
		(start 31.77413 -94.51213)
		(end 31.77413 -90.8812)
		(width 0.11938)
		(layer "F.Cu")
		(net "UNNAMED_524_CAPACITOR_I7_2")
	)
	(segment
		(start 32.2834 -95.25)
		(end 32.2834 -95.0214)
		(width 0.11938)
		(layer "F.Cu")
		(net "UNNAMED_524_CAPACITOR_I7_2")
	)
	(segment
		(start 32.247078 -96.266)
		(end 31.877 -96.636078)
		(width 0.11938)
		(layer "F.Cu")
		(net "UNNAMED_524_CAPACITOR_I7_2")
	)
	(segment
		(start 32.2834 -95.0214)
		(end 31.77413 -94.51213)
		(width 0.11938)
		(layer "F.Cu")
		(net "UNNAMED_524_CAPACITOR_I7_2")
	)
	(segment
		(start 32.2834 -96.229678)
		(end 32.247078 -96.266)
		(width 0.11938)
		(layer "F.Cu")
		(net "UNNAMED_524_CAPACITOR_I7_2")
	)
	(segment
		(start 32.2834 -95.25)
		(end 32.2834 -96.229678)
		(width 0.11938)
		(layer "F.Cu")
		(net "UNNAMED_524_CAPACITOR_I7_2")
	)
	(segment
		(start 32.854138 -99.528884)
		(end 32.977074 -99.528884)
		(width 0.11938)
		(layer "F.Cu")
		(net "UNNAMED_524_CAPACITOR_I7_2")
	)
	(segment
		(start 31.379922 -97.22612)
		(end 30.776926 -97.829116)
		(width 0.11938)
		(layer "F.Cu")
		(net "UNNAMED_524_CAPACITOR_I10_2")
	)
	(segment
		(start 31.274258 -95.192342)
		(end 31.2166 -95.25)
		(width 0.11938)
		(layer "F.Cu")
		(net "UNNAMED_524_CAPACITOR_I10_2")
	)
	(segment
		(start 31.379922 -96.266)
		(end 31.379922 -97.22612)
		(width 0.11938)
		(layer "F.Cu")
		(net "UNNAMED_524_CAPACITOR_I10_2")
	)
	(segment
		(start 31.379922 -96.266)
		(end 31.379922 -95.413322)
		(width 0.11938)
		(layer "F.Cu")
		(net "UNNAMED_524_CAPACITOR_I10_2")
	)
	(segment
		(start 31.274258 -90.8812)
		(end 31.274258 -95.192342)
		(width 0.11938)
		(layer "F.Cu")
		(net "UNNAMED_524_CAPACITOR_I10_2")
	)
	(segment
		(start 31.379922 -95.413322)
		(end 31.2166 -95.25)
		(width 0.11938)
		(layer "F.Cu")
		(net "UNNAMED_524_CAPACITOR_I10_2")
	)
	(segment
		(start 152.2603 -39.894002)
		(end 150.368 -39.894002)
		(width 0.11938)
		(layer "F.Cu")
		(net "UNNAMED_16_CONNHDR2X6FSSMT_I1_7")
	)
	(via
		(at 150.368 -39.894002)
		(size 0.508)
		(drill 0.254)
		(layers "F.Cu" "B.Cu")
		(net "UNNAMED_16_CONNHDR2X6FSSMT_I1_7")
	)
	(segment
		(start 150.368 -39.894002)
		(end 150.631398 -40.1574)
		(width 0.11938)
		(layer "B.Cu")
		(net "UNNAMED_16_CONNHDR2X6FSSMT_I1_7")
	)
	(segment
		(start 150.631398 -40.1574)
		(end 151.892 -40.1574)
		(width 0.11938)
		(layer "B.Cu")
		(net "UNNAMED_16_CONNHDR2X6FSSMT_I1_7")
	)
	(segment
		(start 157.971998 -39.894002)
		(end 157.988 -39.878)
		(width 0.11938)
		(layer "F.Cu")
		(net "UNNAMED_16_CONNHDR2X6FSSMT_I1_6")
	)
	(segment
		(start 156.120592 -39.894002)
		(end 157.971998 -39.894002)
		(width 0.11938)
		(layer "F.Cu")
		(net "UNNAMED_16_CONNHDR2X6FSSMT_I1_6")
	)
	(via
		(at 157.988 -39.878)
		(size 0.508)
		(drill 0.254)
		(layers "F.Cu" "B.Cu")
		(net "UNNAMED_16_CONNHDR2X6FSSMT_I1_6")
	)
	(segment
		(start 157.8356 -40.0304)
		(end 156.718 -40.0304)
		(width 0.11938)
		(layer "B.Cu")
		(net "UNNAMED_16_CONNHDR2X6FSSMT_I1_6")
	)
	(segment
		(start 157.988 -39.878)
		(end 157.8356 -40.0304)
		(width 0.11938)
		(layer "B.Cu")
		(net "UNNAMED_16_CONNHDR2X6FSSMT_I1_6")
	)
	(segment
		(start 150.368 -37.084)
		(end 150.638002 -37.354002)
		(width 0.11938)
		(layer "F.Cu")
		(net "UNNAMED_16_CONNHDR2X6FSSMT_I1_5")
	)
	(segment
		(start 150.638002 -37.354002)
		(end 152.2603 -37.354002)
		(width 0.11938)
		(layer "F.Cu")
		(net "UNNAMED_16_CONNHDR2X6FSSMT_I1_5")
	)
	(via
		(at 150.368 -37.084)
		(size 0.508)
		(drill 0.254)
		(layers "F.Cu" "B.Cu")
		(net "UNNAMED_16_CONNHDR2X6FSSMT_I1_5")
	)
	(segment
		(start 150.3934 -37.1094)
		(end 150.368 -37.084)
		(width 0.11938)
		(layer "B.Cu")
		(net "UNNAMED_16_CONNHDR2X6FSSMT_I1_5")
	)
	(segment
		(start 151.892 -37.1094)
		(end 150.3934 -37.1094)
		(width 0.11938)
		(layer "B.Cu")
		(net "UNNAMED_16_CONNHDR2X6FSSMT_I1_5")
	)
	(segment
		(start 157.988 -37.211)
		(end 157.844998 -37.354002)
		(width 0.11938)
		(layer "F.Cu")
		(net "UNNAMED_16_CONNHDR2X6FSSMT_I1_4")
	)
	(segment
		(start 157.844998 -37.354002)
		(end 156.120592 -37.354002)
		(width 0.11938)
		(layer "F.Cu")
		(net "UNNAMED_16_CONNHDR2X6FSSMT_I1_4")
	)
	(via
		(at 157.988 -37.211)
		(size 0.508)
		(drill 0.254)
		(layers "F.Cu" "B.Cu")
		(net "UNNAMED_16_CONNHDR2X6FSSMT_I1_4")
	)
	(segment
		(start 156.718 -37.4904)
		(end 157.7086 -37.4904)
		(width 0.11938)
		(layer "B.Cu")
		(net "UNNAMED_16_CONNHDR2X6FSSMT_I1_4")
	)
	(segment
		(start 157.7086 -37.4904)
		(end 157.988 -37.211)
		(width 0.11938)
		(layer "B.Cu")
		(net "UNNAMED_16_CONNHDR2X6FSSMT_I1_4")
	)
	(segment
		(start 150.605998 -42.434002)
		(end 152.2603 -42.434002)
		(width 0.11938)
		(layer "F.Cu")
		(net "UNNAMED_16_CONNHDR2X6FSSMT_I1_3")
	)
	(segment
		(start 150.368 -42.672)
		(end 150.605998 -42.434002)
		(width 0.11938)
		(layer "F.Cu")
		(net "UNNAMED_16_CONNHDR2X6FSSMT_I1_3")
	)
	(via
		(at 150.368 -42.672)
		(size 0.508)
		(drill 0.254)
		(layers "F.Cu" "B.Cu")
		(net "UNNAMED_16_CONNHDR2X6FSSMT_I1_3")
	)
	(segment
		(start 150.368 -42.672)
		(end 150.4696 -42.5704)
		(width 0.11938)
		(layer "B.Cu")
		(net "UNNAMED_16_CONNHDR2X6FSSMT_I1_3")
	)
	(segment
		(start 150.4696 -42.5704)
		(end 151.892 -42.5704)
		(width 0.11938)
		(layer "B.Cu")
		(net "UNNAMED_16_CONNHDR2X6FSSMT_I1_3")
	)
	(segment
		(start 156.120592 -42.434002)
		(end 157.99689 -42.434002)
		(width 0.11938)
		(layer "F.Cu")
		(net "UNNAMED_16_CONNHDR2X6FSSMT_I1_2")
	)
	(via
		(at 157.99689 -42.434002)
		(size 0.508)
		(drill 0.254)
		(layers "F.Cu" "B.Cu")
		(net "UNNAMED_16_CONNHDR2X6FSSMT_I1_2")
	)
	(segment
		(start 157.860492 -42.5704)
		(end 157.99689 -42.434002)
		(width 0.11938)
		(layer "B.Cu")
		(net "UNNAMED_16_CONNHDR2X6FSSMT_I1_2")
	)
	(segment
		(start 156.718 -42.5704)
		(end 157.860492 -42.5704)
		(width 0.11938)
		(layer "B.Cu")
		(net "UNNAMED_16_CONNHDR2X6FSSMT_I1_2")
	)
	(segment
		(start 150.495 -45.212)
		(end 150.732998 -44.974002)
		(width 0.11938)
		(layer "F.Cu")
		(net "UNNAMED_16_CONNHDR2X6FSSMT_I1_1")
	)
	(segment
		(start 150.368 -45.212)
		(end 150.495 -45.212)
		(width 0.11938)
		(layer "F.Cu")
		(net "UNNAMED_16_CONNHDR2X6FSSMT_I1_1")
	)
	(segment
		(start 150.732998 -44.974002)
		(end 152.2603 -44.974002)
		(width 0.11938)
		(layer "F.Cu")
		(net "UNNAMED_16_CONNHDR2X6FSSMT_I1_1")
	)
	(via
		(at 150.368 -45.212)
		(size 0.508)
		(drill 0.254)
		(layers "F.Cu" "B.Cu")
		(net "UNNAMED_16_CONNHDR2X6FSSMT_I1_1")
	)
	(segment
		(start 150.368 -45.212)
		(end 150.3934 -45.2374)
		(width 0.11938)
		(layer "B.Cu")
		(net "UNNAMED_16_CONNHDR2X6FSSMT_I1_1")
	)
	(segment
		(start 150.3934 -45.2374)
		(end 151.892 -45.2374)
		(width 0.11938)
		(layer "B.Cu")
		(net "UNNAMED_16_CONNHDR2X6FSSMT_I1_1")
	)
	(segment
		(start 157.988 -44.577)
		(end 157.590998 -44.974002)
		(width 0.11938)
		(layer "F.Cu")
		(net "UNNAMED_16_CONNHDR2X6FSSMT_I161")
	)
	(segment
		(start 157.590998 -44.974002)
		(end 156.120592 -44.974002)
		(width 0.11938)
		(layer "F.Cu")
		(net "UNNAMED_16_CONNHDR2X6FSSMT_I161")
	)
	(via
		(at 157.988 -44.577)
		(size 0.508)
		(drill 0.254)
		(layers "F.Cu" "B.Cu")
		(net "UNNAMED_16_CONNHDR2X6FSSMT_I161")
	)
	(segment
		(start 157.988 -44.577)
		(end 157.6324 -44.9326)
		(width 0.11938)
		(layer "B.Cu")
		(net "UNNAMED_16_CONNHDR2X6FSSMT_I161")
	)
	(segment
		(start 157.6324 -44.9326)
		(end 156.337 -44.9326)
		(width 0.11938)
		(layer "B.Cu")
		(net "UNNAMED_16_CONNHDR2X6FSSMT_I161")
	)
	(segment
		(start 156.04998 -105.099866)
		(end 154.793696 -105.099866)
		(width 0.11938)
		(layer "F.Cu")
		(net "UNNAMED_14_OPTICAL_I289_A")
	)
	(via
		(at 154.793696 -105.099866)
		(size 0.508)
		(drill 0.254)
		(layers "F.Cu" "B.Cu")
		(net "UNNAMED_14_OPTICAL_I289_A")
	)
	(segment
		(start 154.839162 -105.0544)
		(end 156.083 -105.0544)
		(width 0.11938)
		(layer "B.Cu")
		(net "UNNAMED_14_OPTICAL_I289_A")
	)
	(segment
		(start 154.793696 -105.099866)
		(end 154.839162 -105.0544)
		(width 0.11938)
		(layer "B.Cu")
		(net "UNNAMED_14_OPTICAL_I289_A")
	)
	(segment
		(start 26.035 -74.6506)
		(end 27.305 -74.6506)
		(width 0.11938)
		(layer "F.Cu")
		(net "UART_FT4232_TX_FPGA_RX")
	)
	(segment
		(start 26.035 -74.6506)
		(end 26.035 -73.66)
		(width 0.11938)
		(layer "F.Cu")
		(net "UART_FT4232_TX_FPGA_RX")
	)
	(segment
		(start 111.847122 -48.823118)
		(end 112.346994 -49.32299)
		(width 0.11938)
		(layer "F.Cu")
		(net "UART_FT4232_TX_FPGA_RX")
	)
	(via
		(at 26.035 -73.66)
		(size 0.508)
		(drill 0.254)
		(layers "F.Cu" "B.Cu")
		(net "UART_FT4232_TX_FPGA_RX")
	)
	(via
		(at 112.346994 -49.32299)
		(size 0.4572)
		(drill 0.2032)
		(layers "F.Cu" "B.Cu")
		(net "UART_FT4232_TX_FPGA_RX")
	)
	(via
		(at 89.154 -78.232)
		(size 0.508)
		(drill 0.254)
		(layers "F.Cu" "B.Cu")
		(net "UART_FT4232_TX_FPGA_RX")
	)
	(segment
		(start 56.768746 -85.979)
		(end 56.260746 -85.471)
		(width 0.127)
		(layer "In2.Cu")
		(net "UART_FT4232_TX_FPGA_RX")
	)
	(segment
		(start 53.012848 -85.471)
		(end 52.517548 -84.9757)
		(width 0.127)
		(layer "In2.Cu")
		(net "UART_FT4232_TX_FPGA_RX")
	)
	(segment
		(start 58.42 -85.979)
		(end 56.768746 -85.979)
		(width 0.127)
		(layer "In2.Cu")
		(net "UART_FT4232_TX_FPGA_RX")
	)
	(segment
		(start 85.404452 -78.9305)
		(end 84.959952 -79.375)
		(width 0.127)
		(layer "In2.Cu")
		(net "UART_FT4232_TX_FPGA_RX")
	)
	(segment
		(start 50.8 -85.344)
		(end 45.466 -85.344)
		(width 0.127)
		(layer "In2.Cu")
		(net "UART_FT4232_TX_FPGA_RX")
	)
	(segment
		(start 26.797 -74.422)
		(end 26.035 -73.66)
		(width 0.127)
		(layer "In2.Cu")
		(net "UART_FT4232_TX_FPGA_RX")
	)
	(segment
		(start 89.154 -78.232)
		(end 88.4555 -78.9305)
		(width 0.127)
		(layer "In2.Cu")
		(net "UART_FT4232_TX_FPGA_RX")
	)
	(segment
		(start 52.517548 -84.9757)
		(end 51.1683 -84.9757)
		(width 0.127)
		(layer "In2.Cu")
		(net "UART_FT4232_TX_FPGA_RX")
	)
	(segment
		(start 35.366452 -76.8985)
		(end 34.871152 -76.4032)
		(width 0.127)
		(layer "In2.Cu")
		(net "UART_FT4232_TX_FPGA_RX")
	)
	(segment
		(start 28.829 -74.422)
		(end 26.797 -74.422)
		(width 0.127)
		(layer "In2.Cu")
		(net "UART_FT4232_TX_FPGA_RX")
	)
	(segment
		(start 84.959952 -79.375)
		(end 77.724254 -79.375)
		(width 0.127)
		(layer "In2.Cu")
		(net "UART_FT4232_TX_FPGA_RX")
	)
	(segment
		(start 88.4555 -78.9305)
		(end 85.404452 -78.9305)
		(width 0.127)
		(layer "In2.Cu")
		(net "UART_FT4232_TX_FPGA_RX")
	)
	(segment
		(start 51.1683 -84.9757)
		(end 50.8 -85.344)
		(width 0.127)
		(layer "In2.Cu")
		(net "UART_FT4232_TX_FPGA_RX")
	)
	(segment
		(start 76.581254 -78.232)
		(end 73.873614 -78.232)
		(width 0.127)
		(layer "In2.Cu")
		(net "UART_FT4232_TX_FPGA_RX")
	)
	(segment
		(start 56.260746 -85.471)
		(end 53.012848 -85.471)
		(width 0.127)
		(layer "In2.Cu")
		(net "UART_FT4232_TX_FPGA_RX")
	)
	(segment
		(start 66.888614 -85.217)
		(end 59.182 -85.217)
		(width 0.127)
		(layer "In2.Cu")
		(net "UART_FT4232_TX_FPGA_RX")
	)
	(segment
		(start 59.182 -85.217)
		(end 58.42 -85.979)
		(width 0.127)
		(layer "In2.Cu")
		(net "UART_FT4232_TX_FPGA_RX")
	)
	(segment
		(start 34.871152 -76.4032)
		(end 30.8102 -76.4032)
		(width 0.127)
		(layer "In2.Cu")
		(net "UART_FT4232_TX_FPGA_RX")
	)
	(segment
		(start 73.873614 -78.232)
		(end 66.888614 -85.217)
		(width 0.127)
		(layer "In2.Cu")
		(net "UART_FT4232_TX_FPGA_RX")
	)
	(segment
		(start 40.259 -78.486)
		(end 38.6715 -76.8985)
		(width 0.127)
		(layer "In2.Cu")
		(net "UART_FT4232_TX_FPGA_RX")
	)
	(segment
		(start 30.8102 -76.4032)
		(end 28.829 -74.422)
		(width 0.127)
		(layer "In2.Cu")
		(net "UART_FT4232_TX_FPGA_RX")
	)
	(segment
		(start 40.259 -80.137)
		(end 40.259 -78.486)
		(width 0.127)
		(layer "In2.Cu")
		(net "UART_FT4232_TX_FPGA_RX")
	)
	(segment
		(start 77.724254 -79.375)
		(end 76.581254 -78.232)
		(width 0.127)
		(layer "In2.Cu")
		(net "UART_FT4232_TX_FPGA_RX")
	)
	(segment
		(start 45.466 -85.344)
		(end 40.259 -80.137)
		(width 0.127)
		(layer "In2.Cu")
		(net "UART_FT4232_TX_FPGA_RX")
	)
	(segment
		(start 38.6715 -76.8985)
		(end 35.366452 -76.8985)
		(width 0.127)
		(layer "In2.Cu")
		(net "UART_FT4232_TX_FPGA_RX")
	)
	(segment
		(start 99.692714 -77.9653)
		(end 100.0125 -77.645514)
		(width 0.127)
		(layer "In7.Cu")
		(net "UART_FT4232_TX_FPGA_RX")
	)
	(segment
		(start 110.871 -54.483)
		(end 110.871 -50.038)
		(width 0.127)
		(layer "In7.Cu")
		(net "UART_FT4232_TX_FPGA_RX")
	)
	(segment
		(start 109.855 -61.09843)
		(end 109.855 -54.89956)
		(width 0.127)
		(layer "In7.Cu")
		(net "UART_FT4232_TX_FPGA_RX")
	)
	(segment
		(start 102.87 -70.739)
		(end 103.124 -70.485)
		(width 0.127)
		(layer "In7.Cu")
		(net "UART_FT4232_TX_FPGA_RX")
	)
	(segment
		(start 102.87 -74.422)
		(end 102.87 -70.739)
		(width 0.127)
		(layer "In7.Cu")
		(net "UART_FT4232_TX_FPGA_RX")
	)
	(segment
		(start 90.3351 -79.7941)
		(end 97.4979 -79.7941)
		(width 0.127)
		(layer "In7.Cu")
		(net "UART_FT4232_TX_FPGA_RX")
	)
	(segment
		(start 104.561132 -70.485)
		(end 108.6866 -66.359532)
		(width 0.127)
		(layer "In7.Cu")
		(net "UART_FT4232_TX_FPGA_RX")
	)
	(segment
		(start 110.871 -50.038)
		(end 111.125 -49.784)
		(width 0.127)
		(layer "In7.Cu")
		(net "UART_FT4232_TX_FPGA_RX")
	)
	(segment
		(start 89.154 -78.613)
		(end 90.3351 -79.7941)
		(width 0.127)
		(layer "In7.Cu")
		(net "UART_FT4232_TX_FPGA_RX")
	)
	(segment
		(start 89.154 -78.232)
		(end 89.154 -78.613)
		(width 0.127)
		(layer "In7.Cu")
		(net "UART_FT4232_TX_FPGA_RX")
	)
	(segment
		(start 103.124 -70.485)
		(end 104.561132 -70.485)
		(width 0.127)
		(layer "In7.Cu")
		(net "UART_FT4232_TX_FPGA_RX")
	)
	(segment
		(start 97.4979 -79.7941)
		(end 99.3267 -77.9653)
		(width 0.127)
		(layer "In7.Cu")
		(net "UART_FT4232_TX_FPGA_RX")
	)
	(segment
		(start 111.885984 -49.784)
		(end 112.346994 -49.32299)
		(width 0.127)
		(layer "In7.Cu")
		(net "UART_FT4232_TX_FPGA_RX")
	)
	(segment
		(start 108.6866 -62.26683)
		(end 109.855 -61.09843)
		(width 0.127)
		(layer "In7.Cu")
		(net "UART_FT4232_TX_FPGA_RX")
	)
	(segment
		(start 109.982 -54.77256)
		(end 110.58144 -54.77256)
		(width 0.127)
		(layer "In7.Cu")
		(net "UART_FT4232_TX_FPGA_RX")
	)
	(segment
		(start 100.0125 -77.645514)
		(end 100.0125 -77.2795)
		(width 0.127)
		(layer "In7.Cu")
		(net "UART_FT4232_TX_FPGA_RX")
	)
	(segment
		(start 109.855 -54.89956)
		(end 109.982 -54.77256)
		(width 0.127)
		(layer "In7.Cu")
		(net "UART_FT4232_TX_FPGA_RX")
	)
	(segment
		(start 108.6866 -66.359532)
		(end 108.6866 -62.26683)
		(width 0.127)
		(layer "In7.Cu")
		(net "UART_FT4232_TX_FPGA_RX")
	)
	(segment
		(start 100.0125 -77.2795)
		(end 102.87 -74.422)
		(width 0.127)
		(layer "In7.Cu")
		(net "UART_FT4232_TX_FPGA_RX")
	)
	(segment
		(start 111.125 -49.784)
		(end 111.885984 -49.784)
		(width 0.127)
		(layer "In7.Cu")
		(net "UART_FT4232_TX_FPGA_RX")
	)
	(segment
		(start 110.58144 -54.77256)
		(end 110.871 -54.483)
		(width 0.127)
		(layer "In7.Cu")
		(net "UART_FT4232_TX_FPGA_RX")
	)
	(segment
		(start 99.3267 -77.9653)
		(end 99.692714 -77.9653)
		(width 0.127)
		(layer "In7.Cu")
		(net "UART_FT4232_TX_FPGA_RX")
	)
	(segment
		(start 111.847122 -47.82312)
		(end 112.346994 -48.322992)
		(width 0.11938)
		(layer "F.Cu")
		(net "UART_FT4232_RX_FPGA_TX")
	)
	(segment
		(start 28.575 -74.6506)
		(end 28.575 -73.66)
		(width 0.11938)
		(layer "F.Cu")
		(net "UART_FT4232_RX_FPGA_TX")
	)
	(via
		(at 112.346994 -48.322992)
		(size 0.4572)
		(drill 0.2032)
		(layers "F.Cu" "B.Cu")
		(net "UART_FT4232_RX_FPGA_TX")
	)
	(via
		(at 87.884 -77.851)
		(size 0.508)
		(drill 0.254)
		(layers "F.Cu" "B.Cu")
		(net "UART_FT4232_RX_FPGA_TX")
	)
	(via
		(at 28.575 -73.66)
		(size 0.508)
		(drill 0.254)
		(layers "F.Cu" "B.Cu")
		(net "UART_FT4232_RX_FPGA_TX")
	)
	(segment
		(start 76.835 -77.724)
		(end 77.851 -78.74)
		(width 0.127)
		(layer "In2.Cu")
		(net "UART_FT4232_RX_FPGA_TX")
	)
	(segment
		(start 45.211746 -84.328)
		(end 49.077118 -84.328)
		(width 0.127)
		(layer "In2.Cu")
		(net "UART_FT4232_RX_FPGA_TX")
	)
	(segment
		(start 35.081718 -75.8952)
		(end 35.577018 -76.3905)
		(width 0.127)
		(layer "In2.Cu")
		(net "UART_FT4232_RX_FPGA_TX")
	)
	(segment
		(start 56.979312 -85.471)
		(end 58.166 -85.471)
		(width 0.127)
		(layer "In2.Cu")
		(net "UART_FT4232_RX_FPGA_TX")
	)
	(segment
		(start 31.0642 -75.8952)
		(end 35.081718 -75.8952)
		(width 0.127)
		(layer "In2.Cu")
		(net "UART_FT4232_RX_FPGA_TX")
	)
	(segment
		(start 87.503 -78.232)
		(end 87.884 -77.851)
		(width 0.127)
		(layer "In2.Cu")
		(net "UART_FT4232_RX_FPGA_TX")
	)
	(segment
		(start 85.170264 -78.232)
		(end 87.503 -78.232)
		(width 0.127)
		(layer "In2.Cu")
		(net "UART_FT4232_RX_FPGA_TX")
	)
	(segment
		(start 56.471312 -84.963)
		(end 56.979312 -85.471)
		(width 0.127)
		(layer "In2.Cu")
		(net "UART_FT4232_RX_FPGA_TX")
	)
	(segment
		(start 58.166 -85.471)
		(end 58.928 -84.709)
		(width 0.127)
		(layer "In2.Cu")
		(net "UART_FT4232_RX_FPGA_TX")
	)
	(segment
		(start 40.767 -79.883254)
		(end 45.211746 -84.328)
		(width 0.127)
		(layer "In2.Cu")
		(net "UART_FT4232_RX_FPGA_TX")
	)
	(segment
		(start 38.882066 -76.3905)
		(end 40.767 -78.275434)
		(width 0.127)
		(layer "In2.Cu")
		(net "UART_FT4232_RX_FPGA_TX")
	)
	(segment
		(start 53.223414 -84.963)
		(end 56.471312 -84.963)
		(width 0.127)
		(layer "In2.Cu")
		(net "UART_FT4232_RX_FPGA_TX")
	)
	(segment
		(start 51.237134 -84.4677)
		(end 52.728114 -84.4677)
		(width 0.127)
		(layer "In2.Cu")
		(net "UART_FT4232_RX_FPGA_TX")
	)
	(segment
		(start 58.928 -84.709)
		(end 66.678048 -84.709)
		(width 0.127)
		(layer "In2.Cu")
		(net "UART_FT4232_RX_FPGA_TX")
	)
	(segment
		(start 28.829 -73.66)
		(end 31.0642 -75.8952)
		(width 0.127)
		(layer "In2.Cu")
		(net "UART_FT4232_RX_FPGA_TX")
	)
	(segment
		(start 73.663048 -77.724)
		(end 76.835 -77.724)
		(width 0.127)
		(layer "In2.Cu")
		(net "UART_FT4232_RX_FPGA_TX")
	)
	(segment
		(start 52.728114 -84.4677)
		(end 53.223414 -84.963)
		(width 0.127)
		(layer "In2.Cu")
		(net "UART_FT4232_RX_FPGA_TX")
	)
	(segment
		(start 77.851 -78.74)
		(end 84.662264 -78.74)
		(width 0.127)
		(layer "In2.Cu")
		(net "UART_FT4232_RX_FPGA_TX")
	)
	(segment
		(start 50.440082 -84.328)
		(end 51.097434 -84.328)
		(width 0.127)
		(layer "In2.Cu")
		(net "UART_FT4232_RX_FPGA_TX")
	)
	(segment
		(start 49.995582 -83.8835)
		(end 50.440082 -84.328)
		(width 0.127)
		(layer "In2.Cu")
		(net "UART_FT4232_RX_FPGA_TX")
	)
	(segment
		(start 66.678048 -84.709)
		(end 73.663048 -77.724)
		(width 0.127)
		(layer "In2.Cu")
		(net "UART_FT4232_RX_FPGA_TX")
	)
	(segment
		(start 35.577018 -76.3905)
		(end 38.882066 -76.3905)
		(width 0.127)
		(layer "In2.Cu")
		(net "UART_FT4232_RX_FPGA_TX")
	)
	(segment
		(start 40.767 -78.275434)
		(end 40.767 -79.883254)
		(width 0.127)
		(layer "In2.Cu")
		(net "UART_FT4232_RX_FPGA_TX")
	)
	(segment
		(start 28.575 -73.66)
		(end 28.829 -73.66)
		(width 0.127)
		(layer "In2.Cu")
		(net "UART_FT4232_RX_FPGA_TX")
	)
	(segment
		(start 84.662264 -78.74)
		(end 85.170264 -78.232)
		(width 0.127)
		(layer "In2.Cu")
		(net "UART_FT4232_RX_FPGA_TX")
	)
	(segment
		(start 49.521618 -83.8835)
		(end 49.995582 -83.8835)
		(width 0.127)
		(layer "In2.Cu")
		(net "UART_FT4232_RX_FPGA_TX")
	)
	(segment
		(start 49.077118 -84.328)
		(end 49.521618 -83.8835)
		(width 0.127)
		(layer "In2.Cu")
		(net "UART_FT4232_RX_FPGA_TX")
	)
	(segment
		(start 51.097434 -84.328)
		(end 51.237134 -84.4677)
		(width 0.127)
		(layer "In2.Cu")
		(net "UART_FT4232_RX_FPGA_TX")
	)
	(segment
		(start 102.235 -70.475856)
		(end 102.860856 -69.85)
		(width 0.127)
		(layer "In7.Cu")
		(net "UART_FT4232_RX_FPGA_TX")
	)
	(segment
		(start 102.860856 -69.85)
		(end 104.477566 -69.85)
		(width 0.127)
		(layer "In7.Cu")
		(net "UART_FT4232_RX_FPGA_TX")
	)
	(segment
		(start 88.011 -77.6605)
		(end 89.390982 -77.6605)
		(width 0.127)
		(layer "In7.Cu")
		(net "UART_FT4232_RX_FPGA_TX")
	)
	(segment
		(start 97.2439 -79.2861)
		(end 98.9203 -77.6097)
		(width 0.127)
		(layer "In7.Cu")
		(net "UART_FT4232_RX_FPGA_TX")
	)
	(segment
		(start 101.19868 -71.990458)
		(end 101.32568 -71.863458)
		(width 0.127)
		(layer "In7.Cu")
		(net "UART_FT4232_RX_FPGA_TX")
	)
	(segment
		(start 102.235 -73.895458)
		(end 102.108 -73.768458)
		(width 0.127)
		(layer "In7.Cu")
		(net "UART_FT4232_RX_FPGA_TX")
	)
	(segment
		(start 111.01324 -48.768)
		(end 111.633 -48.768)
		(width 0.127)
		(layer "In7.Cu")
		(net "UART_FT4232_RX_FPGA_TX")
	)
	(segment
		(start 101.32568 -73.133458)
		(end 102.108 -73.133458)
		(width 0.127)
		(layer "In7.Cu")
		(net "UART_FT4232_RX_FPGA_TX")
	)
	(segment
		(start 101.19868 -72.371458)
		(end 101.19868 -71.990458)
		(width 0.127)
		(layer "In7.Cu")
		(net "UART_FT4232_RX_FPGA_TX")
	)
	(segment
		(start 102.108 -73.768458)
		(end 101.32568 -73.768458)
		(width 0.127)
		(layer "In7.Cu")
		(net "UART_FT4232_RX_FPGA_TX")
	)
	(segment
		(start 110.5535 -49.8475)
		(end 110.88624 -49.51476)
		(width 0.127)
		(layer "In7.Cu")
		(net "UART_FT4232_RX_FPGA_TX")
	)
	(segment
		(start 87.884 -77.7875)
		(end 88.011 -77.6605)
		(width 0.127)
		(layer "In7.Cu")
		(net "UART_FT4232_RX_FPGA_TX")
	)
	(segment
		(start 101.32568 -71.863458)
		(end 102.108 -71.863458)
		(width 0.127)
		(layer "In7.Cu")
		(net "UART_FT4232_RX_FPGA_TX")
	)
	(segment
		(start 87.884 -77.851)
		(end 87.884 -77.7875)
		(width 0.127)
		(layer "In7.Cu")
		(net "UART_FT4232_RX_FPGA_TX")
	)
	(segment
		(start 112.078008 -48.322992)
		(end 112.346994 -48.322992)
		(width 0.127)
		(layer "In7.Cu")
		(net "UART_FT4232_RX_FPGA_TX")
	)
	(segment
		(start 111.633 -48.768)
		(end 112.078008 -48.322992)
		(width 0.127)
		(layer "In7.Cu")
		(net "UART_FT4232_RX_FPGA_TX")
	)
	(segment
		(start 109.728 -54.229)
		(end 109.728 -50.038)
		(width 0.127)
		(layer "In7.Cu")
		(net "UART_FT4232_RX_FPGA_TX")
	)
	(segment
		(start 101.19868 -73.260458)
		(end 101.32568 -73.133458)
		(width 0.127)
		(layer "In7.Cu")
		(net "UART_FT4232_RX_FPGA_TX")
	)
	(segment
		(start 109.474 -57.023)
		(end 109.347 -56.896)
		(width 0.127)
		(layer "In7.Cu")
		(net "UART_FT4232_RX_FPGA_TX")
	)
	(segment
		(start 110.88624 -48.895)
		(end 111.01324 -48.768)
		(width 0.127)
		(layer "In7.Cu")
		(net "UART_FT4232_RX_FPGA_TX")
	)
	(segment
		(start 108.1786 -61.484256)
		(end 109.474 -60.188856)
		(width 0.127)
		(layer "In7.Cu")
		(net "UART_FT4232_RX_FPGA_TX")
	)
	(segment
		(start 110.88624 -49.51476)
		(end 110.88624 -48.895)
		(width 0.127)
		(layer "In7.Cu")
		(net "UART_FT4232_RX_FPGA_TX")
	)
	(segment
		(start 101.32568 -72.498458)
		(end 101.19868 -72.371458)
		(width 0.127)
		(layer "In7.Cu")
		(net "UART_FT4232_RX_FPGA_TX")
	)
	(segment
		(start 102.235 -73.006458)
		(end 102.235 -72.625458)
		(width 0.127)
		(layer "In7.Cu")
		(net "UART_FT4232_RX_FPGA_TX")
	)
	(segment
		(start 101.19868 -73.641458)
		(end 101.19868 -73.260458)
		(width 0.127)
		(layer "In7.Cu")
		(net "UART_FT4232_RX_FPGA_TX")
	)
	(segment
		(start 102.108 -72.498458)
		(end 101.32568 -72.498458)
		(width 0.127)
		(layer "In7.Cu")
		(net "UART_FT4232_RX_FPGA_TX")
	)
	(segment
		(start 89.390982 -77.6605)
		(end 89.7255 -77.995018)
		(width 0.127)
		(layer "In7.Cu")
		(net "UART_FT4232_RX_FPGA_TX")
	)
	(segment
		(start 102.108 -73.133458)
		(end 102.235 -73.006458)
		(width 0.127)
		(layer "In7.Cu")
		(net "UART_FT4232_RX_FPGA_TX")
	)
	(segment
		(start 108.1786 -66.148966)
		(end 108.1786 -61.484256)
		(width 0.127)
		(layer "In7.Cu")
		(net "UART_FT4232_RX_FPGA_TX")
	)
	(segment
		(start 99.6569 -76.8731)
		(end 102.235 -74.295)
		(width 0.127)
		(layer "In7.Cu")
		(net "UART_FT4232_RX_FPGA_TX")
	)
	(segment
		(start 99.240086 -76.8731)
		(end 99.6569 -76.8731)
		(width 0.127)
		(layer "In7.Cu")
		(net "UART_FT4232_RX_FPGA_TX")
	)
	(segment
		(start 109.9185 -49.8475)
		(end 110.5535 -49.8475)
		(width 0.127)
		(layer "In7.Cu")
		(net "UART_FT4232_RX_FPGA_TX")
	)
	(segment
		(start 102.235 -71.736458)
		(end 102.235 -70.475856)
		(width 0.127)
		(layer "In7.Cu")
		(net "UART_FT4232_RX_FPGA_TX")
	)
	(segment
		(start 90.923618 -79.2861)
		(end 97.2439 -79.2861)
		(width 0.127)
		(layer "In7.Cu")
		(net "UART_FT4232_RX_FPGA_TX")
	)
	(segment
		(start 89.7255 -78.087982)
		(end 90.923618 -79.2861)
		(width 0.127)
		(layer "In7.Cu")
		(net "UART_FT4232_RX_FPGA_TX")
	)
	(segment
		(start 102.235 -72.625458)
		(end 102.108 -72.498458)
		(width 0.127)
		(layer "In7.Cu")
		(net "UART_FT4232_RX_FPGA_TX")
	)
	(segment
		(start 109.347 -54.61)
		(end 109.728 -54.229)
		(width 0.127)
		(layer "In7.Cu")
		(net "UART_FT4232_RX_FPGA_TX")
	)
	(segment
		(start 102.235 -74.295)
		(end 102.235 -73.895458)
		(width 0.127)
		(layer "In7.Cu")
		(net "UART_FT4232_RX_FPGA_TX")
	)
	(segment
		(start 98.9203 -77.192886)
		(end 99.240086 -76.8731)
		(width 0.127)
		(layer "In7.Cu")
		(net "UART_FT4232_RX_FPGA_TX")
	)
	(segment
		(start 101.32568 -73.768458)
		(end 101.19868 -73.641458)
		(width 0.127)
		(layer "In7.Cu")
		(net "UART_FT4232_RX_FPGA_TX")
	)
	(segment
		(start 104.477566 -69.85)
		(end 108.1786 -66.148966)
		(width 0.127)
		(layer "In7.Cu")
		(net "UART_FT4232_RX_FPGA_TX")
	)
	(segment
		(start 109.347 -56.896)
		(end 109.347 -54.61)
		(width 0.127)
		(layer "In7.Cu")
		(net "UART_FT4232_RX_FPGA_TX")
	)
	(segment
		(start 102.108 -71.863458)
		(end 102.235 -71.736458)
		(width 0.127)
		(layer "In7.Cu")
		(net "UART_FT4232_RX_FPGA_TX")
	)
	(segment
		(start 98.9203 -77.6097)
		(end 98.9203 -77.192886)
		(width 0.127)
		(layer "In7.Cu")
		(net "UART_FT4232_RX_FPGA_TX")
	)
	(segment
		(start 109.474 -60.188856)
		(end 109.474 -57.023)
		(width 0.127)
		(layer "In7.Cu")
		(net "UART_FT4232_RX_FPGA_TX")
	)
	(segment
		(start 89.7255 -77.995018)
		(end 89.7255 -78.087982)
		(width 0.127)
		(layer "In7.Cu")
		(net "UART_FT4232_RX_FPGA_TX")
	)
	(segment
		(start 109.728 -50.038)
		(end 109.9185 -49.8475)
		(width 0.127)
		(layer "In7.Cu")
		(net "UART_FT4232_RX_FPGA_TX")
	)
	(segment
		(start 87.441024 -70.231)
		(end 87.441024 -67.93992)
		(width 0.11938)
		(layer "F.Cu")
		(net "SN_EEPROM_WP")
	)
	(segment
		(start 87.503 -67.877944)
		(end 87.503 -67.31)
		(width 0.11938)
		(layer "F.Cu")
		(net "SN_EEPROM_WP")
	)
	(segment
		(start 29.26588 -19.14144)
		(end 29.81198 -19.14144)
		(width 0.11938)
		(layer "F.Cu")
		(net "SN_EEPROM_WP")
	)
	(segment
		(start 27.1907 -18.50136)
		(end 28.6258 -18.50136)
		(width 0.11938)
		(layer "F.Cu")
		(net "SN_EEPROM_WP")
	)
	(segment
		(start 87.441024 -67.93992)
		(end 87.503 -67.877944)
		(width 0.11938)
		(layer "F.Cu")
		(net "SN_EEPROM_WP")
	)
	(segment
		(start 28.67152 -18.54708)
		(end 29.26588 -19.14144)
		(width 0.11938)
		(layer "F.Cu")
		(net "SN_EEPROM_WP")
	)
	(segment
		(start 28.6258 -18.50136)
		(end 28.67152 -18.54708)
		(width 0.11938)
		(layer "F.Cu")
		(net "SN_EEPROM_WP")
	)
	(via
		(at 77.089 -41.656)
		(size 0.508)
		(drill 0.254)
		(layers "F.Cu" "B.Cu")
		(net "SN_EEPROM_WP")
	)
	(via
		(at 28.67152 -18.54708)
		(size 0.4572)
		(drill 0.2032)
		(layers "F.Cu" "B.Cu")
		(net "SN_EEPROM_WP")
	)
	(segment
		(start 27.432 -18.2372)
		(end 28.36164 -18.2372)
		(width 0.11938)
		(layer "B.Cu")
		(net "SN_EEPROM_WP")
	)
	(segment
		(start 29.81198 -17.99844)
		(end 29.22016 -17.99844)
		(width 0.11938)
		(layer "B.Cu")
		(net "SN_EEPROM_WP")
	)
	(segment
		(start 28.36164 -18.2372)
		(end 28.67152 -18.54708)
		(width 0.11938)
		(layer "B.Cu")
		(net "SN_EEPROM_WP")
	)
	(segment
		(start 29.22016 -17.99844)
		(end 28.67152 -18.54708)
		(width 0.11938)
		(layer "B.Cu")
		(net "SN_EEPROM_WP")
	)
	(segment
		(start 84.709 -73.787)
		(end 84.201 -73.279)
		(width 0.127)
		(layer "In2.Cu")
		(net "SN_EEPROM_WP")
	)
	(segment
		(start 87.376 -75.819)
		(end 85.217 -75.819)
		(width 0.127)
		(layer "In2.Cu")
		(net "SN_EEPROM_WP")
	)
	(segment
		(start 84.709 -75.311)
		(end 84.709 -73.787)
		(width 0.127)
		(layer "In2.Cu")
		(net "SN_EEPROM_WP")
	)
	(segment
		(start 77.5335 -44.683934)
		(end 76.962 -44.112434)
		(width 0.127)
		(layer "In2.Cu")
		(net "SN_EEPROM_WP")
	)
	(segment
		(start 88.011 -73.66)
		(end 88.011 -75.184)
		(width 0.127)
		(layer "In2.Cu")
		(net "SN_EEPROM_WP")
	)
	(segment
		(start 76.962 -44.112434)
		(end 76.962 -41.783)
		(width 0.127)
		(layer "In2.Cu")
		(net "SN_EEPROM_WP")
	)
	(segment
		(start 81.026 -73.279)
		(end 77.017118 -69.270118)
		(width 0.127)
		(layer "In2.Cu")
		(net "SN_EEPROM_WP")
	)
	(segment
		(start 76.962 -41.783)
		(end 77.089 -41.656)
		(width 0.127)
		(layer "In2.Cu")
		(net "SN_EEPROM_WP")
	)
	(segment
		(start 84.201 -73.279)
		(end 81.026 -73.279)
		(width 0.127)
		(layer "In2.Cu")
		(net "SN_EEPROM_WP")
	)
	(segment
		(start 77.017118 -50.618136)
		(end 77.5335 -50.101754)
		(width 0.127)
		(layer "In2.Cu")
		(net "SN_EEPROM_WP")
	)
	(segment
		(start 77.017118 -69.270118)
		(end 77.017118 -50.618136)
		(width 0.127)
		(layer "In2.Cu")
		(net "SN_EEPROM_WP")
	)
	(segment
		(start 87.503 -67.31)
		(end 87.503 -73.152)
		(width 0.127)
		(layer "In2.Cu")
		(net "SN_EEPROM_WP")
	)
	(segment
		(start 85.217 -75.819)
		(end 84.709 -75.311)
		(width 0.127)
		(layer "In2.Cu")
		(net "SN_EEPROM_WP")
	)
	(segment
		(start 88.011 -75.184)
		(end 87.376 -75.819)
		(width 0.127)
		(layer "In2.Cu")
		(net "SN_EEPROM_WP")
	)
	(segment
		(start 77.5335 -50.101754)
		(end 77.5335 -44.683934)
		(width 0.127)
		(layer "In2.Cu")
		(net "SN_EEPROM_WP")
	)
	(segment
		(start 87.503 -73.152)
		(end 88.011 -73.66)
		(width 0.127)
		(layer "In2.Cu")
		(net "SN_EEPROM_WP")
	)
	(segment
		(start 37.846 -18.415)
		(end 38.608 -18.415)
		(width 0.127)
		(layer "In7.Cu")
		(net "SN_EEPROM_WP")
	)
	(segment
		(start 36.449 -17.018)
		(end 37.846 -18.415)
		(width 0.127)
		(layer "In7.Cu")
		(net "SN_EEPROM_WP")
	)
	(segment
		(start 28.67152 -18.54708)
		(end 30.85592 -18.54708)
		(width 0.127)
		(layer "In7.Cu")
		(net "SN_EEPROM_WP")
	)
	(segment
		(start 30.85592 -18.54708)
		(end 31.6865 -17.7165)
		(width 0.127)
		(layer "In7.Cu")
		(net "SN_EEPROM_WP")
	)
	(segment
		(start 39.116 -18.923)
		(end 39.116 -21.3106)
		(width 0.127)
		(layer "In7.Cu")
		(net "SN_EEPROM_WP")
	)
	(segment
		(start 34.2265 -17.7165)
		(end 34.925 -17.018)
		(width 0.127)
		(layer "In7.Cu")
		(net "SN_EEPROM_WP")
	)
	(segment
		(start 70.104 -41.656)
		(end 77.089 -41.656)
		(width 0.127)
		(layer "In7.Cu")
		(net "SN_EEPROM_WP")
	)
	(segment
		(start 38.608 -18.415)
		(end 39.116 -18.923)
		(width 0.127)
		(layer "In7.Cu")
		(net "SN_EEPROM_WP")
	)
	(segment
		(start 44.125134 -26.319734)
		(end 54.767734 -26.319734)
		(width 0.127)
		(layer "In7.Cu")
		(net "SN_EEPROM_WP")
	)
	(segment
		(start 39.116 -21.3106)
		(end 44.125134 -26.319734)
		(width 0.127)
		(layer "In7.Cu")
		(net "SN_EEPROM_WP")
	)
	(segment
		(start 54.767734 -26.319734)
		(end 70.104 -41.656)
		(width 0.127)
		(layer "In7.Cu")
		(net "SN_EEPROM_WP")
	)
	(segment
		(start 34.925 -17.018)
		(end 36.449 -17.018)
		(width 0.127)
		(layer "In7.Cu")
		(net "SN_EEPROM_WP")
	)
	(segment
		(start 31.6865 -17.7165)
		(end 34.2265 -17.7165)
		(width 0.127)
		(layer "In7.Cu")
		(net "SN_EEPROM_WP")
	)
	(segment
		(start 85.471 -74.93)
		(end 86.60892 -74.93)
		(width 0.11938)
		(layer "F.Cu")
		(net "SEC_EEPROM_WP")
	)
	(segment
		(start 86.60892 -74.93)
		(end 87.441024 -74.097896)
		(width 0.11938)
		(layer "F.Cu")
		(net "SEC_EEPROM_WP")
	)
	(segment
		(start 20.01012 -16.58112)
		(end 19.177 -15.748)
		(width 0.11938)
		(layer "F.Cu")
		(net "SEC_EEPROM_WP")
	)
	(segment
		(start 87.441024 -74.097896)
		(end 87.441024 -72.771)
		(width 0.11938)
		(layer "F.Cu")
		(net "SEC_EEPROM_WP")
	)
	(segment
		(start 20.01012 -17.9959)
		(end 20.01012 -16.58112)
		(width 0.11938)
		(layer "F.Cu")
		(net "SEC_EEPROM_WP")
	)
	(via
		(at 85.471 -74.93)
		(size 0.4572)
		(drill 0.2032)
		(layers "F.Cu" "B.Cu")
		(net "SEC_EEPROM_WP")
	)
	(via
		(at 78.105 -40.767)
		(size 0.508)
		(drill 0.254)
		(layers "F.Cu" "B.Cu")
		(net "SEC_EEPROM_WP")
	)
	(segment
		(start 20.2946 -18.0594)
		(end 20.5486 -17.8054)
		(width 0.11938)
		(layer "B.Cu")
		(net "SEC_EEPROM_WP")
	)
	(segment
		(start 19.431 -15.748)
		(end 20.5486 -16.8656)
		(width 0.11938)
		(layer "B.Cu")
		(net "SEC_EEPROM_WP")
	)
	(segment
		(start 20.2946 -18.0594)
		(end 21.4884 -18.0594)
		(width 0.11938)
		(layer "B.Cu")
		(net "SEC_EEPROM_WP")
	)
	(segment
		(start 20.5486 -17.8054)
		(end 20.5486 -16.891)
		(width 0.11938)
		(layer "B.Cu")
		(net "SEC_EEPROM_WP")
	)
	(segment
		(start 20.5486 -16.8656)
		(end 20.5486 -16.891)
		(width 0.11938)
		(layer "B.Cu")
		(net "SEC_EEPROM_WP")
	)
	(segment
		(start 19.177 -15.748)
		(end 19.431 -15.748)
		(width 0.11938)
		(layer "B.Cu")
		(net "SEC_EEPROM_WP")
	)
	(segment
		(start 21.4884 -18.0594)
		(end 21.5138 -18.034)
		(width 0.11938)
		(layer "B.Cu")
		(net "SEC_EEPROM_WP")
	)
	(segment
		(start 85.471 -74.93)
		(end 85.471 -73.914)
		(width 0.127)
		(layer "In2.Cu")
		(net "SEC_EEPROM_WP")
	)
	(segment
		(start 81.407 -72.898)
		(end 78.486 -69.977)
		(width 0.127)
		(layer "In2.Cu")
		(net "SEC_EEPROM_WP")
	)
	(segment
		(start 85.471 -73.914)
		(end 84.455 -72.898)
		(width 0.127)
		(layer "In2.Cu")
		(net "SEC_EEPROM_WP")
	)
	(segment
		(start 84.455 -72.898)
		(end 81.407 -72.898)
		(width 0.127)
		(layer "In2.Cu")
		(net "SEC_EEPROM_WP")
	)
	(segment
		(start 77.398118 -51.125628)
		(end 77.9145 -50.609246)
		(width 0.127)
		(layer "In2.Cu")
		(net "SEC_EEPROM_WP")
	)
	(segment
		(start 77.398118 -66.051684)
		(end 77.398118 -51.125628)
		(width 0.127)
		(layer "In2.Cu")
		(net "SEC_EEPROM_WP")
	)
	(segment
		(start 78.74 -43.477434)
		(end 78.74 -42.845482)
		(width 0.127)
		(layer "In2.Cu")
		(net "SEC_EEPROM_WP")
	)
	(segment
		(start 77.851 -41.956482)
		(end 77.851 -41.021)
		(width 0.127)
		(layer "In2.Cu")
		(net "SEC_EEPROM_WP")
	)
	(segment
		(start 78.486 -67.139566)
		(end 77.398118 -66.051684)
		(width 0.127)
		(layer "In2.Cu")
		(net "SEC_EEPROM_WP")
	)
	(segment
		(start 77.9145 -50.609246)
		(end 77.9145 -44.302934)
		(width 0.127)
		(layer "In2.Cu")
		(net "SEC_EEPROM_WP")
	)
	(segment
		(start 78.74 -42.845482)
		(end 77.851 -41.956482)
		(width 0.127)
		(layer "In2.Cu")
		(net "SEC_EEPROM_WP")
	)
	(segment
		(start 78.486 -69.977)
		(end 78.486 -67.139566)
		(width 0.127)
		(layer "In2.Cu")
		(net "SEC_EEPROM_WP")
	)
	(segment
		(start 77.851 -41.021)
		(end 78.105 -40.767)
		(width 0.127)
		(layer "In2.Cu")
		(net "SEC_EEPROM_WP")
	)
	(segment
		(start 77.9145 -44.302934)
		(end 78.74 -43.477434)
		(width 0.127)
		(layer "In2.Cu")
		(net "SEC_EEPROM_WP")
	)
	(segment
		(start 69.85 -40.64)
		(end 77.978 -40.64)
		(width 0.127)
		(layer "In7.Cu")
		(net "SEC_EEPROM_WP")
	)
	(segment
		(start 30.464506 -16.27124)
		(end 31.749746 -14.986)
		(width 0.127)
		(layer "In7.Cu")
		(net "SEC_EEPROM_WP")
	)
	(segment
		(start 54.991 -25.781)
		(end 69.85 -40.64)
		(width 0.127)
		(layer "In7.Cu")
		(net "SEC_EEPROM_WP")
	)
	(segment
		(start 37.1729 -15.648686)
		(end 37.1729 -16.101314)
		(width 0.127)
		(layer "In7.Cu")
		(net "SEC_EEPROM_WP")
	)
	(segment
		(start 39.624 -21.0566)
		(end 44.3484 -25.781)
		(width 0.127)
		(layer "In7.Cu")
		(net "SEC_EEPROM_WP")
	)
	(segment
		(start 21.336 -16.637)
		(end 22.098 -16.637)
		(width 0.127)
		(layer "In7.Cu")
		(net "SEC_EEPROM_WP")
	)
	(segment
		(start 38.943534 -16.4211)
		(end 39.9796 -17.457166)
		(width 0.127)
		(layer "In7.Cu")
		(net "SEC_EEPROM_WP")
	)
	(segment
		(start 22.098 -16.637)
		(end 22.46376 -16.27124)
		(width 0.127)
		(layer "In7.Cu")
		(net "SEC_EEPROM_WP")
	)
	(segment
		(start 37.492686 -16.4211)
		(end 38.943534 -16.4211)
		(width 0.127)
		(layer "In7.Cu")
		(net "SEC_EEPROM_WP")
	)
	(segment
		(start 31.749746 -14.986)
		(end 36.510214 -14.986)
		(width 0.127)
		(layer "In7.Cu")
		(net "SEC_EEPROM_WP")
	)
	(segment
		(start 37.1729 -16.101314)
		(end 37.492686 -16.4211)
		(width 0.127)
		(layer "In7.Cu")
		(net "SEC_EEPROM_WP")
	)
	(segment
		(start 36.510214 -14.986)
		(end 37.1729 -15.648686)
		(width 0.127)
		(layer "In7.Cu")
		(net "SEC_EEPROM_WP")
	)
	(segment
		(start 44.3484 -25.781)
		(end 54.991 -25.781)
		(width 0.127)
		(layer "In7.Cu")
		(net "SEC_EEPROM_WP")
	)
	(segment
		(start 39.9796 -17.457166)
		(end 39.9796 -18.4404)
		(width 0.127)
		(layer "In7.Cu")
		(net "SEC_EEPROM_WP")
	)
	(segment
		(start 39.9796 -18.4404)
		(end 39.624 -18.796)
		(width 0.127)
		(layer "In7.Cu")
		(net "SEC_EEPROM_WP")
	)
	(segment
		(start 39.624 -18.796)
		(end 39.624 -21.0566)
		(width 0.127)
		(layer "In7.Cu")
		(net "SEC_EEPROM_WP")
	)
	(segment
		(start 19.177 -15.748)
		(end 20.447 -15.748)
		(width 0.127)
		(layer "In7.Cu")
		(net "SEC_EEPROM_WP")
	)
	(segment
		(start 77.978 -40.64)
		(end 78.105 -40.767)
		(width 0.127)
		(layer "In7.Cu")
		(net "SEC_EEPROM_WP")
	)
	(segment
		(start 20.447 -15.748)
		(end 21.336 -16.637)
		(width 0.127)
		(layer "In7.Cu")
		(net "SEC_EEPROM_WP")
	)
	(segment
		(start 22.46376 -16.27124)
		(end 30.464506 -16.27124)
		(width 0.127)
		(layer "In7.Cu")
		(net "SEC_EEPROM_WP")
	)
	(segment
		(start 18.710148 -19.008852)
		(end 18.710148 -17.9959)
		(width 0.11938)
		(layer "F.Cu")
		(net "SEC_EEPROM_SDA")
	)
	(segment
		(start 18.161 -19.558)
		(end 18.710148 -19.008852)
		(width 0.11938)
		(layer "F.Cu")
		(net "SEC_EEPROM_SDA")
	)
	(via
		(at 18.161 -19.558)
		(size 0.508)
		(drill 0.254)
		(layers "F.Cu" "B.Cu")
		(net "SEC_EEPROM_SDA")
	)
	(segment
		(start 18.161 -19.558)
		(end 18.3134 -19.7104)
		(width 0.11938)
		(layer "B.Cu")
		(net "SEC_EEPROM_SDA")
	)
	(segment
		(start 18.3134 -19.7104)
		(end 18.3134 -20.7518)
		(width 0.11938)
		(layer "B.Cu")
		(net "SEC_EEPROM_SDA")
	)
	(segment
		(start 28.774136 -90.8812)
		(end 28.774136 -91.765882)
		(width 0.14478)
		(layer "F.Cu")
		(net "R_FT_USB_DP")
	)
	(segment
		(start 28.5496 -92.957142)
		(end 28.5496 -93.133164)
		(width 0.14478)
		(layer "F.Cu")
		(net "R_FT_USB_DP")
	)
	(segment
		(start 28.816554 -91.868244)
		(end 28.822904 -91.874594)
		(width 0.14478)
		(layer "F.Cu")
		(net "R_FT_USB_DP")
	)
	(segment
		(start 28.82392 -91.882976)
		(end 28.82392 -92.294964)
		(width 0.14478)
		(layer "F.Cu")
		(net "R_FT_USB_DP")
	)
	(segment
		(start 28.475432 -93.292168)
		(end 28.067 -93.7006)
		(width 0.14478)
		(layer "F.Cu")
		(net "R_FT_USB_DP")
	)
	(segment
		(start 28.709366 -92.585286)
		(end 28.68676 -92.609416)
		(width 0.14478)
		(layer "F.Cu")
		(net "R_FT_USB_DP")
	)
	(arc
		(start 28.5496 -93.133164)
		(mid 28.548517 -93.150949)
		(end 28.545282 -93.16847)
		(width 0.14478)
		(layer "F.Cu")
		(net "R_FT_USB_DP")
	)
	(arc
		(start 28.82392 -92.294964)
		(mid 28.794248 -92.451018)
		(end 28.709366 -92.585286)
		(width 0.14478)
		(layer "F.Cu")
		(net "R_FT_USB_DP")
	)
	(arc
		(start 28.545282 -93.16847)
		(mid 28.518791 -93.235081)
		(end 28.475432 -93.292168)
		(width 0.14478)
		(layer "F.Cu")
		(net "R_FT_USB_DP")
	)
	(arc
		(start 28.82392 -91.87561)
		(mid 28.823897 -91.879293)
		(end 28.82392 -91.882976)
		(width 0.14478)
		(layer "F.Cu")
		(net "R_FT_USB_DP")
	)
	(arc
		(start 28.822904 -91.874594)
		(mid 28.823413 -91.875101)
		(end 28.82392 -91.87561)
		(width 0.14478)
		(layer "F.Cu")
		(net "R_FT_USB_DP")
	)
	(arc
		(start 28.68676 -92.609416)
		(mid 28.585113 -92.770238)
		(end 28.5496 -92.957142)
		(width 0.14478)
		(layer "F.Cu")
		(net "R_FT_USB_DP")
	)
	(arc
		(start 28.774136 -91.765882)
		(mid 28.785157 -91.821287)
		(end 28.816554 -91.868244)
		(width 0.14478)
		(layer "F.Cu")
		(net "R_FT_USB_DP")
	)
	(segment
		(start 29.044392 -93.408246)
		(end 29.337 -93.7006)
		(width 0.14478)
		(layer "F.Cu")
		(net "R_FT_USB_DM")
	)
	(segment
		(start 28.975812 -92.858336)
		(end 28.965398 -92.869766)
		(width 0.14478)
		(layer "F.Cu")
		(net "R_FT_USB_DM")
	)
	(segment
		(start 28.9306 -92.957142)
		(end 28.9306 -93.133164)
		(width 0.14478)
		(layer "F.Cu")
		(net "R_FT_USB_DM")
	)
	(segment
		(start 29.274262 -90.8812)
		(end 29.274262 -91.765882)
		(width 0.14478)
		(layer "F.Cu")
		(net "R_FT_USB_DM")
	)
	(segment
		(start 29.20492 -91.900248)
		(end 29.20492 -92.294964)
		(width 0.14478)
		(layer "F.Cu")
		(net "R_FT_USB_DM")
	)
	(segment
		(start 28.98775 -92.84589)
		(end 28.975812 -92.858336)
		(width 0.14478)
		(layer "F.Cu")
		(net "R_FT_USB_DM")
	)
	(segment
		(start 29.231844 -91.868244)
		(end 29.22524 -91.874848)
		(width 0.14478)
		(layer "F.Cu")
		(net "R_FT_USB_DM")
	)
	(arc
		(start 29.20492 -92.294964)
		(mid 29.148777 -92.591109)
		(end 28.98775 -92.84589)
		(width 0.14478)
		(layer "F.Cu")
		(net "R_FT_USB_DM")
	)
	(arc
		(start 28.965398 -92.869766)
		(mid 28.939689 -92.910147)
		(end 28.9306 -92.957142)
		(width 0.14478)
		(layer "F.Cu")
		(net "R_FT_USB_DM")
	)
	(arc
		(start 29.274262 -91.765882)
		(mid 29.263241 -91.821287)
		(end 29.231844 -91.868244)
		(width 0.14478)
		(layer "F.Cu")
		(net "R_FT_USB_DM")
	)
	(arc
		(start 28.9306 -93.133164)
		(mid 28.960118 -93.282033)
		(end 29.044392 -93.408246)
		(width 0.14478)
		(layer "F.Cu")
		(net "R_FT_USB_DM")
	)
	(arc
		(start 29.22524 -91.874848)
		(mid 29.214357 -91.88697)
		(end 29.20492 -91.900248)
		(width 0.14478)
		(layer "F.Cu")
		(net "R_FT_USB_DM")
	)
	(segment
		(start 21.082 -87.63)
		(end 21.266658 -87.814658)
		(width 0.11938)
		(layer "F.Cu")
		(net "R_FT4232_TMS")
	)
	(segment
		(start 21.082 -87.503)
		(end 21.082 -87.63)
		(width 0.11938)
		(layer "F.Cu")
		(net "R_FT4232_TMS")
	)
	(segment
		(start 21.266658 -87.814658)
		(end 22.7076 -87.814658)
		(width 0.11938)
		(layer "F.Cu")
		(net "R_FT4232_TMS")
	)
	(via
		(at 21.082 -87.503)
		(size 0.508)
		(drill 0.254)
		(layers "F.Cu" "B.Cu")
		(net "R_FT4232_TMS")
	)
	(segment
		(start 21.082 -87.375746)
		(end 21.843746 -86.614)
		(width 0.11938)
		(layer "B.Cu")
		(net "R_FT4232_TMS")
	)
	(segment
		(start 21.082 -87.503)
		(end 21.082 -87.375746)
		(width 0.11938)
		(layer "B.Cu")
		(net "R_FT4232_TMS")
	)
	(segment
		(start 21.843746 -86.614)
		(end 22.0726 -86.614)
		(width 0.11938)
		(layer "B.Cu")
		(net "R_FT4232_TMS")
	)
	(segment
		(start 20.193 -88.519)
		(end 20.39747 -88.31453)
		(width 0.11938)
		(layer "F.Cu")
		(net "R_FT4232_TDO")
	)
	(segment
		(start 20.39747 -88.31453)
		(end 22.7076 -88.31453)
		(width 0.11938)
		(layer "F.Cu")
		(net "R_FT4232_TDO")
	)
	(via
		(at 20.193 -88.519)
		(size 0.508)
		(drill 0.254)
		(layers "F.Cu" "B.Cu")
		(net "R_FT4232_TDO")
	)
	(segment
		(start 20.52447 -88.519)
		(end 20.65147 -88.646)
		(width 0.11938)
		(layer "B.Cu")
		(net "R_FT4232_TDO")
	)
	(segment
		(start 20.65147 -88.646)
		(end 21.59 -88.646)
		(width 0.11938)
		(layer "B.Cu")
		(net "R_FT4232_TDO")
	)
	(segment
		(start 22.0726 -87.757)
		(end 22.0726 -88.9)
		(width 0.11938)
		(layer "B.Cu")
		(net "R_FT4232_TDO")
	)
	(segment
		(start 20.193 -88.519)
		(end 20.52447 -88.519)
		(width 0.11938)
		(layer "B.Cu")
		(net "R_FT4232_TDO")
	)
	(segment
		(start 21.844 -88.9)
		(end 22.0726 -88.9)
		(width 0.11938)
		(layer "B.Cu")
		(net "R_FT4232_TDO")
	)
	(segment
		(start 21.59 -88.646)
		(end 21.844 -88.9)
		(width 0.11938)
		(layer "B.Cu")
		(net "R_FT4232_TDO")
	)
	(segment
		(start 21.082 -89.535)
		(end 21.082 -89.408)
		(width 0.11938)
		(layer "F.Cu")
		(net "R_FT4232_TDI")
	)
	(segment
		(start 21.776944 -88.814656)
		(end 22.7076 -88.814656)
		(width 0.11938)
		(layer "F.Cu")
		(net "R_FT4232_TDI")
	)
	(segment
		(start 21.209 -89.281)
		(end 21.3106 -89.281)
		(width 0.11938)
		(layer "F.Cu")
		(net "R_FT4232_TDI")
	)
	(segment
		(start 21.082 -89.408)
		(end 21.209 -89.281)
		(width 0.11938)
		(layer "F.Cu")
		(net "R_FT4232_TDI")
	)
	(segment
		(start 21.3106 -89.281)
		(end 21.776944 -88.814656)
		(width 0.11938)
		(layer "F.Cu")
		(net "R_FT4232_TDI")
	)
	(via
		(at 21.082 -89.535)
		(size 0.508)
		(drill 0.254)
		(layers "F.Cu" "B.Cu")
		(net "R_FT4232_TDI")
	)
	(segment
		(start 20.976082 -89.810082)
		(end 21.4122 -90.2462)
		(width 0.11938)
		(layer "B.Cu")
		(net "R_FT4232_TDI")
	)
	(segment
		(start 21.4122 -90.2462)
		(end 22.4028 -90.2462)
		(width 0.11938)
		(layer "B.Cu")
		(net "R_FT4232_TDI")
	)
	(segment
		(start 21.082 -89.535)
		(end 20.976082 -89.640918)
		(width 0.11938)
		(layer "B.Cu")
		(net "R_FT4232_TDI")
	)
	(segment
		(start 20.976082 -89.640918)
		(end 20.976082 -89.810082)
		(width 0.11938)
		(layer "B.Cu")
		(net "R_FT4232_TDI")
	)
	(segment
		(start 24.774144 -89.721944)
		(end 24.774144 -90.8812)
		(width 0.11938)
		(layer "F.Cu")
		(net "R_FT4232_TCK")
	)
	(segment
		(start 24.1554 -89.3826)
		(end 24.4348 -89.3826)
		(width 0.11938)
		(layer "F.Cu")
		(net "R_FT4232_TCK")
	)
	(segment
		(start 24.4348 -89.3826)
		(end 24.774144 -89.721944)
		(width 0.11938)
		(layer "F.Cu")
		(net "R_FT4232_TCK")
	)
	(via
		(at 24.1554 -89.3826)
		(size 0.508)
		(drill 0.254)
		(layers "F.Cu" "B.Cu")
		(net "R_FT4232_TCK")
	)
	(segment
		(start 24.13 -89.408)
		(end 24.13 -90.5256)
		(width 0.11938)
		(layer "B.Cu")
		(net "R_FT4232_TCK")
	)
	(segment
		(start 24.1554 -89.3826)
		(end 24.13 -89.408)
		(width 0.11938)
		(layer "B.Cu")
		(net "R_FT4232_TCK")
	)
	(segment
		(start 20.64258 -82.869786)
		(end 21.069554 -83.29676)
		(width 0.11938)
		(layer "F.Cu")
		(net "R_FT4232_I2C_SDA_OUT")
	)
	(segment
		(start 18.9484 -81.28)
		(end 20.5232 -81.28)
		(width 0.11938)
		(layer "F.Cu")
		(net "R_FT4232_I2C_SDA_OUT")
	)
	(segment
		(start 20.64258 -81.39938)
		(end 20.64258 -82.869786)
		(width 0.11938)
		(layer "F.Cu")
		(net "R_FT4232_I2C_SDA_OUT")
	)
	(segment
		(start 21.58746 -83.814666)
		(end 21.069554 -83.29676)
		(width 0.11938)
		(layer "F.Cu")
		(net "R_FT4232_I2C_SDA_OUT")
	)
	(segment
		(start 20.5232 -81.28)
		(end 20.64258 -81.39938)
		(width 0.11938)
		(layer "F.Cu")
		(net "R_FT4232_I2C_SDA_OUT")
	)
	(segment
		(start 22.7076 -83.814666)
		(end 21.58746 -83.814666)
		(width 0.11938)
		(layer "F.Cu")
		(net "R_FT4232_I2C_SDA_OUT")
	)
	(via
		(at 21.069554 -83.29676)
		(size 0.508)
		(drill 0.254)
		(layers "F.Cu" "B.Cu")
		(net "R_FT4232_I2C_SDA_OUT")
	)
	(segment
		(start 20.066 -80.137)
		(end 21.082 -81.153)
		(width 0.11938)
		(layer "F.Cu")
		(net "R_FT4232_I2C_SDA_IN")
	)
	(segment
		(start 21.082 -82.423)
		(end 21.97354 -83.31454)
		(width 0.11938)
		(layer "F.Cu")
		(net "R_FT4232_I2C_SDA_IN")
	)
	(segment
		(start 21.082 -81.153)
		(end 21.082 -82.423)
		(width 0.11938)
		(layer "F.Cu")
		(net "R_FT4232_I2C_SDA_IN")
	)
	(segment
		(start 21.97354 -83.31454)
		(end 22.7076 -83.31454)
		(width 0.11938)
		(layer "F.Cu")
		(net "R_FT4232_I2C_SDA_IN")
	)
	(via
		(at 20.066 -80.137)
		(size 0.508)
		(drill 0.254)
		(layers "F.Cu" "B.Cu")
		(net "R_FT4232_I2C_SDA_IN")
	)
	(segment
		(start 18.9484 -80.137)
		(end 20.066 -80.137)
		(width 0.11938)
		(layer "B.Cu")
		(net "R_FT4232_I2C_SDA_IN")
	)
	(segment
		(start 20.574 -84.195158)
		(end 20.574 -83.693254)
		(width 0.11938)
		(layer "F.Cu")
		(net "R_FT4232_I2C_SCL")
	)
	(segment
		(start 19.97329 -83.092544)
		(end 19.97329 -82.420968)
		(width 0.11938)
		(layer "F.Cu")
		(net "R_FT4232_I2C_SCL")
	)
	(segment
		(start 19.971258 -82.423)
		(end 19.97329 -82.420968)
		(width 0.11938)
		(layer "F.Cu")
		(net "R_FT4232_I2C_SCL")
	)
	(segment
		(start 20.69338 -84.314538)
		(end 20.574 -84.195158)
		(width 0.11938)
		(layer "F.Cu")
		(net "R_FT4232_I2C_SCL")
	)
	(segment
		(start 20.574 -83.693254)
		(end 19.97329 -83.092544)
		(width 0.11938)
		(layer "F.Cu")
		(net "R_FT4232_I2C_SCL")
	)
	(segment
		(start 18.9484 -82.423)
		(end 19.971258 -82.423)
		(width 0.11938)
		(layer "F.Cu")
		(net "R_FT4232_I2C_SCL")
	)
	(segment
		(start 22.7076 -84.314538)
		(end 20.69338 -84.314538)
		(width 0.11938)
		(layer "F.Cu")
		(net "R_FT4232_I2C_SCL")
	)
	(via
		(at 19.97329 -82.420968)
		(size 0.508)
		(drill 0.254)
		(layers "F.Cu" "B.Cu")
		(net "R_FT4232_I2C_SCL")
	)
	(segment
		(start 32.004 -80.772)
		(end 32.274256 -80.501744)
		(width 0.11938)
		(layer "F.Cu")
		(net "R_FT4232_CHD_TX")
	)
	(segment
		(start 32.274256 -80.501744)
		(end 32.274256 -79.248)
		(width 0.11938)
		(layer "F.Cu")
		(net "R_FT4232_CHD_TX")
	)
	(via
		(at 32.004 -80.772)
		(size 0.508)
		(drill 0.254)
		(layers "F.Cu" "B.Cu")
		(net "R_FT4232_CHD_TX")
	)
	(segment
		(start 32.512 -80.264)
		(end 32.512 -79.6544)
		(width 0.11938)
		(layer "B.Cu")
		(net "R_FT4232_CHD_TX")
	)
	(segment
		(start 32.004 -80.772)
		(end 32.512 -80.264)
		(width 0.11938)
		(layer "B.Cu")
		(net "R_FT4232_CHD_TX")
	)
	(segment
		(start 32.893 -83.312)
		(end 33.390332 -82.814668)
		(width 0.11938)
		(layer "F.Cu")
		(net "R_FT4232_CHD_RX")
	)
	(segment
		(start 33.390332 -82.814668)
		(end 34.3408 -82.814668)
		(width 0.11938)
		(layer "F.Cu")
		(net "R_FT4232_CHD_RX")
	)
	(via
		(at 32.893 -83.312)
		(size 0.508)
		(drill 0.254)
		(layers "F.Cu" "B.Cu")
		(net "R_FT4232_CHD_RX")
	)
	(segment
		(start 32.893 -83.312)
		(end 34.0106 -83.312)
		(width 0.11938)
		(layer "B.Cu")
		(net "R_FT4232_CHD_RX")
	)
	(segment
		(start 34.0106 -82.169)
		(end 34.0106 -83.312)
		(width 0.11938)
		(layer "B.Cu")
		(net "R_FT4232_CHD_RX")
	)
	(segment
		(start 27.305 -76.708)
		(end 27.305 -77.724)
		(width 0.11938)
		(layer "F.Cu")
		(net "R_FT4232_CHC_TX")
	)
	(segment
		(start 27.305 -77.724)
		(end 27.274266 -77.754734)
		(width 0.11938)
		(layer "F.Cu")
		(net "R_FT4232_CHC_TX")
	)
	(segment
		(start 27.274266 -77.754734)
		(end 27.274266 -79.248)
		(width 0.11938)
		(layer "F.Cu")
		(net "R_FT4232_CHC_TX")
	)
	(segment
		(start 27.305 -75.7174)
		(end 27.305 -76.708)
		(width 0.11938)
		(layer "F.Cu")
		(net "R_FT4232_CHC_TX")
	)
	(via
		(at 27.305 -76.708)
		(size 0.508)
		(drill 0.254)
		(layers "F.Cu" "B.Cu")
		(net "R_FT4232_CHC_TX")
	)
	(segment
		(start 28.575 -76.708)
		(end 28.575 -75.7174)
		(width 0.11938)
		(layer "F.Cu")
		(net "R_FT4232_CHC_RX")
	)
	(segment
		(start 29.845 -75.7174)
		(end 28.575 -75.7174)
		(width 0.11938)
		(layer "F.Cu")
		(net "R_FT4232_CHC_RX")
	)
	(segment
		(start 28.575 -77.343)
		(end 28.575 -76.708)
		(width 0.11938)
		(layer "F.Cu")
		(net "R_FT4232_CHC_RX")
	)
	(segment
		(start 27.774138 -78.143862)
		(end 28.575 -77.343)
		(width 0.11938)
		(layer "F.Cu")
		(net "R_FT4232_CHC_RX")
	)
	(segment
		(start 27.774138 -79.248)
		(end 27.774138 -78.143862)
		(width 0.11938)
		(layer "F.Cu")
		(net "R_FT4232_CHC_RX")
	)
	(via
		(at 28.575 -76.708)
		(size 0.508)
		(drill 0.254)
		(layers "F.Cu" "B.Cu")
		(net "R_FT4232_CHC_RX")
	)
	(segment
		(start 17.646142 -88.043258)
		(end 17.544542 -88.144858)
		(width 0.14478)
		(layer "F.Cu")
		(net "FT_USB_DP")
	)
	(segment
		(start 15.229586 -87.8586)
		(end 15.580106 -87.8586)
		(width 0.14478)
		(layer "F.Cu")
		(net "FT_USB_DP")
	)
	(segment
		(start 17.33804 -88.64346)
		(end 17.33804 -89.0651)
		(width 0.14478)
		(layer "F.Cu")
		(net "FT_USB_DP")
	)
	(segment
		(start 9.21004 -87.479886)
		(end 9.21004 -87.6554)
		(width 0.14478)
		(layer "F.Cu")
		(net "FT_USB_DP")
	)
	(segment
		(start 14.071346 -87.8586)
		(end 14.421866 -87.8586)
		(width 0.14478)
		(layer "F.Cu")
		(net "FT_USB_DP")
	)
	(segment
		(start 27.48534 -96.68383)
		(end 27.48534 -96.863916)
		(width 0.14478)
		(layer "F.Cu")
		(net "FT_USB_DP")
	)
	(segment
		(start 17.33804 -89.702386)
		(end 17.33804 -89.0651)
		(width 0.14478)
		(layer "F.Cu")
		(net "FT_USB_DP")
	)
	(segment
		(start 15.808706 -87.63)
		(end 16.159226 -87.63)
		(width 0.14478)
		(layer "F.Cu")
		(net "FT_USB_DP")
	)
	(segment
		(start 9.81964 -88.265)
		(end 12.265152 -88.265)
		(width 0.14478)
		(layer "F.Cu")
		(net "FT_USB_DP")
	)
	(segment
		(start 17.960594 -90.140028)
		(end 17.876266 -90.089228)
		(width 0.14478)
		(layer "F.Cu")
		(net "FT_USB_DP")
	)
	(segment
		(start 17.8562 -90.805)
		(end 18.016982 -90.644218)
		(width 0.14478)
		(layer "F.Cu")
		(net "FT_USB_DP")
	)
	(segment
		(start 17.801082 -90.0684)
		(end 17.685766 -90.061796)
		(width 0.14478)
		(layer "F.Cu")
		(net "FT_USB_DP")
	)
	(segment
		(start 28.067 -94.7674)
		(end 28.451302 -95.151702)
		(width 0.14478)
		(layer "F.Cu")
		(net "FT_USB_DP")
	)
	(segment
		(start 16.966946 -87.63)
		(end 17.47647 -87.63)
		(width 0.14478)
		(layer "F.Cu")
		(net "FT_USB_DP")
	)
	(segment
		(start 8.950452 -87.1601)
		(end 9.167368 -87.37727)
		(width 0.14478)
		(layer "F.Cu")
		(net "FT_USB_DP")
	)
	(segment
		(start 14.650466 -87.63)
		(end 15.000986 -87.63)
		(width 0.14478)
		(layer "F.Cu")
		(net "FT_USB_DP")
	)
	(segment
		(start 16.387826 -87.8586)
		(end 16.738346 -87.8586)
		(width 0.14478)
		(layer "F.Cu")
		(net "FT_USB_DP")
	)
	(segment
		(start 28.451302 -95.474282)
		(end 27.656282 -96.269302)
		(width 0.14478)
		(layer "F.Cu")
		(net "FT_USB_DP")
	)
	(segment
		(start 17.6911 -87.84463)
		(end 17.6911 -87.934546)
		(width 0.14478)
		(layer "F.Cu")
		(net "FT_USB_DP")
	)
	(segment
		(start 18.0594 -90.541602)
		(end 18.0594 -90.297)
		(width 0.14478)
		(layer "F.Cu")
		(net "FT_USB_DP")
	)
	(segment
		(start 12.834112 -88.029288)
		(end 13.05433 -87.80907)
		(width 0.14478)
		(layer "F.Cu")
		(net "FT_USB_DP")
	)
	(segment
		(start 18.018252 -90.197686)
		(end 17.960594 -90.140028)
		(width 0.14478)
		(layer "F.Cu")
		(net "FT_USB_DP")
	)
	(segment
		(start 27.442922 -96.966278)
		(end 27.2542 -97.155)
		(width 0.14478)
		(layer "F.Cu")
		(net "FT_USB_DP")
	)
	(segment
		(start 13.486638 -87.63)
		(end 13.842746 -87.63)
		(width 0.14478)
		(layer "F.Cu")
		(net "FT_USB_DP")
	)
	(arc
		(start 16.159226 -87.63)
		(mid 16.240048 -87.663478)
		(end 16.273526 -87.7443)
		(width 0.14478)
		(layer "F.Cu")
		(net "FT_USB_DP")
	)
	(arc
		(start 15.115286 -87.7443)
		(mid 15.148764 -87.825122)
		(end 15.229586 -87.8586)
		(width 0.14478)
		(layer "F.Cu")
		(net "FT_USB_DP")
	)
	(arc
		(start 14.421866 -87.8586)
		(mid 14.502688 -87.825122)
		(end 14.536166 -87.7443)
		(width 0.14478)
		(layer "F.Cu")
		(net "FT_USB_DP")
	)
	(arc
		(start 17.876266 -90.089228)
		(mid 17.840096 -90.07367)
		(end 17.801082 -90.0684)
		(width 0.14478)
		(layer "F.Cu")
		(net "FT_USB_DP")
	)
	(arc
		(start 17.47647 -87.63)
		(mid 17.628236 -87.692864)
		(end 17.6911 -87.84463)
		(width 0.14478)
		(layer "F.Cu")
		(net "FT_USB_DP")
	)
	(arc
		(start 13.957046 -87.7443)
		(mid 13.990524 -87.825122)
		(end 14.071346 -87.8586)
		(width 0.14478)
		(layer "F.Cu")
		(net "FT_USB_DP")
	)
	(arc
		(start 15.694406 -87.7443)
		(mid 15.727884 -87.663478)
		(end 15.808706 -87.63)
		(width 0.14478)
		(layer "F.Cu")
		(net "FT_USB_DP")
	)
	(arc
		(start 15.000986 -87.63)
		(mid 15.081808 -87.663478)
		(end 15.115286 -87.7443)
		(width 0.14478)
		(layer "F.Cu")
		(net "FT_USB_DP")
	)
	(arc
		(start 12.265152 -88.265)
		(mid 12.573072 -88.203733)
		(end 12.834112 -88.029288)
		(width 0.14478)
		(layer "F.Cu")
		(net "FT_USB_DP")
	)
	(arc
		(start 13.05433 -87.80907)
		(mid 13.252675 -87.67654)
		(end 13.486638 -87.63)
		(width 0.14478)
		(layer "F.Cu")
		(net "FT_USB_DP")
	)
	(arc
		(start 16.852646 -87.7443)
		(mid 16.886124 -87.663478)
		(end 16.966946 -87.63)
		(width 0.14478)
		(layer "F.Cu")
		(net "FT_USB_DP")
	)
	(arc
		(start 18.0594 -90.297)
		(mid 18.048708 -90.243248)
		(end 18.018252 -90.197686)
		(width 0.14478)
		(layer "F.Cu")
		(net "FT_USB_DP")
	)
	(arc
		(start 16.273526 -87.7443)
		(mid 16.307004 -87.825122)
		(end 16.387826 -87.8586)
		(width 0.14478)
		(layer "F.Cu")
		(net "FT_USB_DP")
	)
	(arc
		(start 27.656282 -96.269302)
		(mid 27.529565 -96.45955)
		(end 27.48534 -96.68383)
		(width 0.14478)
		(layer "F.Cu")
		(net "FT_USB_DP")
	)
	(arc
		(start 9.167368 -87.37727)
		(mid 9.198909 -87.424336)
		(end 9.21004 -87.479886)
		(width 0.14478)
		(layer "F.Cu")
		(net "FT_USB_DP")
	)
	(arc
		(start 17.6911 -87.934546)
		(mid 17.679418 -87.993367)
		(end 17.646142 -88.043258)
		(width 0.14478)
		(layer "F.Cu")
		(net "FT_USB_DP")
	)
	(arc
		(start 18.016982 -90.644218)
		(mid 18.048387 -90.597123)
		(end 18.0594 -90.541602)
		(width 0.14478)
		(layer "F.Cu")
		(net "FT_USB_DP")
	)
	(arc
		(start 17.685766 -90.061796)
		(mid 17.551987 -90.0253)
		(end 17.438624 -89.945464)
		(width 0.14478)
		(layer "F.Cu")
		(net "FT_USB_DP")
	)
	(arc
		(start 14.536166 -87.7443)
		(mid 14.569644 -87.663478)
		(end 14.650466 -87.63)
		(width 0.14478)
		(layer "F.Cu")
		(net "FT_USB_DP")
	)
	(arc
		(start 15.580106 -87.8586)
		(mid 15.660928 -87.825122)
		(end 15.694406 -87.7443)
		(width 0.14478)
		(layer "F.Cu")
		(net "FT_USB_DP")
	)
	(arc
		(start 17.438624 -89.945464)
		(mid 17.363953 -89.834007)
		(end 17.33804 -89.702386)
		(width 0.14478)
		(layer "F.Cu")
		(net "FT_USB_DP")
	)
	(arc
		(start 28.451302 -95.151702)
		(mid 28.518111 -95.312992)
		(end 28.451302 -95.474282)
		(width 0.14478)
		(layer "F.Cu")
		(net "FT_USB_DP")
	)
	(arc
		(start 9.21004 -87.6554)
		(mid 9.388588 -88.086452)
		(end 9.81964 -88.265)
		(width 0.14478)
		(layer "F.Cu")
		(net "FT_USB_DP")
	)
	(arc
		(start 17.544542 -88.144858)
		(mid 17.391689 -88.373619)
		(end 17.33804 -88.64346)
		(width 0.14478)
		(layer "F.Cu")
		(net "FT_USB_DP")
	)
	(arc
		(start 27.48534 -96.863916)
		(mid 27.474319 -96.919321)
		(end 27.442922 -96.966278)
		(width 0.14478)
		(layer "F.Cu")
		(net "FT_USB_DP")
	)
	(arc
		(start 13.842746 -87.63)
		(mid 13.923568 -87.663478)
		(end 13.957046 -87.7443)
		(width 0.14478)
		(layer "F.Cu")
		(net "FT_USB_DP")
	)
	(arc
		(start 16.738346 -87.8586)
		(mid 16.819168 -87.825122)
		(end 16.852646 -87.7443)
		(width 0.14478)
		(layer "F.Cu")
		(net "FT_USB_DP")
	)
	(segment
		(start 8.770874 -87.825326)
		(end 8.862568 -87.733632)
		(width 0.15748)
		(layer "In2.Cu")
		(net "FT_USB_DP")
	)
	(segment
		(start 8.950452 -87.521288)
		(end 8.950452 -87.1601)
		(width 0.15748)
		(layer "In2.Cu")
		(net "FT_USB_DP")
	)
	(segment
		(start 7.707884 -87.641684)
		(end 7.926832 -87.860632)
		(width 0.15748)
		(layer "In2.Cu")
		(net "FT_USB_DP")
	)
	(segment
		(start 8.500364 -86.38032)
		(end 7.65048 -86.871302)
		(width 0.1016)
		(layer "In2.Cu")
		(net "FT_USB_DP")
	)
	(segment
		(start 7.59968 -86.95944)
		(end 7.59968 -87.380318)
		(width 0.1016)
		(layer "In2.Cu")
		(net "FT_USB_DP")
	)
	(segment
		(start 8.044434 -87.9094)
		(end 8.568182 -87.9094)
		(width 0.15748)
		(layer "In2.Cu")
		(net "FT_USB_DP")
	)
	(arc
		(start 8.568182 -87.9094)
		(mid 8.677869 -87.887488)
		(end 8.770874 -87.825326)
		(width 0.15748)
		(layer "In2.Cu")
		(net "FT_USB_DP")
	)
	(arc
		(start 8.862568 -87.733632)
		(mid 8.927611 -87.636194)
		(end 8.950452 -87.521288)
		(width 0.15748)
		(layer "In2.Cu")
		(net "FT_USB_DP")
	)
	(arc
		(start 7.65048 -86.871302)
		(mid 7.613287 -86.908574)
		(end 7.59968 -86.95944)
		(width 0.1016)
		(layer "In2.Cu")
		(net "FT_USB_DP")
	)
	(arc
		(start 7.926832 -87.860632)
		(mid 7.980774 -87.896738)
		(end 8.044434 -87.9094)
		(width 0.15748)
		(layer "In2.Cu")
		(net "FT_USB_DP")
	)
	(arc
		(start 7.59968 -87.380318)
		(mid 7.627797 -87.521761)
		(end 7.707884 -87.641684)
		(width 0.1016)
		(layer "In2.Cu")
		(net "FT_USB_DP")
	)
	(segment
		(start 27.433524 -96.975676)
		(end 27.2542 -97.155)
		(width 0.15748)
		(layer "In7.Cu")
		(net "FT_USB_DP")
	)
	(segment
		(start 18.076418 -91.081606)
		(end 18.0975 -91.20886)
		(width 0.15748)
		(layer "In7.Cu")
		(net "FT_USB_DP")
	)
	(segment
		(start 24.82088 -91.67114)
		(end 24.82088 -92.136214)
		(width 0.15748)
		(layer "In7.Cu")
		(net "FT_USB_DP")
	)
	(segment
		(start 21.598636 -90.5764)
		(end 23.72614 -90.5764)
		(width 0.15748)
		(layer "In7.Cu")
		(net "FT_USB_DP")
	)
	(segment
		(start 17.8562 -90.805)
		(end 17.982438 -90.931238)
		(width 0.15748)
		(layer "In7.Cu")
		(net "FT_USB_DP")
	)
	(segment
		(start 27.4955 -96.82607)
		(end 27.4828 -96.898206)
		(width 0.15748)
		(layer "In7.Cu")
		(net "FT_USB_DP")
	)
	(segment
		(start 20.072096 -91.60383)
		(end 20.74672 -90.92946)
		(width 0.15748)
		(layer "In7.Cu")
		(net "FT_USB_DP")
	)
	(segment
		(start 18.0975 -91.20886)
		(end 18.0975 -91.5289)
		(width 0.15748)
		(layer "In7.Cu")
		(net "FT_USB_DP")
	)
	(segment
		(start 25.080722 -92.764102)
		(end 26.610056 -94.293436)
		(width 0.15748)
		(layer "In7.Cu")
		(net "FT_USB_DP")
	)
	(segment
		(start 18.58518 -92.01658)
		(end 19.075654 -92.01658)
		(width 0.15748)
		(layer "In7.Cu")
		(net "FT_USB_DP")
	)
	(segment
		(start 27.4955 -96.4311)
		(end 27.4955 -96.82607)
		(width 0.15748)
		(layer "In7.Cu")
		(net "FT_USB_DP")
	)
	(arc
		(start 17.982438 -90.931238)
		(mid 18.038055 -91.001034)
		(end 18.076418 -91.081606)
		(width 0.15748)
		(layer "In7.Cu")
		(net "FT_USB_DP")
	)
	(arc
		(start 27.4828 -96.898206)
		(mid 27.462409 -96.939642)
		(end 27.433524 -96.975676)
		(width 0.15748)
		(layer "In7.Cu")
		(net "FT_USB_DP")
	)
	(arc
		(start 23.72614 -90.5764)
		(mid 24.500238 -90.897042)
		(end 24.82088 -91.67114)
		(width 0.15748)
		(layer "In7.Cu")
		(net "FT_USB_DP")
	)
	(arc
		(start 18.0975 -91.5289)
		(mid 18.240338 -91.873742)
		(end 18.58518 -92.01658)
		(width 0.15748)
		(layer "In7.Cu")
		(net "FT_USB_DP")
	)
	(arc
		(start 19.075654 -92.01658)
		(mid 19.614889 -91.909244)
		(end 20.072096 -91.60383)
		(width 0.15748)
		(layer "In7.Cu")
		(net "FT_USB_DP")
	)
	(arc
		(start 24.82088 -92.136214)
		(mid 24.888371 -92.475987)
		(end 25.080722 -92.764102)
		(width 0.15748)
		(layer "In7.Cu")
		(net "FT_USB_DP")
	)
	(arc
		(start 26.610056 -94.293436)
		(mid 27.265385 -95.274205)
		(end 27.4955 -96.4311)
		(width 0.15748)
		(layer "In7.Cu")
		(net "FT_USB_DP")
	)
	(arc
		(start 20.74672 -90.92946)
		(mid 21.137568 -90.66824)
		(end 21.598636 -90.5764)
		(width 0.15748)
		(layer "In7.Cu")
		(net "FT_USB_DP")
	)
	(segment
		(start 12.784836 -87.539576)
		(end 12.564618 -87.759794)
		(width 0.14478)
		(layer "F.Cu")
		(net "FT_USB_DM")
	)
	(segment
		(start 19.083782 -88.501982)
		(end 19.025616 -88.443816)
		(width 0.14478)
		(layer "F.Cu")
		(net "FT_USB_DM")
	)
	(segment
		(start 27.930094 -97.018094)
		(end 28.067 -97.155)
		(width 0.14478)
		(layer "F.Cu")
		(net "FT_USB_DM")
	)
	(segment
		(start 19.23796 -89.0651)
		(end 19.23796 -88.874092)
		(width 0.14478)
		(layer "F.Cu")
		(net "FT_USB_DM")
	)
	(segment
		(start 18.669 -90.805)
		(end 18.599658 -90.735658)
		(width 0.14478)
		(layer "F.Cu")
		(net "FT_USB_DM")
	)
	(segment
		(start 18.125694 -87.249)
		(end 13.486384 -87.249)
		(width 0.14478)
		(layer "F.Cu")
		(net "FT_USB_DM")
	)
	(segment
		(start 9.59104 -87.6554)
		(end 9.59104 -87.479886)
		(width 0.14478)
		(layer "F.Cu")
		(net "FT_USB_DM")
	)
	(segment
		(start 19.23796 -89.580212)
		(end 19.23796 -89.0651)
		(width 0.14478)
		(layer "F.Cu")
		(net "FT_USB_DM")
	)
	(segment
		(start 27.86634 -96.683322)
		(end 27.86634 -96.86417)
		(width 0.14478)
		(layer "F.Cu")
		(net "FT_USB_DM")
	)
	(segment
		(start 18.748756 -90.043)
		(end 18.897346 -90.043)
		(width 0.14478)
		(layer "F.Cu")
		(net "FT_USB_DM")
	)
	(segment
		(start 19.060668 -89.975436)
		(end 19.083782 -89.952322)
		(width 0.14478)
		(layer "F.Cu")
		(net "FT_USB_DM")
	)
	(segment
		(start 29.337 -94.7674)
		(end 28.89123 -95.213424)
		(width 0.14478)
		(layer "F.Cu")
		(net "FT_USB_DM")
	)
	(segment
		(start 9.633458 -87.37727)
		(end 9.850628 -87.1601)
		(width 0.14478)
		(layer "F.Cu")
		(net "FT_USB_DM")
	)
	(segment
		(start 18.87093 -88.070436)
		(end 18.87093 -87.940134)
		(width 0.14478)
		(layer "F.Cu")
		(net "FT_USB_DM")
	)
	(segment
		(start 28.72105 -95.743776)
		(end 27.92603 -96.538796)
		(width 0.14478)
		(layer "F.Cu")
		(net "FT_USB_DM")
	)
	(segment
		(start 12.265152 -87.884)
		(end 9.81964 -87.884)
		(width 0.14478)
		(layer "F.Cu")
		(net "FT_USB_DM")
	)
	(arc
		(start 19.23796 -88.874092)
		(mid 19.197884 -88.672705)
		(end 19.083782 -88.501982)
		(width 0.14478)
		(layer "F.Cu")
		(net "FT_USB_DM")
	)
	(arc
		(start 19.083782 -89.952322)
		(mid 19.197911 -89.781611)
		(end 19.23796 -89.580212)
		(width 0.14478)
		(layer "F.Cu")
		(net "FT_USB_DM")
	)
	(arc
		(start 12.564618 -87.759794)
		(mid 12.427251 -87.851736)
		(end 12.265152 -87.884)
		(width 0.14478)
		(layer "F.Cu")
		(net "FT_USB_DM")
	)
	(arc
		(start 18.87093 -87.940134)
		(mid 18.821156 -87.690174)
		(end 18.679414 -87.478362)
		(width 0.14478)
		(layer "F.Cu")
		(net "FT_USB_DM")
	)
	(arc
		(start 28.89123 -95.213424)
		(mid 28.870279 -95.499182)
		(end 28.72105 -95.743776)
		(width 0.14478)
		(layer "F.Cu")
		(net "FT_USB_DM")
	)
	(arc
		(start 27.92603 -96.538796)
		(mid 27.881753 -96.605106)
		(end 27.86634 -96.683322)
		(width 0.14478)
		(layer "F.Cu")
		(net "FT_USB_DM")
	)
	(arc
		(start 9.59104 -87.479886)
		(mid 9.602065 -87.42437)
		(end 9.633458 -87.37727)
		(width 0.14478)
		(layer "F.Cu")
		(net "FT_USB_DM")
	)
	(arc
		(start 18.4404 -90.351356)
		(mid 18.530715 -90.133315)
		(end 18.748756 -90.043)
		(width 0.14478)
		(layer "F.Cu")
		(net "FT_USB_DM")
	)
	(arc
		(start 19.025616 -88.443816)
		(mid 18.911152 -88.272508)
		(end 18.87093 -88.070436)
		(width 0.14478)
		(layer "F.Cu")
		(net "FT_USB_DM")
	)
	(arc
		(start 18.679414 -87.478362)
		(mid 18.425365 -87.308612)
		(end 18.125694 -87.249)
		(width 0.14478)
		(layer "F.Cu")
		(net "FT_USB_DM")
	)
	(arc
		(start 13.486384 -87.249)
		(mid 13.1067 -87.324506)
		(end 12.784836 -87.539576)
		(width 0.14478)
		(layer "F.Cu")
		(net "FT_USB_DM")
	)
	(arc
		(start 18.599658 -90.735658)
		(mid 18.481792 -90.559353)
		(end 18.4404 -90.351356)
		(width 0.14478)
		(layer "F.Cu")
		(net "FT_USB_DM")
	)
	(arc
		(start 27.86634 -96.86417)
		(mid 27.88291 -96.947472)
		(end 27.930094 -97.018094)
		(width 0.14478)
		(layer "F.Cu")
		(net "FT_USB_DM")
	)
	(arc
		(start 18.897346 -90.043)
		(mid 18.985702 -90.025425)
		(end 19.060668 -89.975436)
		(width 0.14478)
		(layer "F.Cu")
		(net "FT_USB_DM")
	)
	(arc
		(start 9.81964 -87.884)
		(mid 9.657995 -87.817045)
		(end 9.59104 -87.6554)
		(width 0.14478)
		(layer "F.Cu")
		(net "FT_USB_DM")
	)
	(segment
		(start 9.685274 -85.834474)
		(end 9.850628 -85.999828)
		(width 0.15748)
		(layer "In2.Cu")
		(net "FT_USB_DM")
	)
	(segment
		(start 7.600188 -86.38032)
		(end 8.037576 -85.942932)
		(width 0.15748)
		(layer "In2.Cu")
		(net "FT_USB_DM")
	)
	(segment
		(start 8.502142 -85.7504)
		(end 9.482582 -85.7504)
		(width 0.15748)
		(layer "In2.Cu")
		(net "FT_USB_DM")
	)
	(segment
		(start 9.850628 -85.999828)
		(end 9.850628 -87.1601)
		(width 0.1016)
		(layer "In2.Cu")
		(net "FT_USB_DM")
	)
	(arc
		(start 8.037576 -85.942932)
		(mid 8.250706 -85.80046)
		(end 8.502142 -85.7504)
		(width 0.15748)
		(layer "In2.Cu")
		(net "FT_USB_DM")
	)
	(arc
		(start 9.482582 -85.7504)
		(mid 9.592269 -85.772312)
		(end 9.685274 -85.834474)
		(width 0.15748)
		(layer "In2.Cu")
		(net "FT_USB_DM")
	)
	(segment
		(start 25.15108 -91.67114)
		(end 25.15108 -92.136214)
		(width 0.15748)
		(layer "In7.Cu")
		(net "FT_USB_DM")
	)
	(segment
		(start 27.8257 -96.82607)
		(end 27.8384 -96.898206)
		(width 0.15748)
		(layer "In7.Cu")
		(net "FT_USB_DM")
	)
	(segment
		(start 27.8257 -96.4311)
		(end 27.8257 -96.82607)
		(width 0.15748)
		(layer "In7.Cu")
		(net "FT_USB_DM")
	)
	(segment
		(start 27.887676 -96.975676)
		(end 28.067 -97.155)
		(width 0.15748)
		(layer "In7.Cu")
		(net "FT_USB_DM")
	)
	(segment
		(start 25.314402 -92.530422)
		(end 26.843736 -94.059756)
		(width 0.15748)
		(layer "In7.Cu")
		(net "FT_USB_DM")
	)
	(segment
		(start 19.838416 -91.37015)
		(end 20.51304 -90.69578)
		(width 0.15748)
		(layer "In7.Cu")
		(net "FT_USB_DM")
	)
	(segment
		(start 18.669 -90.805)
		(end 18.542762 -90.931238)
		(width 0.15748)
		(layer "In7.Cu")
		(net "FT_USB_DM")
	)
	(segment
		(start 18.4277 -91.20886)
		(end 18.4277 -91.5289)
		(width 0.15748)
		(layer "In7.Cu")
		(net "FT_USB_DM")
	)
	(segment
		(start 21.598382 -90.2462)
		(end 23.72614 -90.2462)
		(width 0.15748)
		(layer "In7.Cu")
		(net "FT_USB_DM")
	)
	(segment
		(start 18.58518 -91.68638)
		(end 19.0754 -91.68638)
		(width 0.15748)
		(layer "In7.Cu")
		(net "FT_USB_DM")
	)
	(segment
		(start 18.448782 -91.081606)
		(end 18.4277 -91.20886)
		(width 0.15748)
		(layer "In7.Cu")
		(net "FT_USB_DM")
	)
	(arc
		(start 18.542762 -90.931238)
		(mid 18.487145 -91.001034)
		(end 18.448782 -91.081606)
		(width 0.15748)
		(layer "In7.Cu")
		(net "FT_USB_DM")
	)
	(arc
		(start 25.15108 -92.136214)
		(mid 25.193519 -92.349571)
		(end 25.314402 -92.530422)
		(width 0.15748)
		(layer "In7.Cu")
		(net "FT_USB_DM")
	)
	(arc
		(start 26.843736 -94.059756)
		(mid 27.570566 -95.147767)
		(end 27.8257 -96.4311)
		(width 0.15748)
		(layer "In7.Cu")
		(net "FT_USB_DM")
	)
	(arc
		(start 20.51304 -90.69578)
		(mid 21.010999 -90.363054)
		(end 21.598382 -90.2462)
		(width 0.15748)
		(layer "In7.Cu")
		(net "FT_USB_DM")
	)
	(arc
		(start 23.72614 -90.2462)
		(mid 24.733725 -90.663555)
		(end 25.15108 -91.67114)
		(width 0.15748)
		(layer "In7.Cu")
		(net "FT_USB_DM")
	)
	(arc
		(start 19.0754 -91.68638)
		(mid 19.488356 -91.604144)
		(end 19.838416 -91.37015)
		(width 0.15748)
		(layer "In7.Cu")
		(net "FT_USB_DM")
	)
	(arc
		(start 27.8384 -96.898206)
		(mid 27.858791 -96.939642)
		(end 27.887676 -96.975676)
		(width 0.15748)
		(layer "In7.Cu")
		(net "FT_USB_DM")
	)
	(arc
		(start 18.4277 -91.5289)
		(mid 18.473825 -91.640255)
		(end 18.58518 -91.68638)
		(width 0.15748)
		(layer "In7.Cu")
		(net "FT_USB_DM")
	)
	(segment
		(start 109.7534 -88.7984)
		(end 108.839 -87.884)
		(width 0.11938)
		(layer "F.Cu")
		(net "FT_USB_DETECT")
	)
	(segment
		(start 110.236 -88.7984)
		(end 110.8075 -88.7984)
		(width 0.11938)
		(layer "F.Cu")
		(net "FT_USB_DETECT")
	)
	(segment
		(start 25.840944 -93.98)
		(end 25.273 -93.98)
		(width 0.11938)
		(layer "F.Cu")
		(net "FT_USB_DETECT")
	)
	(segment
		(start 26.797 -93.7006)
		(end 26.120344 -93.7006)
		(width 0.11938)
		(layer "F.Cu")
		(net "FT_USB_DETECT")
	)
	(segment
		(start 110.8075 -88.7984)
		(end 111.7092 -89.7001)
		(width 0.11938)
		(layer "F.Cu")
		(net "FT_USB_DETECT")
	)
	(segment
		(start 110.236 -88.7984)
		(end 109.7534 -88.7984)
		(width 0.11938)
		(layer "F.Cu")
		(net "FT_USB_DETECT")
	)
	(segment
		(start 26.120344 -93.7006)
		(end 25.840944 -93.98)
		(width 0.11938)
		(layer "F.Cu")
		(net "FT_USB_DETECT")
	)
	(via
		(at 108.839 -87.884)
		(size 0.508)
		(drill 0.254)
		(layers "F.Cu" "B.Cu")
		(net "FT_USB_DETECT")
	)
	(segment
		(start 26.0604 -93.7006)
		(end 25.781 -93.98)
		(width 0.11938)
		(layer "B.Cu")
		(net "FT_USB_DETECT")
	)
	(segment
		(start 26.416 -91.5924)
		(end 25.273 -91.5924)
		(width 0.11938)
		(layer "B.Cu")
		(net "FT_USB_DETECT")
	)
	(segment
		(start 26.797 -93.7006)
		(end 26.0604 -93.7006)
		(width 0.11938)
		(layer "B.Cu")
		(net "FT_USB_DETECT")
	)
	(segment
		(start 25.781 -93.98)
		(end 25.273 -93.98)
		(width 0.11938)
		(layer "B.Cu")
		(net "FT_USB_DETECT")
	)
	(segment
		(start 25.273 -93.98)
		(end 25.273 -91.5924)
		(width 0.11938)
		(layer "B.Cu")
		(net "FT_USB_DETECT")
	)
	(segment
		(start 96.922082 -95.885)
		(end 99.568 -95.885)
		(width 0.127)
		(layer "In2.Cu")
		(net "FT_USB_DETECT")
	)
	(segment
		(start 30.226 -95.504)
		(end 32.258 -93.472)
		(width 0.127)
		(layer "In2.Cu")
		(net "FT_USB_DETECT")
	)
	(segment
		(start 26.035 -94.361)
		(end 27.559 -95.885)
		(width 0.127)
		(layer "In2.Cu")
		(net "FT_USB_DETECT")
	)
	(segment
		(start 89.408 -89.916)
		(end 95.5167 -96.0247)
		(width 0.127)
		(layer "In2.Cu")
		(net "FT_USB_DETECT")
	)
	(segment
		(start 29.718 -95.504)
		(end 30.226 -95.504)
		(width 0.127)
		(layer "In2.Cu")
		(net "FT_USB_DETECT")
	)
	(segment
		(start 102.489 -92.964)
		(end 105.998518 -92.964)
		(width 0.127)
		(layer "In2.Cu")
		(net "FT_USB_DETECT")
	)
	(segment
		(start 25.654 -94.361)
		(end 26.035 -94.361)
		(width 0.127)
		(layer "In2.Cu")
		(net "FT_USB_DETECT")
	)
	(segment
		(start 34.671 -93.472)
		(end 35.56 -92.583)
		(width 0.127)
		(layer "In2.Cu")
		(net "FT_USB_DETECT")
	)
	(segment
		(start 32.258 -93.472)
		(end 34.671 -93.472)
		(width 0.127)
		(layer "In2.Cu")
		(net "FT_USB_DETECT")
	)
	(segment
		(start 108.839 -91.821)
		(end 108.839 -87.884)
		(width 0.127)
		(layer "In2.Cu")
		(net "FT_USB_DETECT")
	)
	(segment
		(start 95.5167 -96.0247)
		(end 96.782382 -96.0247)
		(width 0.127)
		(layer "In2.Cu")
		(net "FT_USB_DETECT")
	)
	(segment
		(start 48.005746 -93.853)
		(end 69.140578 -93.853)
		(width 0.127)
		(layer "In2.Cu")
		(net "FT_USB_DETECT")
	)
	(segment
		(start 99.568 -95.885)
		(end 102.489 -92.964)
		(width 0.127)
		(layer "In2.Cu")
		(net "FT_USB_DETECT")
	)
	(segment
		(start 105.998518 -92.964)
		(end 106.570018 -93.5355)
		(width 0.127)
		(layer "In2.Cu")
		(net "FT_USB_DETECT")
	)
	(segment
		(start 29.337 -95.885)
		(end 29.718 -95.504)
		(width 0.127)
		(layer "In2.Cu")
		(net "FT_USB_DETECT")
	)
	(segment
		(start 107.1245 -93.5355)
		(end 108.839 -91.821)
		(width 0.127)
		(layer "In2.Cu")
		(net "FT_USB_DETECT")
	)
	(segment
		(start 69.140578 -93.853)
		(end 73.077578 -89.916)
		(width 0.127)
		(layer "In2.Cu")
		(net "FT_USB_DETECT")
	)
	(segment
		(start 35.56 -92.583)
		(end 46.735746 -92.583)
		(width 0.127)
		(layer "In2.Cu")
		(net "FT_USB_DETECT")
	)
	(segment
		(start 27.559 -95.885)
		(end 29.337 -95.885)
		(width 0.127)
		(layer "In2.Cu")
		(net "FT_USB_DETECT")
	)
	(segment
		(start 25.273 -93.98)
		(end 25.654 -94.361)
		(width 0.127)
		(layer "In2.Cu")
		(net "FT_USB_DETECT")
	)
	(segment
		(start 46.735746 -92.583)
		(end 48.005746 -93.853)
		(width 0.127)
		(layer "In2.Cu")
		(net "FT_USB_DETECT")
	)
	(segment
		(start 73.077578 -89.916)
		(end 89.408 -89.916)
		(width 0.127)
		(layer "In2.Cu")
		(net "FT_USB_DETECT")
	)
	(segment
		(start 96.782382 -96.0247)
		(end 96.922082 -95.885)
		(width 0.127)
		(layer "In2.Cu")
		(net "FT_USB_DETECT")
	)
	(segment
		(start 106.570018 -93.5355)
		(end 107.1245 -93.5355)
		(width 0.127)
		(layer "In2.Cu")
		(net "FT_USB_DETECT")
	)
	(via
		(at 52.07 -85.725)
		(size 0.762)
		(drill 0.381)
		(layers "F.Cu" "B.Cu")
		(net "FTDI_EE_DO")
	)
	(segment
		(start 53.467 -85.3694)
		(end 53.4416 -85.344)
		(width 0.11938)
		(layer "B.Cu")
		(net "FTDI_EE_DO")
	)
	(segment
		(start 51.7398 -86.0552)
		(end 52.07 -85.725)
		(width 0.11938)
		(layer "B.Cu")
		(net "FTDI_EE_DO")
	)
	(segment
		(start 53.4416 -85.344)
		(end 52.451 -85.344)
		(width 0.11938)
		(layer "B.Cu")
		(net "FTDI_EE_DO")
	)
	(segment
		(start 52.451 -85.344)
		(end 52.07 -85.725)
		(width 0.11938)
		(layer "B.Cu")
		(net "FTDI_EE_DO")
	)
	(segment
		(start 50.0253 -86.0552)
		(end 51.7398 -86.0552)
		(width 0.11938)
		(layer "B.Cu")
		(net "FTDI_EE_DO")
	)
	(segment
		(start 53.467 -86.5886)
		(end 53.467 -85.3694)
		(width 0.11938)
		(layer "B.Cu")
		(net "FTDI_EE_DO")
	)
	(segment
		(start 52.07 -87.3252)
		(end 51.3842 -88.011)
		(width 0.11938)
		(layer "F.Cu")
		(net "FTDI_EE_DAT")
	)
	(segment
		(start 41.783 -88.011)
		(end 41.086532 -87.314532)
		(width 0.11938)
		(layer "F.Cu")
		(net "FTDI_EE_DAT")
	)
	(segment
		(start 41.086532 -87.314532)
		(end 34.3408 -87.314532)
		(width 0.11938)
		(layer "F.Cu")
		(net "FTDI_EE_DAT")
	)
	(segment
		(start 54.61 -87.3252)
		(end 52.07 -87.3252)
		(width 0.11938)
		(layer "F.Cu")
		(net "FTDI_EE_DAT")
	)
	(segment
		(start 51.3842 -88.011)
		(end 41.783 -88.011)
		(width 0.11938)
		(layer "F.Cu")
		(net "FTDI_EE_DAT")
	)
	(via
		(at 54.61 -87.3252)
		(size 0.508)
		(drill 0.254)
		(layers "F.Cu" "B.Cu")
		(net "FTDI_EE_DAT")
	)
	(segment
		(start 51.2318 -87.3252)
		(end 50.0253 -87.3252)
		(width 0.11938)
		(layer "B.Cu")
		(net "FTDI_EE_DAT")
	)
	(segment
		(start 52.00777 -86.88578)
		(end 52.00777 -87.53602)
		(width 0.11938)
		(layer "B.Cu")
		(net "FTDI_EE_DAT")
	)
	(segment
		(start 53.467 -87.6554)
		(end 54.2798 -87.6554)
		(width 0.11938)
		(layer "B.Cu")
		(net "FTDI_EE_DAT")
	)
	(segment
		(start 52.63515 -86.88578)
		(end 52.51577 -86.7664)
		(width 0.11938)
		(layer "B.Cu")
		(net "FTDI_EE_DAT")
	)
	(segment
		(start 52.12715 -86.7664)
		(end 52.00777 -86.88578)
		(width 0.11938)
		(layer "B.Cu")
		(net "FTDI_EE_DAT")
	)
	(segment
		(start 52.75453 -87.6554)
		(end 52.63515 -87.53602)
		(width 0.11938)
		(layer "B.Cu")
		(net "FTDI_EE_DAT")
	)
	(segment
		(start 51.88839 -87.6554)
		(end 51.562 -87.6554)
		(width 0.11938)
		(layer "B.Cu")
		(net "FTDI_EE_DAT")
	)
	(segment
		(start 52.63515 -87.53602)
		(end 52.63515 -86.88578)
		(width 0.11938)
		(layer "B.Cu")
		(net "FTDI_EE_DAT")
	)
	(segment
		(start 53.467 -87.6554)
		(end 52.75453 -87.6554)
		(width 0.11938)
		(layer "B.Cu")
		(net "FTDI_EE_DAT")
	)
	(segment
		(start 51.562 -87.6554)
		(end 51.2318 -87.3252)
		(width 0.11938)
		(layer "B.Cu")
		(net "FTDI_EE_DAT")
	)
	(segment
		(start 52.51577 -86.7664)
		(end 52.12715 -86.7664)
		(width 0.11938)
		(layer "B.Cu")
		(net "FTDI_EE_DAT")
	)
	(segment
		(start 52.00777 -87.53602)
		(end 51.88839 -87.6554)
		(width 0.11938)
		(layer "B.Cu")
		(net "FTDI_EE_DAT")
	)
	(segment
		(start 54.2798 -87.6554)
		(end 54.61 -87.3252)
		(width 0.11938)
		(layer "B.Cu")
		(net "FTDI_EE_DAT")
	)
	(segment
		(start 49.29632 -90.6272)
		(end 48.9077 -90.6272)
		(width 0.11938)
		(layer "F.Cu")
		(net "FTDI_EE_CS")
	)
	(segment
		(start 47.02556 -89.8652)
		(end 46.90618 -89.98458)
		(width 0.11938)
		(layer "F.Cu")
		(net "FTDI_EE_CS")
	)
	(segment
		(start 45.02404 -89.98458)
		(end 44.90466 -89.8652)
		(width 0.11938)
		(layer "F.Cu")
		(net "FTDI_EE_CS")
	)
	(segment
		(start 48.28032 -89.8652)
		(end 48.16094 -89.98458)
		(width 0.11938)
		(layer "F.Cu")
		(net "FTDI_EE_CS")
	)
	(segment
		(start 50.67046 -90.50782)
		(end 50.55108 -90.6272)
		(width 0.11938)
		(layer "F.Cu")
		(net "FTDI_EE_CS")
	)
	(segment
		(start 42.3672 -89.8652)
		(end 40.81653 -88.31453)
		(width 0.11938)
		(layer "F.Cu")
		(net "FTDI_EE_CS")
	)
	(segment
		(start 50.67046 -89.98458)
		(end 50.67046 -90.50782)
		(width 0.11938)
		(layer "F.Cu")
		(net "FTDI_EE_CS")
	)
	(segment
		(start 40.81653 -88.31453)
		(end 34.3408 -88.31453)
		(width 0.11938)
		(layer "F.Cu")
		(net "FTDI_EE_CS")
	)
	(segment
		(start 48.9077 -90.6272)
		(end 48.78832 -90.50782)
		(width 0.11938)
		(layer "F.Cu")
		(net "FTDI_EE_CS")
	)
	(segment
		(start 48.16094 -89.98458)
		(end 48.16094 -90.50782)
		(width 0.11938)
		(layer "F.Cu")
		(net "FTDI_EE_CS")
	)
	(segment
		(start 47.65294 -90.6272)
		(end 47.53356 -90.50782)
		(width 0.11938)
		(layer "F.Cu")
		(net "FTDI_EE_CS")
	)
	(segment
		(start 45.02404 -90.50782)
		(end 45.02404 -89.98458)
		(width 0.11938)
		(layer "F.Cu")
		(net "FTDI_EE_CS")
	)
	(segment
		(start 46.90618 -90.50782)
		(end 46.7868 -90.6272)
		(width 0.11938)
		(layer "F.Cu")
		(net "FTDI_EE_CS")
	)
	(segment
		(start 49.4157 -90.50782)
		(end 49.29632 -90.6272)
		(width 0.11938)
		(layer "F.Cu")
		(net "FTDI_EE_CS")
	)
	(segment
		(start 46.7868 -90.6272)
		(end 46.39818 -90.6272)
		(width 0.11938)
		(layer "F.Cu")
		(net "FTDI_EE_CS")
	)
	(segment
		(start 47.41418 -89.8652)
		(end 47.02556 -89.8652)
		(width 0.11938)
		(layer "F.Cu")
		(net "FTDI_EE_CS")
	)
	(segment
		(start 48.78832 -89.98458)
		(end 48.66894 -89.8652)
		(width 0.11938)
		(layer "F.Cu")
		(net "FTDI_EE_CS")
	)
	(segment
		(start 48.78832 -90.50782)
		(end 48.78832 -89.98458)
		(width 0.11938)
		(layer "F.Cu")
		(net "FTDI_EE_CS")
	)
	(segment
		(start 46.39818 -90.6272)
		(end 46.2788 -90.50782)
		(width 0.11938)
		(layer "F.Cu")
		(net "FTDI_EE_CS")
	)
	(segment
		(start 50.78984 -89.8652)
		(end 50.67046 -89.98458)
		(width 0.11938)
		(layer "F.Cu")
		(net "FTDI_EE_CS")
	)
	(segment
		(start 50.16246 -90.6272)
		(end 50.04308 -90.50782)
		(width 0.11938)
		(layer "F.Cu")
		(net "FTDI_EE_CS")
	)
	(segment
		(start 48.04156 -90.6272)
		(end 47.65294 -90.6272)
		(width 0.11938)
		(layer "F.Cu")
		(net "FTDI_EE_CS")
	)
	(segment
		(start 46.90618 -89.98458)
		(end 46.90618 -90.50782)
		(width 0.11938)
		(layer "F.Cu")
		(net "FTDI_EE_CS")
	)
	(segment
		(start 49.9237 -89.8652)
		(end 49.53508 -89.8652)
		(width 0.11938)
		(layer "F.Cu")
		(net "FTDI_EE_CS")
	)
	(segment
		(start 49.4157 -89.98458)
		(end 49.4157 -90.50782)
		(width 0.11938)
		(layer "F.Cu")
		(net "FTDI_EE_CS")
	)
	(segment
		(start 52.07 -89.8652)
		(end 50.78984 -89.8652)
		(width 0.11938)
		(layer "F.Cu")
		(net "FTDI_EE_CS")
	)
	(segment
		(start 47.53356 -89.98458)
		(end 47.41418 -89.8652)
		(width 0.11938)
		(layer "F.Cu")
		(net "FTDI_EE_CS")
	)
	(segment
		(start 44.90466 -89.8652)
		(end 42.3672 -89.8652)
		(width 0.11938)
		(layer "F.Cu")
		(net "FTDI_EE_CS")
	)
	(segment
		(start 50.55108 -90.6272)
		(end 50.16246 -90.6272)
		(width 0.11938)
		(layer "F.Cu")
		(net "FTDI_EE_CS")
	)
	(segment
		(start 46.2788 -89.98458)
		(end 46.15942 -89.8652)
		(width 0.11938)
		(layer "F.Cu")
		(net "FTDI_EE_CS")
	)
	(segment
		(start 50.04308 -89.98458)
		(end 49.9237 -89.8652)
		(width 0.11938)
		(layer "F.Cu")
		(net "FTDI_EE_CS")
	)
	(segment
		(start 48.66894 -89.8652)
		(end 48.28032 -89.8652)
		(width 0.11938)
		(layer "F.Cu")
		(net "FTDI_EE_CS")
	)
	(segment
		(start 45.14342 -90.6272)
		(end 45.02404 -90.50782)
		(width 0.11938)
		(layer "F.Cu")
		(net "FTDI_EE_CS")
	)
	(segment
		(start 49.53508 -89.8652)
		(end 49.4157 -89.98458)
		(width 0.11938)
		(layer "F.Cu")
		(net "FTDI_EE_CS")
	)
	(segment
		(start 45.65142 -90.50782)
		(end 45.53204 -90.6272)
		(width 0.11938)
		(layer "F.Cu")
		(net "FTDI_EE_CS")
	)
	(segment
		(start 47.53356 -90.50782)
		(end 47.53356 -89.98458)
		(width 0.11938)
		(layer "F.Cu")
		(net "FTDI_EE_CS")
	)
	(segment
		(start 50.04308 -90.50782)
		(end 50.04308 -89.98458)
		(width 0.11938)
		(layer "F.Cu")
		(net "FTDI_EE_CS")
	)
	(segment
		(start 45.65142 -89.98458)
		(end 45.65142 -90.50782)
		(width 0.11938)
		(layer "F.Cu")
		(net "FTDI_EE_CS")
	)
	(segment
		(start 45.7708 -89.8652)
		(end 45.65142 -89.98458)
		(width 0.11938)
		(layer "F.Cu")
		(net "FTDI_EE_CS")
	)
	(segment
		(start 45.53204 -90.6272)
		(end 45.14342 -90.6272)
		(width 0.11938)
		(layer "F.Cu")
		(net "FTDI_EE_CS")
	)
	(segment
		(start 46.2788 -90.50782)
		(end 46.2788 -89.98458)
		(width 0.11938)
		(layer "F.Cu")
		(net "FTDI_EE_CS")
	)
	(segment
		(start 46.15942 -89.8652)
		(end 45.7708 -89.8652)
		(width 0.11938)
		(layer "F.Cu")
		(net "FTDI_EE_CS")
	)
	(segment
		(start 48.16094 -90.50782)
		(end 48.04156 -90.6272)
		(width 0.11938)
		(layer "F.Cu")
		(net "FTDI_EE_CS")
	)
	(via
		(at 52.07 -89.8652)
		(size 0.508)
		(drill 0.254)
		(layers "F.Cu" "B.Cu")
		(net "FTDI_EE_CS")
	)
	(segment
		(start 53.1368 -89.8652)
		(end 52.07 -89.8652)
		(width 0.11938)
		(layer "B.Cu")
		(net "FTDI_EE_CS")
	)
	(segment
		(start 52.07 -89.8652)
		(end 50.0253 -89.8652)
		(width 0.11938)
		(layer "B.Cu")
		(net "FTDI_EE_CS")
	)
	(segment
		(start 53.4416 -90.17)
		(end 53.1368 -89.8652)
		(width 0.11938)
		(layer "B.Cu")
		(net "FTDI_EE_CS")
	)
	(segment
		(start 47.9171 -88.5952)
		(end 47.79772 -88.71458)
		(width 0.11938)
		(layer "F.Cu")
		(net "FTDI_EE_CLK")
	)
	(segment
		(start 50.30724 -88.71458)
		(end 50.30724 -89.26322)
		(width 0.11938)
		(layer "F.Cu")
		(net "FTDI_EE_CLK")
	)
	(segment
		(start 46.03496 -89.3826)
		(end 45.91558 -89.26322)
		(width 0.11938)
		(layer "F.Cu")
		(net "FTDI_EE_CLK")
	)
	(segment
		(start 49.05248 -89.26322)
		(end 48.9331 -89.3826)
		(width 0.11938)
		(layer "F.Cu")
		(net "FTDI_EE_CLK")
	)
	(segment
		(start 44.66082 -88.71458)
		(end 44.54144 -88.5952)
		(width 0.11938)
		(layer "F.Cu")
		(net "FTDI_EE_CLK")
	)
	(segment
		(start 45.2882 -88.71458)
		(end 45.2882 -89.26322)
		(width 0.11938)
		(layer "F.Cu")
		(net "FTDI_EE_CLK")
	)
	(segment
		(start 45.91558 -88.71458)
		(end 45.7962 -88.5952)
		(width 0.11938)
		(layer "F.Cu")
		(net "FTDI_EE_CLK")
	)
	(segment
		(start 50.42662 -88.5952)
		(end 50.30724 -88.71458)
		(width 0.11938)
		(layer "F.Cu")
		(net "FTDI_EE_CLK")
	)
	(segment
		(start 47.05096 -88.5952)
		(end 46.66234 -88.5952)
		(width 0.11938)
		(layer "F.Cu")
		(net "FTDI_EE_CLK")
	)
	(segment
		(start 47.28972 -89.3826)
		(end 47.17034 -89.26322)
		(width 0.11938)
		(layer "F.Cu")
		(net "FTDI_EE_CLK")
	)
	(segment
		(start 49.67986 -89.26322)
		(end 49.67986 -88.71458)
		(width 0.11938)
		(layer "F.Cu")
		(net "FTDI_EE_CLK")
	)
	(segment
		(start 45.2882 -89.26322)
		(end 45.16882 -89.3826)
		(width 0.11938)
		(layer "F.Cu")
		(net "FTDI_EE_CLK")
	)
	(segment
		(start 49.56048 -88.5952)
		(end 49.17186 -88.5952)
		(width 0.11938)
		(layer "F.Cu")
		(net "FTDI_EE_CLK")
	)
	(segment
		(start 45.91558 -89.26322)
		(end 45.91558 -88.71458)
		(width 0.11938)
		(layer "F.Cu")
		(net "FTDI_EE_CLK")
	)
	(segment
		(start 46.66234 -88.5952)
		(end 46.54296 -88.71458)
		(width 0.11938)
		(layer "F.Cu")
		(net "FTDI_EE_CLK")
	)
	(segment
		(start 48.30572 -88.5952)
		(end 47.9171 -88.5952)
		(width 0.11938)
		(layer "F.Cu")
		(net "FTDI_EE_CLK")
	)
	(segment
		(start 49.05248 -88.71458)
		(end 49.05248 -89.26322)
		(width 0.11938)
		(layer "F.Cu")
		(net "FTDI_EE_CLK")
	)
	(segment
		(start 44.7802 -89.3826)
		(end 44.66082 -89.26322)
		(width 0.11938)
		(layer "F.Cu")
		(net "FTDI_EE_CLK")
	)
	(segment
		(start 47.17034 -88.71458)
		(end 47.05096 -88.5952)
		(width 0.11938)
		(layer "F.Cu")
		(net "FTDI_EE_CLK")
	)
	(segment
		(start 49.67986 -88.71458)
		(end 49.56048 -88.5952)
		(width 0.11938)
		(layer "F.Cu")
		(net "FTDI_EE_CLK")
	)
	(segment
		(start 50.18786 -89.3826)
		(end 49.79924 -89.3826)
		(width 0.11938)
		(layer "F.Cu")
		(net "FTDI_EE_CLK")
	)
	(segment
		(start 49.79924 -89.3826)
		(end 49.67986 -89.26322)
		(width 0.11938)
		(layer "F.Cu")
		(net "FTDI_EE_CLK")
	)
	(segment
		(start 48.4251 -89.26322)
		(end 48.4251 -88.71458)
		(width 0.11938)
		(layer "F.Cu")
		(net "FTDI_EE_CLK")
	)
	(segment
		(start 48.9331 -89.3826)
		(end 48.54448 -89.3826)
		(width 0.11938)
		(layer "F.Cu")
		(net "FTDI_EE_CLK")
	)
	(segment
		(start 47.79772 -89.26322)
		(end 47.67834 -89.3826)
		(width 0.11938)
		(layer "F.Cu")
		(net "FTDI_EE_CLK")
	)
	(segment
		(start 48.4251 -88.71458)
		(end 48.30572 -88.5952)
		(width 0.11938)
		(layer "F.Cu")
		(net "FTDI_EE_CLK")
	)
	(segment
		(start 45.16882 -89.3826)
		(end 44.7802 -89.3826)
		(width 0.11938)
		(layer "F.Cu")
		(net "FTDI_EE_CLK")
	)
	(segment
		(start 50.30724 -89.26322)
		(end 50.18786 -89.3826)
		(width 0.11938)
		(layer "F.Cu")
		(net "FTDI_EE_CLK")
	)
	(segment
		(start 41.7322 -88.5952)
		(end 40.951658 -87.814658)
		(width 0.11938)
		(layer "F.Cu")
		(net "FTDI_EE_CLK")
	)
	(segment
		(start 44.54144 -88.5952)
		(end 41.7322 -88.5952)
		(width 0.11938)
		(layer "F.Cu")
		(net "FTDI_EE_CLK")
	)
	(segment
		(start 48.54448 -89.3826)
		(end 48.4251 -89.26322)
		(width 0.11938)
		(layer "F.Cu")
		(net "FTDI_EE_CLK")
	)
	(segment
		(start 52.07 -88.5952)
		(end 50.42662 -88.5952)
		(width 0.11938)
		(layer "F.Cu")
		(net "FTDI_EE_CLK")
	)
	(segment
		(start 47.67834 -89.3826)
		(end 47.28972 -89.3826)
		(width 0.11938)
		(layer "F.Cu")
		(net "FTDI_EE_CLK")
	)
	(segment
		(start 40.951658 -87.814658)
		(end 34.3408 -87.814658)
		(width 0.11938)
		(layer "F.Cu")
		(net "FTDI_EE_CLK")
	)
	(segment
		(start 49.17186 -88.5952)
		(end 49.05248 -88.71458)
		(width 0.11938)
		(layer "F.Cu")
		(net "FTDI_EE_CLK")
	)
	(segment
		(start 46.54296 -89.26322)
		(end 46.42358 -89.3826)
		(width 0.11938)
		(layer "F.Cu")
		(net "FTDI_EE_CLK")
	)
	(segment
		(start 45.7962 -88.5952)
		(end 45.40758 -88.5952)
		(width 0.11938)
		(layer "F.Cu")
		(net "FTDI_EE_CLK")
	)
	(segment
		(start 46.54296 -88.71458)
		(end 46.54296 -89.26322)
		(width 0.11938)
		(layer "F.Cu")
		(net "FTDI_EE_CLK")
	)
	(segment
		(start 45.40758 -88.5952)
		(end 45.2882 -88.71458)
		(width 0.11938)
		(layer "F.Cu")
		(net "FTDI_EE_CLK")
	)
	(segment
		(start 46.42358 -89.3826)
		(end 46.03496 -89.3826)
		(width 0.11938)
		(layer "F.Cu")
		(net "FTDI_EE_CLK")
	)
	(segment
		(start 44.66082 -89.26322)
		(end 44.66082 -88.71458)
		(width 0.11938)
		(layer "F.Cu")
		(net "FTDI_EE_CLK")
	)
	(segment
		(start 47.79772 -88.71458)
		(end 47.79772 -89.26322)
		(width 0.11938)
		(layer "F.Cu")
		(net "FTDI_EE_CLK")
	)
	(segment
		(start 47.17034 -89.26322)
		(end 47.17034 -88.71458)
		(width 0.11938)
		(layer "F.Cu")
		(net "FTDI_EE_CLK")
	)
	(via
		(at 52.07 -88.5952)
		(size 0.508)
		(drill 0.254)
		(layers "F.Cu" "B.Cu")
		(net "FTDI_EE_CLK")
	)
	(segment
		(start 53.1368 -88.5952)
		(end 53.4416 -88.9)
		(width 0.11938)
		(layer "B.Cu")
		(net "FTDI_EE_CLK")
	)
	(segment
		(start 52.07 -88.5952)
		(end 53.1368 -88.5952)
		(width 0.11938)
		(layer "B.Cu")
		(net "FTDI_EE_CLK")
	)
	(segment
		(start 50.0253 -88.5952)
		(end 52.07 -88.5952)
		(width 0.11938)
		(layer "B.Cu")
		(net "FTDI_EE_CLK")
	)
	(segment
		(start 26.77414 -88.62314)
		(end 26.77414 -90.8812)
		(width 0.254)
		(layer "F.Cu")
		(net "FT4232_VREGOUT")
	)
	(segment
		(start 34.3408 -88.814656)
		(end 33.02 -88.814656)
		(width 0.254)
		(layer "F.Cu")
		(net "FT4232_VREGOUT")
	)
	(segment
		(start 33.112456 -81.314544)
		(end 34.3408 -81.314544)
		(width 0.381)
		(layer "F.Cu")
		(net "FT4232_VREGOUT")
	)
	(segment
		(start 26.420826 -88.269826)
		(end 26.77414 -88.62314)
		(width 0.254)
		(layer "F.Cu")
		(net "FT4232_VREGOUT")
	)
	(segment
		(start 32.766 -81.661)
		(end 33.112456 -81.314544)
		(width 0.381)
		(layer "F.Cu")
		(net "FT4232_VREGOUT")
	)
	(segment
		(start 26.420826 -88.24595)
		(end 26.420826 -88.269826)
		(width 0.254)
		(layer "F.Cu")
		(net "FT4232_VREGOUT")
	)
	(segment
		(start 26.77414 -79.248)
		(end 26.77414 -80.899)
		(width 0.254)
		(layer "F.Cu")
		(net "FT4232_VREGOUT")
	)
	(via
		(at 26.420826 -88.24595)
		(size 0.508)
		(drill 0.254)
		(layers "F.Cu" "B.Cu")
		(net "FT4232_VREGOUT")
	)
	(via
		(at 32.766 -81.661)
		(size 0.508)
		(drill 0.254)
		(layers "F.Cu" "B.Cu")
		(net "FT4232_VREGOUT")
	)
	(via
		(at 26.77414 -80.899)
		(size 0.508)
		(drill 0.254)
		(layers "F.Cu" "B.Cu")
		(net "FT4232_VREGOUT")
	)
	(via
		(at 33.02 -88.814656)
		(size 0.508)
		(drill 0.254)
		(layers "F.Cu" "B.Cu")
		(net "FT4232_VREGOUT")
	)
	(segment
		(start 26.289 -80.41386)
		(end 26.289 -79.6544)
		(width 0.381)
		(layer "B.Cu")
		(net "FT4232_VREGOUT")
	)
	(segment
		(start 33.105344 -88.9)
		(end 33.8836 -88.9)
		(width 0.381)
		(layer "B.Cu")
		(net "FT4232_VREGOUT")
	)
	(segment
		(start 31.877 -86.995)
		(end 33.02 -88.138)
		(width 0.4572)
		(layer "B.Cu")
		(net "FT4232_VREGOUT")
	)
	(segment
		(start 31.877 -82.55)
		(end 31.877 -86.995)
		(width 0.4572)
		(layer "B.Cu")
		(net "FT4232_VREGOUT")
	)
	(segment
		(start 33.02 -88.814656)
		(end 33.105344 -88.9)
		(width 0.381)
		(layer "B.Cu")
		(net "FT4232_VREGOUT")
	)
	(segment
		(start 26.77414 -80.899)
		(end 26.289 -80.41386)
		(width 0.381)
		(layer "B.Cu")
		(net "FT4232_VREGOUT")
	)
	(segment
		(start 33.02 -88.138)
		(end 33.02 -88.814656)
		(width 0.4572)
		(layer "B.Cu")
		(net "FT4232_VREGOUT")
	)
	(segment
		(start 32.766 -81.661)
		(end 31.877 -82.55)
		(width 0.4572)
		(layer "B.Cu")
		(net "FT4232_VREGOUT")
	)
	(segment
		(start 27.53614 -81.661)
		(end 26.77414 -80.899)
		(width 0.4572)
		(layer "In2.Cu")
		(net "FT4232_VREGOUT")
	)
	(segment
		(start 33.02 -88.814656)
		(end 31.746444 -87.5411)
		(width 0.4572)
		(layer "In2.Cu")
		(net "FT4232_VREGOUT")
	)
	(segment
		(start 32.766 -81.661)
		(end 27.53614 -81.661)
		(width 0.4572)
		(layer "In2.Cu")
		(net "FT4232_VREGOUT")
	)
	(segment
		(start 31.687008 -87.5411)
		(end 31.674308 -87.5284)
		(width 0.4572)
		(layer "In2.Cu")
		(net "FT4232_VREGOUT")
	)
	(segment
		(start 30.4419 -87.5411)
		(end 29.73705 -88.24595)
		(width 0.4572)
		(layer "In2.Cu")
		(net "FT4232_VREGOUT")
	)
	(segment
		(start 31.746444 -87.5411)
		(end 31.687008 -87.5411)
		(width 0.4572)
		(layer "In2.Cu")
		(net "FT4232_VREGOUT")
	)
	(segment
		(start 31.063692 -87.5284)
		(end 31.050992 -87.5411)
		(width 0.4572)
		(layer "In2.Cu")
		(net "FT4232_VREGOUT")
	)
	(segment
		(start 31.050992 -87.5411)
		(end 30.4419 -87.5411)
		(width 0.4572)
		(layer "In2.Cu")
		(net "FT4232_VREGOUT")
	)
	(segment
		(start 31.674308 -87.5284)
		(end 31.063692 -87.5284)
		(width 0.4572)
		(layer "In2.Cu")
		(net "FT4232_VREGOUT")
	)
	(segment
		(start 29.73705 -88.24595)
		(end 26.420826 -88.24595)
		(width 0.4572)
		(layer "In2.Cu")
		(net "FT4232_VREGOUT")
	)
	(segment
		(start 106.807 -92.964)
		(end 106.86288 -93.01988)
		(width 0.11938)
		(layer "F.Cu")
		(net "FT4232_TMS_SPICS_N")
	)
	(segment
		(start 106.86288 -93.01988)
		(end 108.5723 -93.01988)
		(width 0.11938)
		(layer "F.Cu")
		(net "FT4232_TMS_SPICS_N")
	)
	(via
		(at 24.765 -86.614)
		(size 0.508)
		(drill 0.254)
		(layers "F.Cu" "B.Cu")
		(net "FT4232_TMS_SPICS_N")
	)
	(via
		(at 106.807 -92.964)
		(size 0.508)
		(drill 0.254)
		(layers "F.Cu" "B.Cu")
		(net "FT4232_TMS_SPICS_N")
	)
	(segment
		(start 23.1394 -86.614)
		(end 24.765 -86.614)
		(width 0.11938)
		(layer "B.Cu")
		(net "FT4232_TMS_SPICS_N")
	)
	(segment
		(start 84.37118 -86.106)
		(end 83.92668 -86.5505)
		(width 0.127)
		(layer "In2.Cu")
		(net "FT4232_TMS_SPICS_N")
	)
	(segment
		(start 34.29 -85.725)
		(end 25.654 -85.725)
		(width 0.127)
		(layer "In2.Cu")
		(net "FT4232_TMS_SPICS_N")
	)
	(segment
		(start 102.19944 -89.43086)
		(end 101.41458 -88.646)
		(width 0.127)
		(layer "In2.Cu")
		(net "FT4232_TMS_SPICS_N")
	)
	(segment
		(start 81.080864 -86.995)
		(end 72.405748 -86.995)
		(width 0.127)
		(layer "In2.Cu")
		(net "FT4232_TMS_SPICS_N")
	)
	(segment
		(start 49.145698 -91.313)
		(end 47.875698 -90.043)
		(width 0.127)
		(layer "In2.Cu")
		(net "FT4232_TMS_SPICS_N")
	)
	(segment
		(start 95.57512 -87.376)
		(end 91.0844 -87.376)
		(width 0.127)
		(layer "In2.Cu")
		(net "FT4232_TMS_SPICS_N")
	)
	(segment
		(start 25.654 -85.725)
		(end 24.765 -86.614)
		(width 0.127)
		(layer "In2.Cu")
		(net "FT4232_TMS_SPICS_N")
	)
	(segment
		(start 102.6668 -90.43924)
		(end 102.19944 -89.97188)
		(width 0.127)
		(layer "In2.Cu")
		(net "FT4232_TMS_SPICS_N")
	)
	(segment
		(start 35.433 -86.868)
		(end 34.29 -85.725)
		(width 0.127)
		(layer "In2.Cu")
		(net "FT4232_TMS_SPICS_N")
	)
	(segment
		(start 83.92668 -86.5505)
		(end 81.525364 -86.5505)
		(width 0.127)
		(layer "In2.Cu")
		(net "FT4232_TMS_SPICS_N")
	)
	(segment
		(start 81.525364 -86.5505)
		(end 81.080864 -86.995)
		(width 0.127)
		(layer "In2.Cu")
		(net "FT4232_TMS_SPICS_N")
	)
	(segment
		(start 108.204 -91.567)
		(end 108.204 -89.535)
		(width 0.127)
		(layer "In2.Cu")
		(net "FT4232_TMS_SPICS_N")
	)
	(segment
		(start 36.532566 -86.868)
		(end 35.433 -86.868)
		(width 0.127)
		(layer "In2.Cu")
		(net "FT4232_TMS_SPICS_N")
	)
	(segment
		(start 105.88244 -90.43924)
		(end 102.6668 -90.43924)
		(width 0.127)
		(layer "In2.Cu")
		(net "FT4232_TMS_SPICS_N")
	)
	(segment
		(start 108.05414 -89.38514)
		(end 106.93654 -89.38514)
		(width 0.127)
		(layer "In2.Cu")
		(net "FT4232_TMS_SPICS_N")
	)
	(segment
		(start 108.204 -89.535)
		(end 108.05414 -89.38514)
		(width 0.127)
		(layer "In2.Cu")
		(net "FT4232_TMS_SPICS_N")
	)
	(segment
		(start 72.405748 -86.995)
		(end 70.201028 -89.19972)
		(width 0.127)
		(layer "In2.Cu")
		(net "FT4232_TMS_SPICS_N")
	)
	(segment
		(start 101.41458 -88.646)
		(end 96.84512 -88.646)
		(width 0.127)
		(layer "In2.Cu")
		(net "FT4232_TMS_SPICS_N")
	)
	(segment
		(start 96.84512 -88.646)
		(end 95.57512 -87.376)
		(width 0.127)
		(layer "In2.Cu")
		(net "FT4232_TMS_SPICS_N")
	)
	(segment
		(start 37.548566 -87.884)
		(end 36.532566 -86.868)
		(width 0.127)
		(layer "In2.Cu")
		(net "FT4232_TMS_SPICS_N")
	)
	(segment
		(start 102.19944 -89.97188)
		(end 102.19944 -89.43086)
		(width 0.127)
		(layer "In2.Cu")
		(net "FT4232_TMS_SPICS_N")
	)
	(segment
		(start 90.805 -87.0966)
		(end 87.086186 -87.0966)
		(width 0.127)
		(layer "In2.Cu")
		(net "FT4232_TMS_SPICS_N")
	)
	(segment
		(start 58.93816 -91.313)
		(end 49.145698 -91.313)
		(width 0.127)
		(layer "In2.Cu")
		(net "FT4232_TMS_SPICS_N")
	)
	(segment
		(start 40.820848 -87.884)
		(end 37.548566 -87.884)
		(width 0.127)
		(layer "In2.Cu")
		(net "FT4232_TMS_SPICS_N")
	)
	(segment
		(start 70.201028 -89.19972)
		(end 61.05144 -89.19972)
		(width 0.127)
		(layer "In2.Cu")
		(net "FT4232_TMS_SPICS_N")
	)
	(segment
		(start 87.086186 -87.0966)
		(end 86.095586 -86.106)
		(width 0.127)
		(layer "In2.Cu")
		(net "FT4232_TMS_SPICS_N")
	)
	(segment
		(start 91.0844 -87.376)
		(end 90.805 -87.0966)
		(width 0.127)
		(layer "In2.Cu")
		(net "FT4232_TMS_SPICS_N")
	)
	(segment
		(start 42.979848 -90.043)
		(end 40.820848 -87.884)
		(width 0.127)
		(layer "In2.Cu")
		(net "FT4232_TMS_SPICS_N")
	)
	(segment
		(start 61.05144 -89.19972)
		(end 58.93816 -91.313)
		(width 0.127)
		(layer "In2.Cu")
		(net "FT4232_TMS_SPICS_N")
	)
	(segment
		(start 106.93654 -89.38514)
		(end 105.88244 -90.43924)
		(width 0.127)
		(layer "In2.Cu")
		(net "FT4232_TMS_SPICS_N")
	)
	(segment
		(start 86.095586 -86.106)
		(end 84.37118 -86.106)
		(width 0.127)
		(layer "In2.Cu")
		(net "FT4232_TMS_SPICS_N")
	)
	(segment
		(start 106.807 -92.964)
		(end 108.204 -91.567)
		(width 0.127)
		(layer "In2.Cu")
		(net "FT4232_TMS_SPICS_N")
	)
	(segment
		(start 47.875698 -90.043)
		(end 42.979848 -90.043)
		(width 0.127)
		(layer "In2.Cu")
		(net "FT4232_TMS_SPICS_N")
	)
	(segment
		(start 107.315 -90.678254)
		(end 107.706668 -91.069922)
		(width 0.11938)
		(layer "F.Cu")
		(net "FT4232_TDO_MISO")
	)
	(segment
		(start 107.706668 -91.069922)
		(end 108.5723 -91.069922)
		(width 0.11938)
		(layer "F.Cu")
		(net "FT4232_TDO_MISO")
	)
	(segment
		(start 107.315 -90.043)
		(end 107.315 -90.678254)
		(width 0.11938)
		(layer "F.Cu")
		(net "FT4232_TDO_MISO")
	)
	(via
		(at 107.315 -90.043)
		(size 0.508)
		(drill 0.254)
		(layers "F.Cu" "B.Cu")
		(net "FT4232_TDO_MISO")
	)
	(via
		(at 25.781 -86.614)
		(size 0.508)
		(drill 0.254)
		(layers "F.Cu" "B.Cu")
		(net "FT4232_TDO_MISO")
	)
	(segment
		(start 23.6474 -88.392)
		(end 23.1394 -88.9)
		(width 0.11938)
		(layer "B.Cu")
		(net "FT4232_TDO_MISO")
	)
	(segment
		(start 25.781 -86.614)
		(end 25.781 -86.741)
		(width 0.11938)
		(layer "B.Cu")
		(net "FT4232_TDO_MISO")
	)
	(segment
		(start 24.13 -88.392)
		(end 23.6474 -88.392)
		(width 0.11938)
		(layer "B.Cu")
		(net "FT4232_TDO_MISO")
	)
	(segment
		(start 25.781 -86.741)
		(end 24.13 -88.392)
		(width 0.11938)
		(layer "B.Cu")
		(net "FT4232_TDO_MISO")
	)
	(segment
		(start 67.459606 -90.40368)
		(end 67.840606 -90.40368)
		(width 0.127)
		(layer "In2.Cu")
		(net "FT4232_TDO_MISO")
	)
	(segment
		(start 68.094606 -89.82964)
		(end 68.475606 -89.82964)
		(width 0.127)
		(layer "In2.Cu")
		(net "FT4232_TDO_MISO")
	)
	(segment
		(start 67.332606 -90.27668)
		(end 67.459606 -90.40368)
		(width 0.127)
		(layer "In2.Cu")
		(net "FT4232_TDO_MISO")
	)
	(segment
		(start 69.715634 -90.40368)
		(end 72.235314 -87.884)
		(width 0.127)
		(layer "In2.Cu")
		(net "FT4232_TDO_MISO")
	)
	(segment
		(start 59.40298 -91.821)
		(end 60.8203 -90.40368)
		(width 0.127)
		(layer "In2.Cu")
		(net "FT4232_TDO_MISO")
	)
	(segment
		(start 42.769282 -90.551)
		(end 47.665132 -90.551)
		(width 0.127)
		(layer "In2.Cu")
		(net "FT4232_TDO_MISO")
	)
	(segment
		(start 92.271596 -88.588342)
		(end 92.271596 -89.444576)
		(width 0.127)
		(layer "In2.Cu")
		(net "FT4232_TDO_MISO")
	)
	(segment
		(start 48.935132 -91.821)
		(end 59.40298 -91.821)
		(width 0.127)
		(layer "In2.Cu")
		(net "FT4232_TDO_MISO")
	)
	(segment
		(start 90.9066 -88.2142)
		(end 91.897454 -88.2142)
		(width 0.127)
		(layer "In2.Cu")
		(net "FT4232_TDO_MISO")
	)
	(segment
		(start 105.64368 -91.71432)
		(end 107.315 -90.043)
		(width 0.127)
		(layer "In2.Cu")
		(net "FT4232_TDO_MISO")
	)
	(segment
		(start 84.581746 -86.614)
		(end 85.82406 -86.614)
		(width 0.127)
		(layer "In2.Cu")
		(net "FT4232_TDO_MISO")
	)
	(segment
		(start 67.967606 -89.95664)
		(end 68.094606 -89.82964)
		(width 0.127)
		(layer "In2.Cu")
		(net "FT4232_TDO_MISO")
	)
	(segment
		(start 66.824606 -89.82964)
		(end 67.205606 -89.82964)
		(width 0.127)
		(layer "In2.Cu")
		(net "FT4232_TDO_MISO")
	)
	(segment
		(start 68.602606 -89.95664)
		(end 68.602606 -90.27668)
		(width 0.127)
		(layer "In2.Cu")
		(net "FT4232_TDO_MISO")
	)
	(segment
		(start 86.96706 -87.757)
		(end 90.4494 -87.757)
		(width 0.127)
		(layer "In2.Cu")
		(net "FT4232_TDO_MISO")
	)
	(segment
		(start 34.798 -87.376)
		(end 36.322 -87.376)
		(width 0.127)
		(layer "In2.Cu")
		(net "FT4232_TDO_MISO")
	)
	(segment
		(start 90.4494 -87.757)
		(end 90.9066 -88.2142)
		(width 0.127)
		(layer "In2.Cu")
		(net "FT4232_TDO_MISO")
	)
	(segment
		(start 66.697606 -89.95664)
		(end 66.824606 -89.82964)
		(width 0.127)
		(layer "In2.Cu")
		(net "FT4232_TDO_MISO")
	)
	(segment
		(start 26.162 -86.233)
		(end 33.655 -86.233)
		(width 0.127)
		(layer "In2.Cu")
		(net "FT4232_TDO_MISO")
	)
	(segment
		(start 68.729606 -90.40368)
		(end 69.715634 -90.40368)
		(width 0.127)
		(layer "In2.Cu")
		(net "FT4232_TDO_MISO")
	)
	(segment
		(start 83.311746 -87.884)
		(end 84.581746 -86.614)
		(width 0.127)
		(layer "In2.Cu")
		(net "FT4232_TDO_MISO")
	)
	(segment
		(start 60.8203 -90.40368)
		(end 66.570606 -90.40368)
		(width 0.127)
		(layer "In2.Cu")
		(net "FT4232_TDO_MISO")
	)
	(segment
		(start 67.332606 -89.95664)
		(end 67.332606 -90.27668)
		(width 0.127)
		(layer "In2.Cu")
		(net "FT4232_TDO_MISO")
	)
	(segment
		(start 101.13772 -90.4494)
		(end 102.40264 -91.71432)
		(width 0.127)
		(layer "In2.Cu")
		(net "FT4232_TDO_MISO")
	)
	(segment
		(start 72.235314 -87.884)
		(end 83.311746 -87.884)
		(width 0.127)
		(layer "In2.Cu")
		(net "FT4232_TDO_MISO")
	)
	(segment
		(start 102.40264 -91.71432)
		(end 105.64368 -91.71432)
		(width 0.127)
		(layer "In2.Cu")
		(net "FT4232_TDO_MISO")
	)
	(segment
		(start 47.665132 -90.551)
		(end 48.935132 -91.821)
		(width 0.127)
		(layer "In2.Cu")
		(net "FT4232_TDO_MISO")
	)
	(segment
		(start 66.697606 -90.27668)
		(end 66.697606 -89.95664)
		(width 0.127)
		(layer "In2.Cu")
		(net "FT4232_TDO_MISO")
	)
	(segment
		(start 100.057966 -90.4494)
		(end 101.13772 -90.4494)
		(width 0.127)
		(layer "In2.Cu")
		(net "FT4232_TDO_MISO")
	)
	(segment
		(start 92.271596 -89.444576)
		(end 93.25102 -90.424)
		(width 0.127)
		(layer "In2.Cu")
		(net "FT4232_TDO_MISO")
	)
	(segment
		(start 25.781 -86.614)
		(end 26.162 -86.233)
		(width 0.127)
		(layer "In2.Cu")
		(net "FT4232_TDO_MISO")
	)
	(segment
		(start 68.602606 -90.27668)
		(end 68.729606 -90.40368)
		(width 0.127)
		(layer "In2.Cu")
		(net "FT4232_TDO_MISO")
	)
	(segment
		(start 67.205606 -89.82964)
		(end 67.332606 -89.95664)
		(width 0.127)
		(layer "In2.Cu")
		(net "FT4232_TDO_MISO")
	)
	(segment
		(start 68.475606 -89.82964)
		(end 68.602606 -89.95664)
		(width 0.127)
		(layer "In2.Cu")
		(net "FT4232_TDO_MISO")
	)
	(segment
		(start 100.032566 -90.424)
		(end 100.057966 -90.4494)
		(width 0.127)
		(layer "In2.Cu")
		(net "FT4232_TDO_MISO")
	)
	(segment
		(start 66.570606 -90.40368)
		(end 66.697606 -90.27668)
		(width 0.127)
		(layer "In2.Cu")
		(net "FT4232_TDO_MISO")
	)
	(segment
		(start 37.338 -88.392)
		(end 40.610282 -88.392)
		(width 0.127)
		(layer "In2.Cu")
		(net "FT4232_TDO_MISO")
	)
	(segment
		(start 85.82406 -86.614)
		(end 86.96706 -87.757)
		(width 0.127)
		(layer "In2.Cu")
		(net "FT4232_TDO_MISO")
	)
	(segment
		(start 40.610282 -88.392)
		(end 42.769282 -90.551)
		(width 0.127)
		(layer "In2.Cu")
		(net "FT4232_TDO_MISO")
	)
	(segment
		(start 67.840606 -90.40368)
		(end 67.967606 -90.27668)
		(width 0.127)
		(layer "In2.Cu")
		(net "FT4232_TDO_MISO")
	)
	(segment
		(start 36.322 -87.376)
		(end 37.338 -88.392)
		(width 0.127)
		(layer "In2.Cu")
		(net "FT4232_TDO_MISO")
	)
	(segment
		(start 93.25102 -90.424)
		(end 100.032566 -90.424)
		(width 0.127)
		(layer "In2.Cu")
		(net "FT4232_TDO_MISO")
	)
	(segment
		(start 33.655 -86.233)
		(end 34.798 -87.376)
		(width 0.127)
		(layer "In2.Cu")
		(net "FT4232_TDO_MISO")
	)
	(segment
		(start 91.897454 -88.2142)
		(end 92.271596 -88.588342)
		(width 0.127)
		(layer "In2.Cu")
		(net "FT4232_TDO_MISO")
	)
	(segment
		(start 67.967606 -90.27668)
		(end 67.967606 -89.95664)
		(width 0.127)
		(layer "In2.Cu")
		(net "FT4232_TDO_MISO")
	)
	(segment
		(start 100.609908 -91.719908)
		(end 100.33 -91.44)
		(width 0.11938)
		(layer "F.Cu")
		(net "FT4232_TDI_MOSI")
	)
	(segment
		(start 102.5017 -91.719908)
		(end 100.609908 -91.719908)
		(width 0.11938)
		(layer "F.Cu")
		(net "FT4232_TDI_MOSI")
	)
	(via
		(at 21.209 -91.44)
		(size 0.508)
		(drill 0.254)
		(layers "F.Cu" "B.Cu")
		(net "FT4232_TDI_MOSI")
	)
	(via
		(at 100.33 -91.44)
		(size 0.508)
		(drill 0.254)
		(layers "F.Cu" "B.Cu")
		(net "FT4232_TDI_MOSI")
	)
	(segment
		(start 21.209 -91.44)
		(end 21.336 -91.44)
		(width 0.11938)
		(layer "B.Cu")
		(net "FT4232_TDI_MOSI")
	)
	(segment
		(start 21.463 -91.313)
		(end 22.4028 -91.313)
		(width 0.11938)
		(layer "B.Cu")
		(net "FT4232_TDI_MOSI")
	)
	(segment
		(start 21.336 -91.44)
		(end 21.463 -91.313)
		(width 0.11938)
		(layer "B.Cu")
		(net "FT4232_TDI_MOSI")
	)
	(segment
		(start 65.209166 -90.98788)
		(end 65.590166 -90.98788)
		(width 0.127)
		(layer "In2.Cu")
		(net "FT4232_TDI_MOSI")
	)
	(segment
		(start 21.209 -91.44)
		(end 25.019 -87.63)
		(width 0.127)
		(layer "In2.Cu")
		(net "FT4232_TDI_MOSI")
	)
	(segment
		(start 64.447166 -91.186)
		(end 64.447166 -91.64066)
		(width 0.127)
		(layer "In2.Cu")
		(net "FT4232_TDI_MOSI")
	)
	(segment
		(start 63.050166 -90.98788)
		(end 63.177166 -91.11488)
		(width 0.127)
		(layer "In2.Cu")
		(net "FT4232_TDI_MOSI")
	)
	(segment
		(start 98.39579 -90.932)
		(end 98.52279 -91.059)
		(width 0.127)
		(layer "In2.Cu")
		(net "FT4232_TDI_MOSI")
	)
	(segment
		(start 33.020254 -86.741)
		(end 35.814254 -89.535)
		(width 0.127)
		(layer "In2.Cu")
		(net "FT4232_TDI_MOSI")
	)
	(segment
		(start 66.987166 -91.11488)
		(end 66.987166 -91.64066)
		(width 0.127)
		(layer "In2.Cu")
		(net "FT4232_TDI_MOSI")
	)
	(segment
		(start 63.939166 -91.059)
		(end 64.320166 -91.059)
		(width 0.127)
		(layer "In2.Cu")
		(net "FT4232_TDI_MOSI")
	)
	(segment
		(start 66.352166 -91.11488)
		(end 66.479166 -90.98788)
		(width 0.127)
		(layer "In2.Cu")
		(net "FT4232_TDI_MOSI")
	)
	(segment
		(start 61.907166 -91.64066)
		(end 62.034166 -91.76766)
		(width 0.127)
		(layer "In2.Cu")
		(net "FT4232_TDI_MOSI")
	)
	(segment
		(start 63.177166 -91.64066)
		(end 63.304166 -91.76766)
		(width 0.127)
		(layer "In2.Cu")
		(net "FT4232_TDI_MOSI")
	)
	(segment
		(start 62.415166 -91.76766)
		(end 62.542166 -91.64066)
		(width 0.127)
		(layer "In2.Cu")
		(net "FT4232_TDI_MOSI")
	)
	(segment
		(start 38.862 -89.535)
		(end 40.386 -91.059)
		(width 0.127)
		(layer "In2.Cu")
		(net "FT4232_TDI_MOSI")
	)
	(segment
		(start 64.447166 -91.64066)
		(end 64.574166 -91.76766)
		(width 0.127)
		(layer "In2.Cu")
		(net "FT4232_TDI_MOSI")
	)
	(segment
		(start 72.44588 -88.392)
		(end 90.33764 -88.392)
		(width 0.127)
		(layer "In2.Cu")
		(net "FT4232_TDI_MOSI")
	)
	(segment
		(start 62.542166 -91.11488)
		(end 62.669166 -90.98788)
		(width 0.127)
		(layer "In2.Cu")
		(net "FT4232_TDI_MOSI")
	)
	(segment
		(start 67.622166 -91.11488)
		(end 67.749166 -90.98788)
		(width 0.127)
		(layer "In2.Cu")
		(net "FT4232_TDI_MOSI")
	)
	(segment
		(start 64.320166 -91.059)
		(end 64.447166 -91.186)
		(width 0.127)
		(layer "In2.Cu")
		(net "FT4232_TDI_MOSI")
	)
	(segment
		(start 65.082166 -91.64066)
		(end 65.082166 -91.11488)
		(width 0.127)
		(layer "In2.Cu")
		(net "FT4232_TDI_MOSI")
	)
	(segment
		(start 61.907166 -91.11488)
		(end 61.907166 -91.64066)
		(width 0.127)
		(layer "In2.Cu")
		(net "FT4232_TDI_MOSI")
	)
	(segment
		(start 40.386 -91.059)
		(end 47.454566 -91.059)
		(width 0.127)
		(layer "In2.Cu")
		(net "FT4232_TDI_MOSI")
	)
	(segment
		(start 60.39612 -91.76766)
		(end 61.145166 -91.76766)
		(width 0.127)
		(layer "In2.Cu")
		(net "FT4232_TDI_MOSI")
	)
	(segment
		(start 68.130166 -90.98788)
		(end 68.257166 -91.11488)
		(width 0.127)
		(layer "In2.Cu")
		(net "FT4232_TDI_MOSI")
	)
	(segment
		(start 69.07022 -91.76766)
		(end 72.44588 -88.392)
		(width 0.127)
		(layer "In2.Cu")
		(net "FT4232_TDI_MOSI")
	)
	(segment
		(start 68.384166 -91.76766)
		(end 69.07022 -91.76766)
		(width 0.127)
		(layer "In2.Cu")
		(net "FT4232_TDI_MOSI")
	)
	(segment
		(start 61.272166 -91.64066)
		(end 61.272166 -91.11488)
		(width 0.127)
		(layer "In2.Cu")
		(net "FT4232_TDI_MOSI")
	)
	(segment
		(start 63.812166 -91.64066)
		(end 63.812166 -91.186)
		(width 0.127)
		(layer "In2.Cu")
		(net "FT4232_TDI_MOSI")
	)
	(segment
		(start 25.019 -87.63)
		(end 26.084784 -87.63)
		(width 0.127)
		(layer "In2.Cu")
		(net "FT4232_TDI_MOSI")
	)
	(segment
		(start 64.955166 -91.76766)
		(end 65.082166 -91.64066)
		(width 0.127)
		(layer "In2.Cu")
		(net "FT4232_TDI_MOSI")
	)
	(segment
		(start 99.15779 -91.29522)
		(end 99.15779 -91.059)
		(width 0.127)
		(layer "In2.Cu")
		(net "FT4232_TDI_MOSI")
	)
	(segment
		(start 26.973784 -86.741)
		(end 33.020254 -86.741)
		(width 0.127)
		(layer "In2.Cu")
		(net "FT4232_TDI_MOSI")
	)
	(segment
		(start 68.257166 -91.64066)
		(end 68.384166 -91.76766)
		(width 0.127)
		(layer "In2.Cu")
		(net "FT4232_TDI_MOSI")
	)
	(segment
		(start 65.717166 -91.64066)
		(end 65.844166 -91.76766)
		(width 0.127)
		(layer "In2.Cu")
		(net "FT4232_TDI_MOSI")
	)
	(segment
		(start 65.717166 -91.11488)
		(end 65.717166 -91.64066)
		(width 0.127)
		(layer "In2.Cu")
		(net "FT4232_TDI_MOSI")
	)
	(segment
		(start 35.814254 -89.535)
		(end 38.862 -89.535)
		(width 0.127)
		(layer "In2.Cu")
		(net "FT4232_TDI_MOSI")
	)
	(segment
		(start 98.64979 -91.42222)
		(end 99.03079 -91.42222)
		(width 0.127)
		(layer "In2.Cu")
		(net "FT4232_TDI_MOSI")
	)
	(segment
		(start 66.225166 -91.76766)
		(end 66.352166 -91.64066)
		(width 0.127)
		(layer "In2.Cu")
		(net "FT4232_TDI_MOSI")
	)
	(segment
		(start 67.749166 -90.98788)
		(end 68.130166 -90.98788)
		(width 0.127)
		(layer "In2.Cu")
		(net "FT4232_TDI_MOSI")
	)
	(segment
		(start 64.574166 -91.76766)
		(end 64.955166 -91.76766)
		(width 0.127)
		(layer "In2.Cu")
		(net "FT4232_TDI_MOSI")
	)
	(segment
		(start 61.399166 -90.98788)
		(end 61.780166 -90.98788)
		(width 0.127)
		(layer "In2.Cu")
		(net "FT4232_TDI_MOSI")
	)
	(segment
		(start 62.669166 -90.98788)
		(end 63.050166 -90.98788)
		(width 0.127)
		(layer "In2.Cu")
		(net "FT4232_TDI_MOSI")
	)
	(segment
		(start 26.084784 -87.63)
		(end 26.973784 -86.741)
		(width 0.127)
		(layer "In2.Cu")
		(net "FT4232_TDI_MOSI")
	)
	(segment
		(start 65.844166 -91.76766)
		(end 66.225166 -91.76766)
		(width 0.127)
		(layer "In2.Cu")
		(net "FT4232_TDI_MOSI")
	)
	(segment
		(start 66.987166 -91.64066)
		(end 67.114166 -91.76766)
		(width 0.127)
		(layer "In2.Cu")
		(net "FT4232_TDI_MOSI")
	)
	(segment
		(start 61.780166 -90.98788)
		(end 61.907166 -91.11488)
		(width 0.127)
		(layer "In2.Cu")
		(net "FT4232_TDI_MOSI")
	)
	(segment
		(start 68.257166 -91.11488)
		(end 68.257166 -91.64066)
		(width 0.127)
		(layer "In2.Cu")
		(net "FT4232_TDI_MOSI")
	)
	(segment
		(start 67.622166 -91.64066)
		(end 67.622166 -91.11488)
		(width 0.127)
		(layer "In2.Cu")
		(net "FT4232_TDI_MOSI")
	)
	(segment
		(start 99.15779 -91.059)
		(end 99.28479 -90.932)
		(width 0.127)
		(layer "In2.Cu")
		(net "FT4232_TDI_MOSI")
	)
	(segment
		(start 99.28479 -90.932)
		(end 99.822 -90.932)
		(width 0.127)
		(layer "In2.Cu")
		(net "FT4232_TDI_MOSI")
	)
	(segment
		(start 63.685166 -91.76766)
		(end 63.812166 -91.64066)
		(width 0.127)
		(layer "In2.Cu")
		(net "FT4232_TDI_MOSI")
	)
	(segment
		(start 48.724566 -92.329)
		(end 59.83478 -92.329)
		(width 0.127)
		(layer "In2.Cu")
		(net "FT4232_TDI_MOSI")
	)
	(segment
		(start 62.542166 -91.64066)
		(end 62.542166 -91.11488)
		(width 0.127)
		(layer "In2.Cu")
		(net "FT4232_TDI_MOSI")
	)
	(segment
		(start 65.590166 -90.98788)
		(end 65.717166 -91.11488)
		(width 0.127)
		(layer "In2.Cu")
		(net "FT4232_TDI_MOSI")
	)
	(segment
		(start 98.52279 -91.059)
		(end 98.52279 -91.29522)
		(width 0.127)
		(layer "In2.Cu")
		(net "FT4232_TDI_MOSI")
	)
	(segment
		(start 61.272166 -91.11488)
		(end 61.399166 -90.98788)
		(width 0.127)
		(layer "In2.Cu")
		(net "FT4232_TDI_MOSI")
	)
	(segment
		(start 59.83478 -92.329)
		(end 60.39612 -91.76766)
		(width 0.127)
		(layer "In2.Cu")
		(net "FT4232_TDI_MOSI")
	)
	(segment
		(start 67.495166 -91.76766)
		(end 67.622166 -91.64066)
		(width 0.127)
		(layer "In2.Cu")
		(net "FT4232_TDI_MOSI")
	)
	(segment
		(start 63.177166 -91.11488)
		(end 63.177166 -91.64066)
		(width 0.127)
		(layer "In2.Cu")
		(net "FT4232_TDI_MOSI")
	)
	(segment
		(start 63.304166 -91.76766)
		(end 63.685166 -91.76766)
		(width 0.127)
		(layer "In2.Cu")
		(net "FT4232_TDI_MOSI")
	)
	(segment
		(start 61.145166 -91.76766)
		(end 61.272166 -91.64066)
		(width 0.127)
		(layer "In2.Cu")
		(net "FT4232_TDI_MOSI")
	)
	(segment
		(start 90.33764 -88.392)
		(end 92.87764 -90.932)
		(width 0.127)
		(layer "In2.Cu")
		(net "FT4232_TDI_MOSI")
	)
	(segment
		(start 63.812166 -91.186)
		(end 63.939166 -91.059)
		(width 0.127)
		(layer "In2.Cu")
		(net "FT4232_TDI_MOSI")
	)
	(segment
		(start 67.114166 -91.76766)
		(end 67.495166 -91.76766)
		(width 0.127)
		(layer "In2.Cu")
		(net "FT4232_TDI_MOSI")
	)
	(segment
		(start 47.454566 -91.059)
		(end 48.724566 -92.329)
		(width 0.127)
		(layer "In2.Cu")
		(net "FT4232_TDI_MOSI")
	)
	(segment
		(start 62.034166 -91.76766)
		(end 62.415166 -91.76766)
		(width 0.127)
		(layer "In2.Cu")
		(net "FT4232_TDI_MOSI")
	)
	(segment
		(start 66.860166 -90.98788)
		(end 66.987166 -91.11488)
		(width 0.127)
		(layer "In2.Cu")
		(net "FT4232_TDI_MOSI")
	)
	(segment
		(start 99.03079 -91.42222)
		(end 99.15779 -91.29522)
		(width 0.127)
		(layer "In2.Cu")
		(net "FT4232_TDI_MOSI")
	)
	(segment
		(start 92.87764 -90.932)
		(end 98.39579 -90.932)
		(width 0.127)
		(layer "In2.Cu")
		(net "FT4232_TDI_MOSI")
	)
	(segment
		(start 98.52279 -91.29522)
		(end 98.64979 -91.42222)
		(width 0.127)
		(layer "In2.Cu")
		(net "FT4232_TDI_MOSI")
	)
	(segment
		(start 66.479166 -90.98788)
		(end 66.860166 -90.98788)
		(width 0.127)
		(layer "In2.Cu")
		(net "FT4232_TDI_MOSI")
	)
	(segment
		(start 99.822 -90.932)
		(end 100.33 -91.44)
		(width 0.127)
		(layer "In2.Cu")
		(net "FT4232_TDI_MOSI")
	)
	(segment
		(start 65.082166 -91.11488)
		(end 65.209166 -90.98788)
		(width 0.127)
		(layer "In2.Cu")
		(net "FT4232_TDI_MOSI")
	)
	(segment
		(start 66.352166 -91.64066)
		(end 66.352166 -91.11488)
		(width 0.127)
		(layer "In2.Cu")
		(net "FT4232_TDI_MOSI")
	)
	(segment
		(start 100.33 -93.98)
		(end 100.63988 -93.67012)
		(width 0.11938)
		(layer "F.Cu")
		(net "FT4232_TCK_SCLK")
	)
	(segment
		(start 100.63988 -93.67012)
		(end 102.5017 -93.67012)
		(width 0.11938)
		(layer "F.Cu")
		(net "FT4232_TCK_SCLK")
	)
	(via
		(at 23.241 -91.313)
		(size 0.508)
		(drill 0.254)
		(layers "F.Cu" "B.Cu")
		(net "FT4232_TCK_SCLK")
	)
	(via
		(at 100.33 -93.98)
		(size 0.508)
		(drill 0.254)
		(layers "F.Cu" "B.Cu")
		(net "FT4232_TCK_SCLK")
	)
	(segment
		(start 24.13 -91.5924)
		(end 23.36038 -91.5924)
		(width 0.11938)
		(layer "B.Cu")
		(net "FT4232_TCK_SCLK")
	)
	(segment
		(start 23.36038 -91.5924)
		(end 23.241 -91.47302)
		(width 0.11938)
		(layer "B.Cu")
		(net "FT4232_TCK_SCLK")
	)
	(segment
		(start 23.241 -91.47302)
		(end 23.241 -91.313)
		(width 0.11938)
		(layer "B.Cu")
		(net "FT4232_TCK_SCLK")
	)
	(segment
		(start 63.699898 -92.30868)
		(end 63.572898 -92.43568)
		(width 0.127)
		(layer "In2.Cu")
		(net "FT4232_TCK_SCLK")
	)
	(segment
		(start 37.084254 -90.424)
		(end 36.449 -90.424)
		(width 0.127)
		(layer "In2.Cu")
		(net "FT4232_TCK_SCLK")
	)
	(segment
		(start 66.620898 -92.30868)
		(end 66.239898 -92.30868)
		(width 0.127)
		(layer "In2.Cu")
		(net "FT4232_TCK_SCLK")
	)
	(segment
		(start 89.880694 -88.9)
		(end 72.656446 -88.9)
		(width 0.127)
		(layer "In2.Cu")
		(net "FT4232_TCK_SCLK")
	)
	(segment
		(start 96.105218 -91.821)
		(end 95.978218 -91.948)
		(width 0.127)
		(layer "In2.Cu")
		(net "FT4232_TCK_SCLK")
	)
	(segment
		(start 99.829112 -93.045534)
		(end 100.07092 -92.803472)
		(width 0.127)
		(layer "In2.Cu")
		(net "FT4232_TCK_SCLK")
	)
	(segment
		(start 100.07092 -92.624148)
		(end 99.801172 -92.3544)
		(width 0.127)
		(layer "In2.Cu")
		(net "FT4232_TCK_SCLK")
	)
	(segment
		(start 68.017898 -92.43568)
		(end 67.890898 -92.30868)
		(width 0.127)
		(layer "In2.Cu")
		(net "FT4232_TCK_SCLK")
	)
	(segment
		(start 95.343218 -91.948)
		(end 95.216218 -91.821)
		(width 0.127)
		(layer "In2.Cu")
		(net "FT4232_TCK_SCLK")
	)
	(segment
		(start 30.607 -90.805)
		(end 29.464 -91.948)
		(width 0.127)
		(layer "In2.Cu")
		(net "FT4232_TCK_SCLK")
	)
	(segment
		(start 62.175898 -92.837)
		(end 48.514 -92.837)
		(width 0.127)
		(layer "In2.Cu")
		(net "FT4232_TCK_SCLK")
	)
	(segment
		(start 68.017898 -92.71)
		(end 68.017898 -92.43568)
		(width 0.127)
		(layer "In2.Cu")
		(net "FT4232_TCK_SCLK")
	)
	(segment
		(start 67.890898 -92.30868)
		(end 67.509898 -92.30868)
		(width 0.127)
		(layer "In2.Cu")
		(net "FT4232_TCK_SCLK")
	)
	(segment
		(start 63.445898 -92.837)
		(end 63.064898 -92.837)
		(width 0.127)
		(layer "In2.Cu")
		(net "FT4232_TCK_SCLK")
	)
	(segment
		(start 63.572898 -92.43568)
		(end 63.572898 -92.71)
		(width 0.127)
		(layer "In2.Cu")
		(net "FT4232_TCK_SCLK")
	)
	(segment
		(start 94.073218 -91.948)
		(end 93.946218 -91.821)
		(width 0.127)
		(layer "In2.Cu")
		(net "FT4232_TCK_SCLK")
	)
	(segment
		(start 66.747898 -92.43568)
		(end 66.620898 -92.30868)
		(width 0.127)
		(layer "In2.Cu")
		(net "FT4232_TCK_SCLK")
	)
	(segment
		(start 66.239898 -92.30868)
		(end 66.112898 -92.43568)
		(width 0.127)
		(layer "In2.Cu")
		(net "FT4232_TCK_SCLK")
	)
	(segment
		(start 98.283014 -91.821)
		(end 96.105218 -91.821)
		(width 0.127)
		(layer "In2.Cu")
		(net "FT4232_TCK_SCLK")
	)
	(segment
		(start 64.334898 -92.837)
		(end 64.207898 -92.71)
		(width 0.127)
		(layer "In2.Cu")
		(net "FT4232_TCK_SCLK")
	)
	(segment
		(start 65.985898 -92.837)
		(end 65.604898 -92.837)
		(width 0.127)
		(layer "In2.Cu")
		(net "FT4232_TCK_SCLK")
	)
	(segment
		(start 48.514 -92.837)
		(end 47.244 -91.567)
		(width 0.127)
		(layer "In2.Cu")
		(net "FT4232_TCK_SCLK")
	)
	(segment
		(start 63.572898 -92.71)
		(end 63.445898 -92.837)
		(width 0.127)
		(layer "In2.Cu")
		(net "FT4232_TCK_SCLK")
	)
	(segment
		(start 62.937898 -92.71)
		(end 62.937898 -92.43568)
		(width 0.127)
		(layer "In2.Cu")
		(net "FT4232_TCK_SCLK")
	)
	(segment
		(start 35.306 -91.059)
		(end 35.052 -90.805)
		(width 0.127)
		(layer "In2.Cu")
		(net "FT4232_TCK_SCLK")
	)
	(segment
		(start 66.112898 -92.71)
		(end 65.985898 -92.837)
		(width 0.127)
		(layer "In2.Cu")
		(net "FT4232_TCK_SCLK")
	)
	(segment
		(start 64.207898 -92.71)
		(end 64.207898 -92.43568)
		(width 0.127)
		(layer "In2.Cu")
		(net "FT4232_TCK_SCLK")
	)
	(segment
		(start 23.495 -91.059)
		(end 23.241 -91.313)
		(width 0.127)
		(layer "In2.Cu")
		(net "FT4232_TCK_SCLK")
	)
	(segment
		(start 94.708218 -92.98686)
		(end 94.581218 -93.11386)
		(width 0.127)
		(layer "In2.Cu")
		(net "FT4232_TCK_SCLK")
	)
	(segment
		(start 62.937898 -92.43568)
		(end 62.810898 -92.30868)
		(width 0.127)
		(layer "In2.Cu")
		(net "FT4232_TCK_SCLK")
	)
	(segment
		(start 95.978218 -91.948)
		(end 95.978218 -94.14002)
		(width 0.127)
		(layer "In2.Cu")
		(net "FT4232_TCK_SCLK")
	)
	(segment
		(start 66.874898 -92.837)
		(end 66.747898 -92.71)
		(width 0.127)
		(layer "In2.Cu")
		(net "FT4232_TCK_SCLK")
	)
	(segment
		(start 28.321 -91.948)
		(end 27.432 -91.059)
		(width 0.127)
		(layer "In2.Cu")
		(net "FT4232_TCK_SCLK")
	)
	(segment
		(start 67.255898 -92.837)
		(end 66.874898 -92.837)
		(width 0.127)
		(layer "In2.Cu")
		(net "FT4232_TCK_SCLK")
	)
	(segment
		(start 67.382898 -92.71)
		(end 67.255898 -92.837)
		(width 0.127)
		(layer "In2.Cu")
		(net "FT4232_TCK_SCLK")
	)
	(segment
		(start 66.112898 -92.43568)
		(end 66.112898 -92.71)
		(width 0.127)
		(layer "In2.Cu")
		(net "FT4232_TCK_SCLK")
	)
	(segment
		(start 68.719446 -92.837)
		(end 68.144898 -92.837)
		(width 0.127)
		(layer "In2.Cu")
		(net "FT4232_TCK_SCLK")
	)
	(segment
		(start 94.835218 -91.821)
		(end 94.708218 -91.948)
		(width 0.127)
		(layer "In2.Cu")
		(net "FT4232_TCK_SCLK")
	)
	(segment
		(start 35.814 -91.059)
		(end 35.306 -91.059)
		(width 0.127)
		(layer "In2.Cu")
		(net "FT4232_TCK_SCLK")
	)
	(segment
		(start 65.604898 -92.837)
		(end 65.477898 -92.71)
		(width 0.127)
		(layer "In2.Cu")
		(net "FT4232_TCK_SCLK")
	)
	(segment
		(start 68.144898 -92.837)
		(end 68.017898 -92.71)
		(width 0.127)
		(layer "In2.Cu")
		(net "FT4232_TCK_SCLK")
	)
	(segment
		(start 64.715898 -92.837)
		(end 64.334898 -92.837)
		(width 0.127)
		(layer "In2.Cu")
		(net "FT4232_TCK_SCLK")
	)
	(segment
		(start 95.216218 -91.821)
		(end 94.835218 -91.821)
		(width 0.127)
		(layer "In2.Cu")
		(net "FT4232_TCK_SCLK")
	)
	(segment
		(start 66.747898 -92.71)
		(end 66.747898 -92.43568)
		(width 0.127)
		(layer "In2.Cu")
		(net "FT4232_TCK_SCLK")
	)
	(segment
		(start 100.07092 -92.803472)
		(end 100.07092 -92.624148)
		(width 0.127)
		(layer "In2.Cu")
		(net "FT4232_TCK_SCLK")
	)
	(segment
		(start 95.343218 -94.14002)
		(end 95.343218 -91.948)
		(width 0.127)
		(layer "In2.Cu")
		(net "FT4232_TCK_SCLK")
	)
	(segment
		(start 94.073218 -92.98686)
		(end 94.073218 -91.948)
		(width 0.127)
		(layer "In2.Cu")
		(net "FT4232_TCK_SCLK")
	)
	(segment
		(start 47.244 -91.567)
		(end 38.227254 -91.567)
		(width 0.127)
		(layer "In2.Cu")
		(net "FT4232_TCK_SCLK")
	)
	(segment
		(start 100.33 -93.98)
		(end 100.33 -93.725746)
		(width 0.127)
		(layer "In2.Cu")
		(net "FT4232_TCK_SCLK")
	)
	(segment
		(start 99.621848 -92.3544)
		(end 99.38004 -92.596462)
		(width 0.127)
		(layer "In2.Cu")
		(net "FT4232_TCK_SCLK")
	)
	(segment
		(start 93.946218 -91.821)
		(end 92.801694 -91.821)
		(width 0.127)
		(layer "In2.Cu")
		(net "FT4232_TCK_SCLK")
	)
	(segment
		(start 94.200218 -93.11386)
		(end 94.073218 -92.98686)
		(width 0.127)
		(layer "In2.Cu")
		(net "FT4232_TCK_SCLK")
	)
	(segment
		(start 94.708218 -91.948)
		(end 94.708218 -92.98686)
		(width 0.127)
		(layer "In2.Cu")
		(net "FT4232_TCK_SCLK")
	)
	(segment
		(start 64.842898 -92.71)
		(end 64.715898 -92.837)
		(width 0.127)
		(layer "In2.Cu")
		(net "FT4232_TCK_SCLK")
	)
	(segment
		(start 65.477898 -92.71)
		(end 65.477898 -92.43568)
		(width 0.127)
		(layer "In2.Cu")
		(net "FT4232_TCK_SCLK")
	)
	(segment
		(start 65.350898 -92.30868)
		(end 64.969898 -92.30868)
		(width 0.127)
		(layer "In2.Cu")
		(net "FT4232_TCK_SCLK")
	)
	(segment
		(start 64.080898 -92.30868)
		(end 63.699898 -92.30868)
		(width 0.127)
		(layer "In2.Cu")
		(net "FT4232_TCK_SCLK")
	)
	(segment
		(start 65.477898 -92.43568)
		(end 65.350898 -92.30868)
		(width 0.127)
		(layer "In2.Cu")
		(net "FT4232_TCK_SCLK")
	)
	(segment
		(start 94.581218 -93.11386)
		(end 94.200218 -93.11386)
		(width 0.127)
		(layer "In2.Cu")
		(net "FT4232_TCK_SCLK")
	)
	(segment
		(start 95.851218 -94.26702)
		(end 95.470218 -94.26702)
		(width 0.127)
		(layer "In2.Cu")
		(net "FT4232_TCK_SCLK")
	)
	(segment
		(start 99.829112 -93.224858)
		(end 99.829112 -93.045534)
		(width 0.127)
		(layer "In2.Cu")
		(net "FT4232_TCK_SCLK")
	)
	(segment
		(start 99.38004 -92.596462)
		(end 99.058476 -92.596462)
		(width 0.127)
		(layer "In2.Cu")
		(net "FT4232_TCK_SCLK")
	)
	(segment
		(start 92.801694 -91.821)
		(end 89.880694 -88.9)
		(width 0.127)
		(layer "In2.Cu")
		(net "FT4232_TCK_SCLK")
	)
	(segment
		(start 62.302898 -92.43568)
		(end 62.302898 -92.71)
		(width 0.127)
		(layer "In2.Cu")
		(net "FT4232_TCK_SCLK")
	)
	(segment
		(start 62.810898 -92.30868)
		(end 62.429898 -92.30868)
		(width 0.127)
		(layer "In2.Cu")
		(net "FT4232_TCK_SCLK")
	)
	(segment
		(start 72.656446 -88.9)
		(end 68.719446 -92.837)
		(width 0.127)
		(layer "In2.Cu")
		(net "FT4232_TCK_SCLK")
	)
	(segment
		(start 67.382898 -92.43568)
		(end 67.382898 -92.71)
		(width 0.127)
		(layer "In2.Cu")
		(net "FT4232_TCK_SCLK")
	)
	(segment
		(start 62.302898 -92.71)
		(end 62.175898 -92.837)
		(width 0.127)
		(layer "In2.Cu")
		(net "FT4232_TCK_SCLK")
	)
	(segment
		(start 67.509898 -92.30868)
		(end 67.382898 -92.43568)
		(width 0.127)
		(layer "In2.Cu")
		(net "FT4232_TCK_SCLK")
	)
	(segment
		(start 29.464 -91.948)
		(end 28.321 -91.948)
		(width 0.127)
		(layer "In2.Cu")
		(net "FT4232_TCK_SCLK")
	)
	(segment
		(start 95.470218 -94.26702)
		(end 95.343218 -94.14002)
		(width 0.127)
		(layer "In2.Cu")
		(net "FT4232_TCK_SCLK")
	)
	(segment
		(start 100.33 -93.725746)
		(end 99.829112 -93.224858)
		(width 0.127)
		(layer "In2.Cu")
		(net "FT4232_TCK_SCLK")
	)
	(segment
		(start 35.052 -90.805)
		(end 30.607 -90.805)
		(width 0.127)
		(layer "In2.Cu")
		(net "FT4232_TCK_SCLK")
	)
	(segment
		(start 64.842898 -92.43568)
		(end 64.842898 -92.71)
		(width 0.127)
		(layer "In2.Cu")
		(net "FT4232_TCK_SCLK")
	)
	(segment
		(start 99.801172 -92.3544)
		(end 99.621848 -92.3544)
		(width 0.127)
		(layer "In2.Cu")
		(net "FT4232_TCK_SCLK")
	)
	(segment
		(start 62.429898 -92.30868)
		(end 62.302898 -92.43568)
		(width 0.127)
		(layer "In2.Cu")
		(net "FT4232_TCK_SCLK")
	)
	(segment
		(start 38.227254 -91.567)
		(end 37.084254 -90.424)
		(width 0.127)
		(layer "In2.Cu")
		(net "FT4232_TCK_SCLK")
	)
	(segment
		(start 36.449 -90.424)
		(end 35.814 -91.059)
		(width 0.127)
		(layer "In2.Cu")
		(net "FT4232_TCK_SCLK")
	)
	(segment
		(start 63.064898 -92.837)
		(end 62.937898 -92.71)
		(width 0.127)
		(layer "In2.Cu")
		(net "FT4232_TCK_SCLK")
	)
	(segment
		(start 99.058476 -92.596462)
		(end 98.283014 -91.821)
		(width 0.127)
		(layer "In2.Cu")
		(net "FT4232_TCK_SCLK")
	)
	(segment
		(start 95.978218 -94.14002)
		(end 95.851218 -94.26702)
		(width 0.127)
		(layer "In2.Cu")
		(net "FT4232_TCK_SCLK")
	)
	(segment
		(start 64.207898 -92.43568)
		(end 64.080898 -92.30868)
		(width 0.127)
		(layer "In2.Cu")
		(net "FT4232_TCK_SCLK")
	)
	(segment
		(start 64.969898 -92.30868)
		(end 64.842898 -92.43568)
		(width 0.127)
		(layer "In2.Cu")
		(net "FT4232_TCK_SCLK")
	)
	(segment
		(start 27.432 -91.059)
		(end 23.495 -91.059)
		(width 0.127)
		(layer "In2.Cu")
		(net "FT4232_TCK_SCLK")
	)
	(segment
		(start 105.9053 -79.187294)
		(end 103.952294 -79.187294)
		(width 0.11938)
		(layer "F.Cu")
		(net "FT4232_SPI_MOSI")
	)
	(segment
		(start 104.040686 -92.369894)
		(end 102.5017 -92.369894)
		(width 0.11938)
		(layer "F.Cu")
		(net "FT4232_SPI_MOSI")
	)
	(segment
		(start 104.74198 -91.6686)
		(end 104.040686 -92.369894)
		(width 0.11938)
		(layer "F.Cu")
		(net "FT4232_SPI_MOSI")
	)
	(segment
		(start 103.952294 -79.187294)
		(end 103.759 -78.994)
		(width 0.11938)
		(layer "F.Cu")
		(net "FT4232_SPI_MOSI")
	)
	(segment
		(start 104.60736 -89.81948)
		(end 104.74198 -89.9541)
		(width 0.11938)
		(layer "F.Cu")
		(net "FT4232_SPI_MOSI")
	)
	(segment
		(start 104.74198 -89.9541)
		(end 104.74198 -91.6686)
		(width 0.11938)
		(layer "F.Cu")
		(net "FT4232_SPI_MOSI")
	)
	(via
		(at 103.759 -78.994)
		(size 0.508)
		(drill 0.254)
		(layers "F.Cu" "B.Cu")
		(net "FT4232_SPI_MOSI")
	)
	(via
		(at 104.60736 -89.81948)
		(size 0.508)
		(drill 0.254)
		(layers "F.Cu" "B.Cu")
		(net "FT4232_SPI_MOSI")
	)
	(segment
		(start 105.740962 -88.506046)
		(end 105.243884 -88.008968)
		(width 0.127)
		(layer "In2.Cu")
		(net "FT4232_SPI_MOSI")
	)
	(segment
		(start 106.78668 -84.29244)
		(end 104.3686 -81.87436)
		(width 0.127)
		(layer "In2.Cu")
		(net "FT4232_SPI_MOSI")
	)
	(segment
		(start 105.692956 -87.559896)
		(end 106.190034 -88.056974)
		(width 0.127)
		(layer "In2.Cu")
		(net "FT4232_SPI_MOSI")
	)
	(segment
		(start 105.243884 -87.829136)
		(end 105.513124 -87.559896)
		(width 0.127)
		(layer "In2.Cu")
		(net "FT4232_SPI_MOSI")
	)
	(segment
		(start 106.369866 -88.056974)
		(end 106.78668 -87.64016)
		(width 0.127)
		(layer "In2.Cu")
		(net "FT4232_SPI_MOSI")
	)
	(segment
		(start 104.60736 -89.81948)
		(end 105.740962 -88.685878)
		(width 0.127)
		(layer "In2.Cu")
		(net "FT4232_SPI_MOSI")
	)
	(segment
		(start 104.3686 -81.87436)
		(end 104.3686 -79.6036)
		(width 0.127)
		(layer "In2.Cu")
		(net "FT4232_SPI_MOSI")
	)
	(segment
		(start 105.513124 -87.559896)
		(end 105.692956 -87.559896)
		(width 0.127)
		(layer "In2.Cu")
		(net "FT4232_SPI_MOSI")
	)
	(segment
		(start 106.78668 -87.64016)
		(end 106.78668 -84.29244)
		(width 0.127)
		(layer "In2.Cu")
		(net "FT4232_SPI_MOSI")
	)
	(segment
		(start 106.190034 -88.056974)
		(end 106.369866 -88.056974)
		(width 0.127)
		(layer "In2.Cu")
		(net "FT4232_SPI_MOSI")
	)
	(segment
		(start 105.740962 -88.685878)
		(end 105.740962 -88.506046)
		(width 0.127)
		(layer "In2.Cu")
		(net "FT4232_SPI_MOSI")
	)
	(segment
		(start 105.243884 -88.008968)
		(end 105.243884 -87.829136)
		(width 0.127)
		(layer "In2.Cu")
		(net "FT4232_SPI_MOSI")
	)
	(segment
		(start 104.3686 -79.6036)
		(end 103.759 -78.994)
		(width 0.127)
		(layer "In2.Cu")
		(net "FT4232_SPI_MOSI")
	)
	(segment
		(start 114.173 -77.851)
		(end 113.486692 -78.537308)
		(width 0.11938)
		(layer "F.Cu")
		(net "FT4232_SPI_MISO")
	)
	(segment
		(start 109.917484 -91.719908)
		(end 110.079028 -91.558364)
		(width 0.11938)
		(layer "F.Cu")
		(net "FT4232_SPI_MISO")
	)
	(segment
		(start 113.486692 -78.537308)
		(end 111.9759 -78.537308)
		(width 0.11938)
		(layer "F.Cu")
		(net "FT4232_SPI_MISO")
	)
	(segment
		(start 108.5723 -91.719908)
		(end 109.917484 -91.719908)
		(width 0.11938)
		(layer "F.Cu")
		(net "FT4232_SPI_MISO")
	)
	(segment
		(start 114.554 -77.851)
		(end 114.173 -77.851)
		(width 0.11938)
		(layer "F.Cu")
		(net "FT4232_SPI_MISO")
	)
	(via
		(at 114.554 -77.851)
		(size 0.508)
		(drill 0.254)
		(layers "F.Cu" "B.Cu")
		(net "FT4232_SPI_MISO")
	)
	(via
		(at 110.079028 -91.558364)
		(size 0.508)
		(drill 0.254)
		(layers "F.Cu" "B.Cu")
		(net "FT4232_SPI_MISO")
	)
	(segment
		(start 113.538 -77.851)
		(end 114.554 -77.851)
		(width 0.11938)
		(layer "B.Cu")
		(net "FT4232_SPI_MISO")
	)
	(segment
		(start 110.617 -89.408)
		(end 110.2995 -89.0905)
		(width 0.11938)
		(layer "B.Cu")
		(net "FT4232_SPI_MISO")
	)
	(segment
		(start 110.617 -91.020392)
		(end 110.617 -89.408)
		(width 0.11938)
		(layer "B.Cu")
		(net "FT4232_SPI_MISO")
	)
	(segment
		(start 112.903 -78.486)
		(end 113.538 -77.851)
		(width 0.11938)
		(layer "B.Cu")
		(net "FT4232_SPI_MISO")
	)
	(segment
		(start 110.079028 -91.558364)
		(end 110.617 -91.020392)
		(width 0.11938)
		(layer "B.Cu")
		(net "FT4232_SPI_MISO")
	)
	(segment
		(start 110.2995 -89.0905)
		(end 110.2995 -87.61984)
		(width 0.11938)
		(layer "B.Cu")
		(net "FT4232_SPI_MISO")
	)
	(segment
		(start 109.474 -83.058)
		(end 112.903 -79.629)
		(width 0.11938)
		(layer "B.Cu")
		(net "FT4232_SPI_MISO")
	)
	(segment
		(start 110.2995 -87.61984)
		(end 109.474 -86.79434)
		(width 0.11938)
		(layer "B.Cu")
		(net "FT4232_SPI_MISO")
	)
	(segment
		(start 112.903 -79.629)
		(end 112.903 -78.486)
		(width 0.11938)
		(layer "B.Cu")
		(net "FT4232_SPI_MISO")
	)
	(segment
		(start 109.474 -86.79434)
		(end 109.474 -83.058)
		(width 0.11938)
		(layer "B.Cu")
		(net "FT4232_SPI_MISO")
	)
	(segment
		(start 110.109 -93.472)
		(end 109.91088 -93.67012)
		(width 0.11938)
		(layer "F.Cu")
		(net "FT4232_SPI_CS_N")
	)
	(segment
		(start 111.9759 -80.48752)
		(end 110.77448 -80.48752)
		(width 0.11938)
		(layer "F.Cu")
		(net "FT4232_SPI_CS_N")
	)
	(segment
		(start 110.236 -81.026)
		(end 110.236 -83.312)
		(width 0.11938)
		(layer "F.Cu")
		(net "FT4232_SPI_CS_N")
	)
	(segment
		(start 109.91088 -93.67012)
		(end 108.5723 -93.67012)
		(width 0.11938)
		(layer "F.Cu")
		(net "FT4232_SPI_CS_N")
	)
	(segment
		(start 110.77448 -80.48752)
		(end 110.236 -81.026)
		(width 0.11938)
		(layer "F.Cu")
		(net "FT4232_SPI_CS_N")
	)
	(segment
		(start 110.109 -93.091)
		(end 110.109 -93.472)
		(width 0.11938)
		(layer "F.Cu")
		(net "FT4232_SPI_CS_N")
	)
	(via
		(at 110.109 -93.091)
		(size 0.508)
		(drill 0.254)
		(layers "F.Cu" "B.Cu")
		(net "FT4232_SPI_CS_N")
	)
	(via
		(at 110.236 -83.312)
		(size 0.508)
		(drill 0.254)
		(layers "F.Cu" "B.Cu")
		(net "FT4232_SPI_CS_N")
	)
	(segment
		(start 110.62462 -86.026244)
		(end 110.49254 -86.026244)
		(width 0.11938)
		(layer "B.Cu")
		(net "FT4232_SPI_CS_N")
	)
	(segment
		(start 111.05642 -87.56142)
		(end 111.05642 -88.100408)
		(width 0.11938)
		(layer "B.Cu")
		(net "FT4232_SPI_CS_N")
	)
	(segment
		(start 111.05642 -88.966548)
		(end 111.05642 -89.355168)
		(width 0.11938)
		(layer "B.Cu")
		(net "FT4232_SPI_CS_N")
	)
	(segment
		(start 111.1758 -90.729308)
		(end 111.62792 -90.729308)
		(width 0.11938)
		(layer "B.Cu")
		(net "FT4232_SPI_CS_N")
	)
	(segment
		(start 111.05642 -91.476068)
		(end 111.05642 -91.743276)
		(width 0.11938)
		(layer "B.Cu")
		(net "FT4232_SPI_CS_N")
	)
	(segment
		(start 111.62792 -91.356688)
		(end 111.1758 -91.356688)
		(width 0.11938)
		(layer "B.Cu")
		(net "FT4232_SPI_CS_N")
	)
	(segment
		(start 110.49254 -84.771484)
		(end 110.37316 -84.890864)
		(width 0.11938)
		(layer "B.Cu")
		(net "FT4232_SPI_CS_N")
	)
	(segment
		(start 110.37316 -85.279484)
		(end 110.49254 -85.398864)
		(width 0.11938)
		(layer "B.Cu")
		(net "FT4232_SPI_CS_N")
	)
	(segment
		(start 111.7473 -88.727788)
		(end 111.62792 -88.847168)
		(width 0.11938)
		(layer "B.Cu")
		(net "FT4232_SPI_CS_N")
	)
	(segment
		(start 111.62792 -90.101928)
		(end 111.1758 -90.101928)
		(width 0.11938)
		(layer "B.Cu")
		(net "FT4232_SPI_CS_N")
	)
	(segment
		(start 111.62792 -88.219788)
		(end 111.7473 -88.339168)
		(width 0.11938)
		(layer "B.Cu")
		(net "FT4232_SPI_CS_N")
	)
	(segment
		(start 110.62462 -85.398864)
		(end 110.744 -85.518244)
		(width 0.11938)
		(layer "B.Cu")
		(net "FT4232_SPI_CS_N")
	)
	(segment
		(start 110.62462 -84.771484)
		(end 110.49254 -84.771484)
		(width 0.11938)
		(layer "B.Cu")
		(net "FT4232_SPI_CS_N")
	)
	(segment
		(start 111.62792 -88.847168)
		(end 111.1758 -88.847168)
		(width 0.11938)
		(layer "B.Cu")
		(net "FT4232_SPI_CS_N")
	)
	(segment
		(start 111.05642 -88.100408)
		(end 111.1758 -88.219788)
		(width 0.11938)
		(layer "B.Cu")
		(net "FT4232_SPI_CS_N")
	)
	(segment
		(start 111.05642 -90.221308)
		(end 111.05642 -90.609928)
		(width 0.11938)
		(layer "B.Cu")
		(net "FT4232_SPI_CS_N")
	)
	(segment
		(start 110.62462 -86.653624)
		(end 110.744 -86.773004)
		(width 0.11938)
		(layer "B.Cu")
		(net "FT4232_SPI_CS_N")
	)
	(segment
		(start 111.05642 -91.743276)
		(end 110.109 -92.690696)
		(width 0.11938)
		(layer "B.Cu")
		(net "FT4232_SPI_CS_N")
	)
	(segment
		(start 111.7473 -91.237308)
		(end 111.62792 -91.356688)
		(width 0.11938)
		(layer "B.Cu")
		(net "FT4232_SPI_CS_N")
	)
	(segment
		(start 111.7473 -89.982548)
		(end 111.62792 -90.101928)
		(width 0.11938)
		(layer "B.Cu")
		(net "FT4232_SPI_CS_N")
	)
	(segment
		(start 111.7473 -89.593928)
		(end 111.7473 -89.982548)
		(width 0.11938)
		(layer "B.Cu")
		(net "FT4232_SPI_CS_N")
	)
	(segment
		(start 110.744 -83.82)
		(end 110.744 -84.652104)
		(width 0.11938)
		(layer "B.Cu")
		(net "FT4232_SPI_CS_N")
	)
	(segment
		(start 110.37316 -86.534244)
		(end 110.49254 -86.653624)
		(width 0.11938)
		(layer "B.Cu")
		(net "FT4232_SPI_CS_N")
	)
	(segment
		(start 111.7473 -90.848688)
		(end 111.7473 -91.237308)
		(width 0.11938)
		(layer "B.Cu")
		(net "FT4232_SPI_CS_N")
	)
	(segment
		(start 110.744 -86.773004)
		(end 110.744 -87.249)
		(width 0.11938)
		(layer "B.Cu")
		(net "FT4232_SPI_CS_N")
	)
	(segment
		(start 111.1758 -91.356688)
		(end 111.05642 -91.476068)
		(width 0.11938)
		(layer "B.Cu")
		(net "FT4232_SPI_CS_N")
	)
	(segment
		(start 111.62792 -90.729308)
		(end 111.7473 -90.848688)
		(width 0.11938)
		(layer "B.Cu")
		(net "FT4232_SPI_CS_N")
	)
	(segment
		(start 110.37316 -84.890864)
		(end 110.37316 -85.279484)
		(width 0.11938)
		(layer "B.Cu")
		(net "FT4232_SPI_CS_N")
	)
	(segment
		(start 110.744 -85.518244)
		(end 110.744 -85.906864)
		(width 0.11938)
		(layer "B.Cu")
		(net "FT4232_SPI_CS_N")
	)
	(segment
		(start 111.1758 -89.474548)
		(end 111.62792 -89.474548)
		(width 0.11938)
		(layer "B.Cu")
		(net "FT4232_SPI_CS_N")
	)
	(segment
		(start 110.49254 -85.398864)
		(end 110.62462 -85.398864)
		(width 0.11938)
		(layer "B.Cu")
		(net "FT4232_SPI_CS_N")
	)
	(segment
		(start 110.37316 -86.145624)
		(end 110.37316 -86.534244)
		(width 0.11938)
		(layer "B.Cu")
		(net "FT4232_SPI_CS_N")
	)
	(segment
		(start 111.05642 -89.355168)
		(end 111.1758 -89.474548)
		(width 0.11938)
		(layer "B.Cu")
		(net "FT4232_SPI_CS_N")
	)
	(segment
		(start 111.62792 -89.474548)
		(end 111.7473 -89.593928)
		(width 0.11938)
		(layer "B.Cu")
		(net "FT4232_SPI_CS_N")
	)
	(segment
		(start 110.744 -87.249)
		(end 111.05642 -87.56142)
		(width 0.11938)
		(layer "B.Cu")
		(net "FT4232_SPI_CS_N")
	)
	(segment
		(start 111.1758 -88.847168)
		(end 111.05642 -88.966548)
		(width 0.11938)
		(layer "B.Cu")
		(net "FT4232_SPI_CS_N")
	)
	(segment
		(start 110.744 -84.652104)
		(end 110.62462 -84.771484)
		(width 0.11938)
		(layer "B.Cu")
		(net "FT4232_SPI_CS_N")
	)
	(segment
		(start 110.49254 -86.653624)
		(end 110.62462 -86.653624)
		(width 0.11938)
		(layer "B.Cu")
		(net "FT4232_SPI_CS_N")
	)
	(segment
		(start 111.7473 -88.339168)
		(end 111.7473 -88.727788)
		(width 0.11938)
		(layer "B.Cu")
		(net "FT4232_SPI_CS_N")
	)
	(segment
		(start 110.49254 -86.026244)
		(end 110.37316 -86.145624)
		(width 0.11938)
		(layer "B.Cu")
		(net "FT4232_SPI_CS_N")
	)
	(segment
		(start 111.1758 -90.101928)
		(end 111.05642 -90.221308)
		(width 0.11938)
		(layer "B.Cu")
		(net "FT4232_SPI_CS_N")
	)
	(segment
		(start 110.109 -92.690696)
		(end 110.109 -93.091)
		(width 0.11938)
		(layer "B.Cu")
		(net "FT4232_SPI_CS_N")
	)
	(segment
		(start 111.05642 -90.609928)
		(end 111.1758 -90.729308)
		(width 0.11938)
		(layer "B.Cu")
		(net "FT4232_SPI_CS_N")
	)
	(segment
		(start 110.236 -83.312)
		(end 110.744 -83.82)
		(width 0.11938)
		(layer "B.Cu")
		(net "FT4232_SPI_CS_N")
	)
	(segment
		(start 111.1758 -88.219788)
		(end 111.62792 -88.219788)
		(width 0.11938)
		(layer "B.Cu")
		(net "FT4232_SPI_CS_N")
	)
	(segment
		(start 110.744 -85.906864)
		(end 110.62462 -86.026244)
		(width 0.11938)
		(layer "B.Cu")
		(net "FT4232_SPI_CS_N")
	)
	(segment
		(start 107.95 -85.022436)
		(end 108.06938 -84.903056)
		(width 0.11938)
		(layer "F.Cu")
		(net "FT4232_SPI_CLK")
	)
	(segment
		(start 106.299 -90.043)
		(end 107.95 -88.392)
		(width 0.11938)
		(layer "F.Cu")
		(net "FT4232_SPI_CLK")
	)
	(segment
		(start 108.93806 -84.783676)
		(end 108.93806 -84.395056)
		(width 0.11938)
		(layer "F.Cu")
		(net "FT4232_SPI_CLK")
	)
	(segment
		(start 103.886 -93.77426)
		(end 106.299 -91.36126)
		(width 0.11938)
		(layer "F.Cu")
		(net "FT4232_SPI_CLK")
	)
	(segment
		(start 107.95 -81.940654)
		(end 107.162346 -81.153)
		(width 0.11938)
		(layer "F.Cu")
		(net "FT4232_SPI_CLK")
	)
	(segment
		(start 108.81868 -84.903056)
		(end 108.93806 -84.783676)
		(width 0.11938)
		(layer "F.Cu")
		(net "FT4232_SPI_CLK")
	)
	(segment
		(start 108.06938 -84.275676)
		(end 107.95 -84.156296)
		(width 0.11938)
		(layer "F.Cu")
		(net "FT4232_SPI_CLK")
	)
	(segment
		(start 108.81868 -86.157816)
		(end 108.93806 -86.038436)
		(width 0.11938)
		(layer "F.Cu")
		(net "FT4232_SPI_CLK")
	)
	(segment
		(start 108.81868 -85.530436)
		(end 108.06938 -85.530436)
		(width 0.11938)
		(layer "F.Cu")
		(net "FT4232_SPI_CLK")
	)
	(segment
		(start 107.95 -84.156296)
		(end 107.95 -81.940654)
		(width 0.11938)
		(layer "F.Cu")
		(net "FT4232_SPI_CLK")
	)
	(segment
		(start 103.886 -94.320106)
		(end 103.886 -93.77426)
		(width 0.11938)
		(layer "F.Cu")
		(net "FT4232_SPI_CLK")
	)
	(segment
		(start 105.920794 -81.153)
		(end 105.9053 -81.137506)
		(width 0.11938)
		(layer "F.Cu")
		(net "FT4232_SPI_CLK")
	)
	(segment
		(start 107.162346 -81.153)
		(end 105.920794 -81.153)
		(width 0.11938)
		(layer "F.Cu")
		(net "FT4232_SPI_CLK")
	)
	(segment
		(start 107.95 -86.277196)
		(end 108.06938 -86.157816)
		(width 0.11938)
		(layer "F.Cu")
		(net "FT4232_SPI_CLK")
	)
	(segment
		(start 108.93806 -84.395056)
		(end 108.81868 -84.275676)
		(width 0.11938)
		(layer "F.Cu")
		(net "FT4232_SPI_CLK")
	)
	(segment
		(start 108.06938 -86.157816)
		(end 108.81868 -86.157816)
		(width 0.11938)
		(layer "F.Cu")
		(net "FT4232_SPI_CLK")
	)
	(segment
		(start 107.95 -88.392)
		(end 107.95 -86.277196)
		(width 0.11938)
		(layer "F.Cu")
		(net "FT4232_SPI_CLK")
	)
	(segment
		(start 106.299 -91.36126)
		(end 106.299 -90.043)
		(width 0.11938)
		(layer "F.Cu")
		(net "FT4232_SPI_CLK")
	)
	(segment
		(start 108.06938 -85.530436)
		(end 107.95 -85.411056)
		(width 0.11938)
		(layer "F.Cu")
		(net "FT4232_SPI_CLK")
	)
	(segment
		(start 108.81868 -84.275676)
		(end 108.06938 -84.275676)
		(width 0.11938)
		(layer "F.Cu")
		(net "FT4232_SPI_CLK")
	)
	(segment
		(start 103.886 -94.320106)
		(end 102.5017 -94.320106)
		(width 0.11938)
		(layer "F.Cu")
		(net "FT4232_SPI_CLK")
	)
	(segment
		(start 108.93806 -86.038436)
		(end 108.93806 -85.649816)
		(width 0.11938)
		(layer "F.Cu")
		(net "FT4232_SPI_CLK")
	)
	(segment
		(start 108.93806 -85.649816)
		(end 108.81868 -85.530436)
		(width 0.11938)
		(layer "F.Cu")
		(net "FT4232_SPI_CLK")
	)
	(segment
		(start 107.95 -85.411056)
		(end 107.95 -85.022436)
		(width 0.11938)
		(layer "F.Cu")
		(net "FT4232_SPI_CLK")
	)
	(segment
		(start 108.06938 -84.903056)
		(end 108.81868 -84.903056)
		(width 0.11938)
		(layer "F.Cu")
		(net "FT4232_SPI_CLK")
	)
	(via
		(at 103.886 -94.320106)
		(size 0.508)
		(drill 0.254)
		(layers "F.Cu" "B.Cu")
		(net "FT4232_SPI_CLK")
	)
	(segment
		(start 118.237 -22.733)
		(end 117.221 -22.733)
		(width 0.11938)
		(layer "F.Cu")
		(net "FT4232_MUX3_SEL")
	)
	(segment
		(start 87.249 -19.431)
		(end 85.852 -20.828)
		(width 0.11938)
		(layer "F.Cu")
		(net "FT4232_MUX3_SEL")
	)
	(segment
		(start 16.69669 -82.73669)
		(end 17.08531 -83.12531)
		(width 0.11938)
		(layer "F.Cu")
		(net "FT4232_MUX3_SEL")
	)
	(segment
		(start 116.459 -21.971)
		(end 116.459 -21.463)
		(width 0.11938)
		(layer "F.Cu")
		(net "FT4232_MUX3_SEL")
	)
	(segment
		(start 91.059 -19.431)
		(end 87.249 -19.431)
		(width 0.11938)
		(layer "F.Cu")
		(net "FT4232_MUX3_SEL")
	)
	(segment
		(start 18.85569 -83.606386)
		(end 18.85569 -84.517992)
		(width 0.11938)
		(layer "F.Cu")
		(net "FT4232_MUX3_SEL")
	)
	(segment
		(start 118.745 -23.241)
		(end 118.237 -22.733)
		(width 0.11938)
		(layer "F.Cu")
		(net "FT4232_MUX3_SEL")
	)
	(segment
		(start 15.748 -82.169)
		(end 15.875254 -82.169)
		(width 0.11938)
		(layer "F.Cu")
		(net "FT4232_MUX3_SEL")
	)
	(segment
		(start 16.442944 -82.73669)
		(end 16.69669 -82.73669)
		(width 0.11938)
		(layer "F.Cu")
		(net "FT4232_MUX3_SEL")
	)
	(segment
		(start 18.85569 -84.517992)
		(end 19.681698 -85.344)
		(width 0.11938)
		(layer "F.Cu")
		(net "FT4232_MUX3_SEL")
	)
	(segment
		(start 116.586 -17.272)
		(end 93.218 -17.272)
		(width 0.11938)
		(layer "F.Cu")
		(net "FT4232_MUX3_SEL")
	)
	(segment
		(start 119.2276 -23.241)
		(end 118.745 -23.241)
		(width 0.11938)
		(layer "F.Cu")
		(net "FT4232_MUX3_SEL")
	)
	(segment
		(start 20.995894 -85.344)
		(end 21.466556 -85.814662)
		(width 0.11938)
		(layer "F.Cu")
		(net "FT4232_MUX3_SEL")
	)
	(segment
		(start 116.459 -21.463)
		(end 117.475 -20.447)
		(width 0.11938)
		(layer "F.Cu")
		(net "FT4232_MUX3_SEL")
	)
	(segment
		(start 15.875254 -82.169)
		(end 16.442944 -82.73669)
		(width 0.11938)
		(layer "F.Cu")
		(net "FT4232_MUX3_SEL")
	)
	(segment
		(start 18.374614 -83.12531)
		(end 18.85569 -83.606386)
		(width 0.11938)
		(layer "F.Cu")
		(net "FT4232_MUX3_SEL")
	)
	(segment
		(start 117.475 -20.447)
		(end 117.475 -18.161)
		(width 0.11938)
		(layer "F.Cu")
		(net "FT4232_MUX3_SEL")
	)
	(segment
		(start 117.221 -22.733)
		(end 116.459 -21.971)
		(width 0.11938)
		(layer "F.Cu")
		(net "FT4232_MUX3_SEL")
	)
	(segment
		(start 93.218 -17.272)
		(end 91.059 -19.431)
		(width 0.11938)
		(layer "F.Cu")
		(net "FT4232_MUX3_SEL")
	)
	(segment
		(start 17.08531 -83.12531)
		(end 18.374614 -83.12531)
		(width 0.11938)
		(layer "F.Cu")
		(net "FT4232_MUX3_SEL")
	)
	(segment
		(start 85.852 -20.828)
		(end 85.852 -26.035)
		(width 0.11938)
		(layer "F.Cu")
		(net "FT4232_MUX3_SEL")
	)
	(segment
		(start 117.475 -18.161)
		(end 116.586 -17.272)
		(width 0.11938)
		(layer "F.Cu")
		(net "FT4232_MUX3_SEL")
	)
	(segment
		(start 19.681698 -85.344)
		(end 20.995894 -85.344)
		(width 0.11938)
		(layer "F.Cu")
		(net "FT4232_MUX3_SEL")
	)
	(segment
		(start 21.466556 -85.814662)
		(end 22.7076 -85.814662)
		(width 0.11938)
		(layer "F.Cu")
		(net "FT4232_MUX3_SEL")
	)
	(via
		(at 15.748 -82.169)
		(size 0.508)
		(drill 0.254)
		(layers "F.Cu" "B.Cu")
		(net "FT4232_MUX3_SEL")
	)
	(via
		(at 85.852 -26.035)
		(size 0.508)
		(drill 0.254)
		(layers "F.Cu" "B.Cu")
		(net "FT4232_MUX3_SEL")
	)
	(via
		(at 116.459 -21.971)
		(size 0.508)
		(drill 0.254)
		(layers "F.Cu" "B.Cu")
		(net "FT4232_MUX3_SEL")
	)
	(segment
		(start 32.0802 -74.3712)
		(end 34.765234 -74.3712)
		(width 0.127)
		(layer "In2.Cu")
		(net "FT4232_MUX3_SEL")
	)
	(segment
		(start 31.695644 -73.986644)
		(end 32.0802 -74.3712)
		(width 0.127)
		(layer "In2.Cu")
		(net "FT4232_MUX3_SEL")
	)
	(segment
		(start 13.081 -73.309988)
		(end 15.270988 -71.12)
		(width 0.127)
		(layer "In2.Cu")
		(net "FT4232_MUX3_SEL")
	)
	(segment
		(start 34.765234 -74.3712)
		(end 37.337746 -71.798688)
		(width 0.127)
		(layer "In2.Cu")
		(net "FT4232_MUX3_SEL")
	)
	(segment
		(start 14.986 -81.407)
		(end 14.986 -80.772)
		(width 0.127)
		(layer "In2.Cu")
		(net "FT4232_MUX3_SEL")
	)
	(segment
		(start 31.695644 -72.952356)
		(end 31.695644 -73.986644)
		(width 0.127)
		(layer "In2.Cu")
		(net "FT4232_MUX3_SEL")
	)
	(segment
		(start 75.493118 -52.252118)
		(end 72.8472 -49.6062)
		(width 0.127)
		(layer "In2.Cu")
		(net "FT4232_MUX3_SEL")
	)
	(segment
		(start 13.081 -78.867)
		(end 13.081 -73.309988)
		(width 0.127)
		(layer "In2.Cu")
		(net "FT4232_MUX3_SEL")
	)
	(segment
		(start 24.595582 -70.2691)
		(end 25.446482 -71.12)
		(width 0.127)
		(layer "In2.Cu")
		(net "FT4232_MUX3_SEL")
	)
	(segment
		(start 24.121618 -70.2691)
		(end 24.595582 -70.2691)
		(width 0.127)
		(layer "In2.Cu")
		(net "FT4232_MUX3_SEL")
	)
	(segment
		(start 37.337746 -71.798688)
		(end 72.727312 -71.798688)
		(width 0.127)
		(layer "In2.Cu")
		(net "FT4232_MUX3_SEL")
	)
	(segment
		(start 72.8472 -49.6062)
		(end 72.8472 -45.3898)
		(width 0.127)
		(layer "In2.Cu")
		(net "FT4232_MUX3_SEL")
	)
	(segment
		(start 75.438 -42.799)
		(end 75.438 -40.345868)
		(width 0.127)
		(layer "In2.Cu")
		(net "FT4232_MUX3_SEL")
	)
	(segment
		(start 14.986 -80.772)
		(end 13.081 -78.867)
		(width 0.127)
		(layer "In2.Cu")
		(net "FT4232_MUX3_SEL")
	)
	(segment
		(start 83.947 -27.94)
		(end 85.852 -26.035)
		(width 0.127)
		(layer "In2.Cu")
		(net "FT4232_MUX3_SEL")
	)
	(segment
		(start 83.947 -31.836868)
		(end 83.947 -27.94)
		(width 0.127)
		(layer "In2.Cu")
		(net "FT4232_MUX3_SEL")
	)
	(segment
		(start 72.8472 -45.3898)
		(end 75.438 -42.799)
		(width 0.127)
		(layer "In2.Cu")
		(net "FT4232_MUX3_SEL")
	)
	(segment
		(start 72.727312 -71.798688)
		(end 75.493118 -69.032882)
		(width 0.127)
		(layer "In2.Cu")
		(net "FT4232_MUX3_SEL")
	)
	(segment
		(start 29.863288 -71.12)
		(end 31.695644 -72.952356)
		(width 0.127)
		(layer "In2.Cu")
		(net "FT4232_MUX3_SEL")
	)
	(segment
		(start 15.270988 -71.12)
		(end 23.270718 -71.12)
		(width 0.127)
		(layer "In2.Cu")
		(net "FT4232_MUX3_SEL")
	)
	(segment
		(start 75.438 -40.345868)
		(end 83.947 -31.836868)
		(width 0.127)
		(layer "In2.Cu")
		(net "FT4232_MUX3_SEL")
	)
	(segment
		(start 75.493118 -69.032882)
		(end 75.493118 -52.252118)
		(width 0.127)
		(layer "In2.Cu")
		(net "FT4232_MUX3_SEL")
	)
	(segment
		(start 23.270718 -71.12)
		(end 24.121618 -70.2691)
		(width 0.127)
		(layer "In2.Cu")
		(net "FT4232_MUX3_SEL")
	)
	(segment
		(start 25.446482 -71.12)
		(end 29.863288 -71.12)
		(width 0.127)
		(layer "In2.Cu")
		(net "FT4232_MUX3_SEL")
	)
	(segment
		(start 15.748 -82.169)
		(end 14.986 -81.407)
		(width 0.127)
		(layer "In2.Cu")
		(net "FT4232_MUX3_SEL")
	)
	(segment
		(start 21.163534 -86.314534)
		(end 20.955 -86.106)
		(width 0.11938)
		(layer "F.Cu")
		(net "FT4232_MUX2_SEL")
	)
	(segment
		(start 100.9142 -82.2706)
		(end 99.695 -82.2706)
		(width 0.11938)
		(layer "F.Cu")
		(net "FT4232_MUX2_SEL")
	)
	(segment
		(start 22.7076 -86.314534)
		(end 21.163534 -86.314534)
		(width 0.11938)
		(layer "F.Cu")
		(net "FT4232_MUX2_SEL")
	)
	(via
		(at 20.955 -86.106)
		(size 0.508)
		(drill 0.254)
		(layers "F.Cu" "B.Cu")
		(net "FT4232_MUX2_SEL")
	)
	(via
		(at 99.695 -82.2706)
		(size 0.508)
		(drill 0.254)
		(layers "F.Cu" "B.Cu")
		(net "FT4232_MUX2_SEL")
	)
	(segment
		(start 37.973254 -87.376)
		(end 41.148 -87.376)
		(width 0.127)
		(layer "In2.Cu")
		(net "FT4232_MUX2_SEL")
	)
	(segment
		(start 21.0185 -86.1695)
		(end 24.401018 -86.1695)
		(width 0.127)
		(layer "In2.Cu")
		(net "FT4232_MUX2_SEL")
	)
	(segment
		(start 99.695 -82.0166)
		(end 99.695 -82.2706)
		(width 0.127)
		(layer "In2.Cu")
		(net "FT4232_MUX2_SEL")
	)
	(segment
		(start 24.401018 -86.1695)
		(end 25.353518 -85.217)
		(width 0.127)
		(layer "In2.Cu")
		(net "FT4232_MUX2_SEL")
	)
	(segment
		(start 48.086264 -89.535)
		(end 49.356264 -90.805)
		(width 0.127)
		(layer "In2.Cu")
		(net "FT4232_MUX2_SEL")
	)
	(segment
		(start 49.356264 -90.805)
		(end 58.60288 -90.805)
		(width 0.127)
		(layer "In2.Cu")
		(net "FT4232_MUX2_SEL")
	)
	(segment
		(start 89.048082 -80.645)
		(end 98.3234 -80.645)
		(width 0.127)
		(layer "In2.Cu")
		(net "FT4232_MUX2_SEL")
	)
	(segment
		(start 85.703664 -81.9531)
		(end 86.366096 -81.290668)
		(width 0.127)
		(layer "In2.Cu")
		(net "FT4232_MUX2_SEL")
	)
	(segment
		(start 86.366096 -81.290668)
		(end 88.402414 -81.290668)
		(width 0.127)
		(layer "In2.Cu")
		(net "FT4232_MUX2_SEL")
	)
	(segment
		(start 79.629254 -86.487)
		(end 84.163154 -81.9531)
		(width 0.127)
		(layer "In2.Cu")
		(net "FT4232_MUX2_SEL")
	)
	(segment
		(start 88.402414 -81.290668)
		(end 89.048082 -80.645)
		(width 0.127)
		(layer "In2.Cu")
		(net "FT4232_MUX2_SEL")
	)
	(segment
		(start 70.036182 -88.646)
		(end 72.195182 -86.487)
		(width 0.127)
		(layer "In2.Cu")
		(net "FT4232_MUX2_SEL")
	)
	(segment
		(start 34.544 -85.217)
		(end 35.687 -86.36)
		(width 0.127)
		(layer "In2.Cu")
		(net "FT4232_MUX2_SEL")
	)
	(segment
		(start 98.3234 -80.645)
		(end 99.695 -82.0166)
		(width 0.127)
		(layer "In2.Cu")
		(net "FT4232_MUX2_SEL")
	)
	(segment
		(start 41.148 -87.376)
		(end 43.307 -89.535)
		(width 0.127)
		(layer "In2.Cu")
		(net "FT4232_MUX2_SEL")
	)
	(segment
		(start 25.353518 -85.217)
		(end 34.544 -85.217)
		(width 0.127)
		(layer "In2.Cu")
		(net "FT4232_MUX2_SEL")
	)
	(segment
		(start 60.76188 -88.646)
		(end 70.036182 -88.646)
		(width 0.127)
		(layer "In2.Cu")
		(net "FT4232_MUX2_SEL")
	)
	(segment
		(start 36.957254 -86.36)
		(end 37.973254 -87.376)
		(width 0.127)
		(layer "In2.Cu")
		(net "FT4232_MUX2_SEL")
	)
	(segment
		(start 35.687 -86.36)
		(end 36.957254 -86.36)
		(width 0.127)
		(layer "In2.Cu")
		(net "FT4232_MUX2_SEL")
	)
	(segment
		(start 43.307 -89.535)
		(end 48.086264 -89.535)
		(width 0.127)
		(layer "In2.Cu")
		(net "FT4232_MUX2_SEL")
	)
	(segment
		(start 20.955 -86.106)
		(end 21.0185 -86.1695)
		(width 0.127)
		(layer "In2.Cu")
		(net "FT4232_MUX2_SEL")
	)
	(segment
		(start 84.163154 -81.9531)
		(end 85.703664 -81.9531)
		(width 0.127)
		(layer "In2.Cu")
		(net "FT4232_MUX2_SEL")
	)
	(segment
		(start 58.60288 -90.805)
		(end 60.76188 -88.646)
		(width 0.127)
		(layer "In2.Cu")
		(net "FT4232_MUX2_SEL")
	)
	(segment
		(start 72.195182 -86.487)
		(end 79.629254 -86.487)
		(width 0.127)
		(layer "In2.Cu")
		(net "FT4232_MUX2_SEL")
	)
	(segment
		(start 97.5106 -95.4532)
		(end 96.393 -95.4532)
		(width 0.11938)
		(layer "F.Cu")
		(net "FT4232_MUX1_SEL")
	)
	(segment
		(start 22.7076 -86.81466)
		(end 20.193 -86.81466)
		(width 0.11938)
		(layer "F.Cu")
		(net "FT4232_MUX1_SEL")
	)
	(via
		(at 96.393 -95.4532)
		(size 0.508)
		(drill 0.254)
		(layers "F.Cu" "B.Cu")
		(net "FT4232_MUX1_SEL")
	)
	(via
		(at 20.193 -86.81466)
		(size 0.508)
		(drill 0.254)
		(layers "F.Cu" "B.Cu")
		(net "FT4232_MUX1_SEL")
	)
	(segment
		(start 21.844 -86.94166)
		(end 21.717 -86.81466)
		(width 0.127)
		(layer "In2.Cu")
		(net "FT4232_MUX1_SEL")
	)
	(segment
		(start 20.6375 -91.676982)
		(end 20.6375 -90.995754)
		(width 0.127)
		(layer "In2.Cu")
		(net "FT4232_MUX1_SEL")
	)
	(segment
		(start 20.6375 -90.995754)
		(end 21.844 -89.789254)
		(width 0.127)
		(layer "In2.Cu")
		(net "FT4232_MUX1_SEL")
	)
	(segment
		(start 28.194 -93.091)
		(end 25.908 -93.091)
		(width 0.127)
		(layer "In2.Cu")
		(net "FT4232_MUX1_SEL")
	)
	(segment
		(start 46.990254 -92.075)
		(end 35.433254 -92.075)
		(width 0.127)
		(layer "In2.Cu")
		(net "FT4232_MUX1_SEL")
	)
	(segment
		(start 68.930012 -93.345)
		(end 48.260254 -93.345)
		(width 0.127)
		(layer "In2.Cu")
		(net "FT4232_MUX1_SEL")
	)
	(segment
		(start 28.702 -92.583)
		(end 28.194 -93.091)
		(width 0.127)
		(layer "In2.Cu")
		(net "FT4232_MUX1_SEL")
	)
	(segment
		(start 21.717 -86.81466)
		(end 20.193 -86.81466)
		(width 0.127)
		(layer "In2.Cu")
		(net "FT4232_MUX1_SEL")
	)
	(segment
		(start 48.260254 -93.345)
		(end 46.990254 -92.075)
		(width 0.127)
		(layer "In2.Cu")
		(net "FT4232_MUX1_SEL")
	)
	(segment
		(start 24.8285 -92.0115)
		(end 20.972018 -92.0115)
		(width 0.127)
		(layer "In2.Cu")
		(net "FT4232_MUX1_SEL")
	)
	(segment
		(start 30.861 -91.313)
		(end 29.591 -92.583)
		(width 0.127)
		(layer "In2.Cu")
		(net "FT4232_MUX1_SEL")
	)
	(segment
		(start 29.591 -92.583)
		(end 28.702 -92.583)
		(width 0.127)
		(layer "In2.Cu")
		(net "FT4232_MUX1_SEL")
	)
	(segment
		(start 95.7072 -95.4532)
		(end 89.662 -89.408)
		(width 0.127)
		(layer "In2.Cu")
		(net "FT4232_MUX1_SEL")
	)
	(segment
		(start 89.662 -89.408)
		(end 72.867012 -89.408)
		(width 0.127)
		(layer "In2.Cu")
		(net "FT4232_MUX1_SEL")
	)
	(segment
		(start 72.867012 -89.408)
		(end 68.930012 -93.345)
		(width 0.127)
		(layer "In2.Cu")
		(net "FT4232_MUX1_SEL")
	)
	(segment
		(start 20.972018 -92.0115)
		(end 20.6375 -91.676982)
		(width 0.127)
		(layer "In2.Cu")
		(net "FT4232_MUX1_SEL")
	)
	(segment
		(start 25.908 -93.091)
		(end 24.8285 -92.0115)
		(width 0.127)
		(layer "In2.Cu")
		(net "FT4232_MUX1_SEL")
	)
	(segment
		(start 35.433254 -92.075)
		(end 34.671254 -91.313)
		(width 0.127)
		(layer "In2.Cu")
		(net "FT4232_MUX1_SEL")
	)
	(segment
		(start 21.844 -89.789254)
		(end 21.844 -86.94166)
		(width 0.127)
		(layer "In2.Cu")
		(net "FT4232_MUX1_SEL")
	)
	(segment
		(start 96.393 -95.4532)
		(end 95.7072 -95.4532)
		(width 0.127)
		(layer "In2.Cu")
		(net "FT4232_MUX1_SEL")
	)
	(segment
		(start 34.671254 -91.313)
		(end 30.861 -91.313)
		(width 0.127)
		(layer "In2.Cu")
		(net "FT4232_MUX1_SEL")
	)
	(segment
		(start 17.761966 -80.615282)
		(end 17.047718 -80.615282)
		(width 0.11938)
		(layer "F.Cu")
		(net "FT4232_I2C_SDA")
	)
	(segment
		(start 125.516894 -22.057106)
		(end 125.984 -21.59)
		(width 0.11938)
		(layer "F.Cu")
		(net "FT4232_I2C_SDA")
	)
	(segment
		(start 131.953 -19.177)
		(end 131.673092 -19.456908)
		(width 0.11938)
		(layer "F.Cu")
		(net "FT4232_I2C_SDA")
	)
	(segment
		(start 17.8816 -80.734916)
		(end 17.761966 -80.615282)
		(width 0.11938)
		(layer "F.Cu")
		(net "FT4232_I2C_SDA")
	)
	(segment
		(start 17.047718 -80.615282)
		(end 16.764 -80.899)
		(width 0.11938)
		(layer "F.Cu")
		(net "FT4232_I2C_SDA")
	)
	(segment
		(start 17.8816 -81.28)
		(end 17.8816 -80.734916)
		(width 0.11938)
		(layer "F.Cu")
		(net "FT4232_I2C_SDA")
	)
	(segment
		(start 124.0917 -22.057106)
		(end 125.516894 -22.057106)
		(width 0.11938)
		(layer "F.Cu")
		(net "FT4232_I2C_SDA")
	)
	(segment
		(start 131.673092 -19.456908)
		(end 130.1623 -19.456908)
		(width 0.11938)
		(layer "F.Cu")
		(net "FT4232_I2C_SDA")
	)
	(via
		(at 16.764 -80.899)
		(size 0.508)
		(drill 0.254)
		(layers "F.Cu" "B.Cu")
		(net "FT4232_I2C_SDA")
	)
	(via
		(at 125.984 -21.59)
		(size 0.508)
		(drill 0.254)
		(layers "F.Cu" "B.Cu")
		(net "FT4232_I2C_SDA")
	)
	(via
		(at 131.953 -19.177)
		(size 0.508)
		(drill 0.254)
		(layers "F.Cu" "B.Cu")
		(net "FT4232_I2C_SDA")
	)
	(via
		(at 91.948 -32.512)
		(size 0.508)
		(drill 0.254)
		(layers "F.Cu" "B.Cu")
		(net "FT4232_I2C_SDA")
	)
	(segment
		(start 17.8816 -81.28)
		(end 17.145 -81.28)
		(width 0.11938)
		(layer "B.Cu")
		(net "FT4232_I2C_SDA")
	)
	(segment
		(start 131.953 -19.177)
		(end 129.413 -19.177)
		(width 0.11938)
		(layer "B.Cu")
		(net "FT4232_I2C_SDA")
	)
	(segment
		(start 91.313 -31.877)
		(end 91.948 -32.512)
		(width 0.11938)
		(layer "B.Cu")
		(net "FT4232_I2C_SDA")
	)
	(segment
		(start 91.313 -28.83408)
		(end 91.313 -31.877)
		(width 0.11938)
		(layer "B.Cu")
		(net "FT4232_I2C_SDA")
	)
	(segment
		(start 93.98 -14.986)
		(end 89.662 -19.304)
		(width 0.11938)
		(layer "B.Cu")
		(net "FT4232_I2C_SDA")
	)
	(segment
		(start 85.09 -21.082)
		(end 85.09 -22.733254)
		(width 0.11938)
		(layer "B.Cu")
		(net "FT4232_I2C_SDA")
	)
	(segment
		(start 91.381072 -24.832818)
		(end 92.007182 -25.458928)
		(width 0.11938)
		(layer "B.Cu")
		(net "FT4232_I2C_SDA")
	)
	(segment
		(start 85.09 -22.733254)
		(end 87.189564 -24.832818)
		(width 0.11938)
		(layer "B.Cu")
		(net "FT4232_I2C_SDA")
	)
	(segment
		(start 87.189564 -24.832818)
		(end 91.381072 -24.832818)
		(width 0.11938)
		(layer "B.Cu")
		(net "FT4232_I2C_SDA")
	)
	(segment
		(start 17.145 -81.28)
		(end 16.764 -80.899)
		(width 0.11938)
		(layer "B.Cu")
		(net "FT4232_I2C_SDA")
	)
	(segment
		(start 89.662 -19.304)
		(end 86.868 -19.304)
		(width 0.11938)
		(layer "B.Cu")
		(net "FT4232_I2C_SDA")
	)
	(segment
		(start 92.007182 -25.458928)
		(end 92.007182 -28.139898)
		(width 0.11938)
		(layer "B.Cu")
		(net "FT4232_I2C_SDA")
	)
	(segment
		(start 17.8816 -80.137)
		(end 17.8816 -81.28)
		(width 0.11938)
		(layer "B.Cu")
		(net "FT4232_I2C_SDA")
	)
	(segment
		(start 129.413 -19.177)
		(end 125.222 -14.986)
		(width 0.11938)
		(layer "B.Cu")
		(net "FT4232_I2C_SDA")
	)
	(segment
		(start 125.222 -14.986)
		(end 93.98 -14.986)
		(width 0.11938)
		(layer "B.Cu")
		(net "FT4232_I2C_SDA")
	)
	(segment
		(start 86.868 -19.304)
		(end 85.09 -21.082)
		(width 0.11938)
		(layer "B.Cu")
		(net "FT4232_I2C_SDA")
	)
	(segment
		(start 92.007182 -28.139898)
		(end 91.313 -28.83408)
		(width 0.11938)
		(layer "B.Cu")
		(net "FT4232_I2C_SDA")
	)
	(segment
		(start 77.0255 -44.8945)
		(end 76.454 -44.323)
		(width 0.127)
		(layer "In2.Cu")
		(net "FT4232_I2C_SDA")
	)
	(segment
		(start 14.478 -75.39863)
		(end 14.351 -75.27163)
		(width 0.127)
		(layer "In2.Cu")
		(net "FT4232_I2C_SDA")
	)
	(segment
		(start 14.351 -76.54163)
		(end 14.351 -76.16063)
		(width 0.127)
		(layer "In2.Cu")
		(net "FT4232_I2C_SDA")
	)
	(segment
		(start 90.708734 -31.272734)
		(end 91.948 -32.512)
		(width 0.127)
		(layer "In2.Cu")
		(net "FT4232_I2C_SDA")
	)
	(segment
		(start 37.758878 -72.814688)
		(end 73.489312 -72.814688)
		(width 0.127)
		(layer "In2.Cu")
		(net "FT4232_I2C_SDA")
	)
	(segment
		(start 76.454 -40.767)
		(end 84.424266 -32.796734)
		(width 0.127)
		(layer "In2.Cu")
		(net "FT4232_I2C_SDA")
	)
	(segment
		(start 14.605 -77.30363)
		(end 14.732 -77.17663)
		(width 0.127)
		(layer "In2.Cu")
		(net "FT4232_I2C_SDA")
	)
	(segment
		(start 14.97076 -75.52563)
		(end 14.84376 -75.39863)
		(width 0.127)
		(layer "In2.Cu")
		(net "FT4232_I2C_SDA")
	)
	(segment
		(start 16.764 -80.899)
		(end 16.764 -80.391)
		(width 0.127)
		(layer "In2.Cu")
		(net "FT4232_I2C_SDA")
	)
	(segment
		(start 14.351 -75.27163)
		(end 14.351 -74.802746)
		(width 0.127)
		(layer "In2.Cu")
		(net "FT4232_I2C_SDA")
	)
	(segment
		(start 76.509118 -50.40757)
		(end 77.0255 -49.891188)
		(width 0.127)
		(layer "In2.Cu")
		(net "FT4232_I2C_SDA")
	)
	(segment
		(start 73.489312 -72.814688)
		(end 76.509118 -69.794882)
		(width 0.127)
		(layer "In2.Cu")
		(net "FT4232_I2C_SDA")
	)
	(segment
		(start 14.732 -76.79563)
		(end 14.605 -76.66863)
		(width 0.127)
		(layer "In2.Cu")
		(net "FT4232_I2C_SDA")
	)
	(segment
		(start 30.6705 -74.398632)
		(end 31.659068 -75.3872)
		(width 0.127)
		(layer "In2.Cu")
		(net "FT4232_I2C_SDA")
	)
	(segment
		(start 14.351 -77.43063)
		(end 14.478 -77.30363)
		(width 0.127)
		(layer "In2.Cu")
		(net "FT4232_I2C_SDA")
	)
	(segment
		(start 20.711414 -72.39)
		(end 29.591 -72.39)
		(width 0.127)
		(layer "In2.Cu")
		(net "FT4232_I2C_SDA")
	)
	(segment
		(start 77.0255 -49.891188)
		(end 77.0255 -44.8945)
		(width 0.127)
		(layer "In2.Cu")
		(net "FT4232_I2C_SDA")
	)
	(segment
		(start 14.97076 -75.90663)
		(end 14.97076 -75.52563)
		(width 0.127)
		(layer "In2.Cu")
		(net "FT4232_I2C_SDA")
	)
	(segment
		(start 14.351 -74.802746)
		(end 15.874746 -73.279)
		(width 0.127)
		(layer "In2.Cu")
		(net "FT4232_I2C_SDA")
	)
	(segment
		(start 15.874746 -73.279)
		(end 19.303746 -73.279)
		(width 0.127)
		(layer "In2.Cu")
		(net "FT4232_I2C_SDA")
	)
	(segment
		(start 20.710906 -72.389492)
		(end 20.711414 -72.39)
		(width 0.127)
		(layer "In2.Cu")
		(net "FT4232_I2C_SDA")
	)
	(segment
		(start 14.605 -76.66863)
		(end 14.478 -76.66863)
		(width 0.127)
		(layer "In2.Cu")
		(net "FT4232_I2C_SDA")
	)
	(segment
		(start 14.478 -77.30363)
		(end 14.605 -77.30363)
		(width 0.127)
		(layer "In2.Cu")
		(net "FT4232_I2C_SDA")
	)
	(segment
		(start 31.659068 -75.3872)
		(end 35.186366 -75.3872)
		(width 0.127)
		(layer "In2.Cu")
		(net "FT4232_I2C_SDA")
	)
	(segment
		(start 20.258278 -72.389492)
		(end 20.710906 -72.389492)
		(width 0.127)
		(layer "In2.Cu")
		(net "FT4232_I2C_SDA")
	)
	(segment
		(start 14.478 -76.66863)
		(end 14.351 -76.54163)
		(width 0.127)
		(layer "In2.Cu")
		(net "FT4232_I2C_SDA")
	)
	(segment
		(start 20.25777 -72.39)
		(end 20.258278 -72.389492)
		(width 0.127)
		(layer "In2.Cu")
		(net "FT4232_I2C_SDA")
	)
	(segment
		(start 14.84376 -76.03363)
		(end 14.97076 -75.90663)
		(width 0.127)
		(layer "In2.Cu")
		(net "FT4232_I2C_SDA")
	)
	(segment
		(start 14.351 -77.978)
		(end 14.351 -77.43063)
		(width 0.127)
		(layer "In2.Cu")
		(net "FT4232_I2C_SDA")
	)
	(segment
		(start 14.84376 -75.39863)
		(end 14.478 -75.39863)
		(width 0.127)
		(layer "In2.Cu")
		(net "FT4232_I2C_SDA")
	)
	(segment
		(start 20.192746 -72.39)
		(end 20.25777 -72.39)
		(width 0.127)
		(layer "In2.Cu")
		(net "FT4232_I2C_SDA")
	)
	(segment
		(start 88.107266 -31.272734)
		(end 90.708734 -31.272734)
		(width 0.127)
		(layer "In2.Cu")
		(net "FT4232_I2C_SDA")
	)
	(segment
		(start 14.478 -76.03363)
		(end 14.84376 -76.03363)
		(width 0.127)
		(layer "In2.Cu")
		(net "FT4232_I2C_SDA")
	)
	(segment
		(start 86.583266 -32.796734)
		(end 88.107266 -31.272734)
		(width 0.127)
		(layer "In2.Cu")
		(net "FT4232_I2C_SDA")
	)
	(segment
		(start 16.764 -80.391)
		(end 14.351 -77.978)
		(width 0.127)
		(layer "In2.Cu")
		(net "FT4232_I2C_SDA")
	)
	(segment
		(start 76.509118 -69.794882)
		(end 76.509118 -50.40757)
		(width 0.127)
		(layer "In2.Cu")
		(net "FT4232_I2C_SDA")
	)
	(segment
		(start 35.186366 -75.3872)
		(end 37.758878 -72.814688)
		(width 0.127)
		(layer "In2.Cu")
		(net "FT4232_I2C_SDA")
	)
	(segment
		(start 14.732 -77.17663)
		(end 14.732 -76.79563)
		(width 0.127)
		(layer "In2.Cu")
		(net "FT4232_I2C_SDA")
	)
	(segment
		(start 30.6705 -73.4695)
		(end 30.6705 -74.398632)
		(width 0.127)
		(layer "In2.Cu")
		(net "FT4232_I2C_SDA")
	)
	(segment
		(start 84.424266 -32.796734)
		(end 86.583266 -32.796734)
		(width 0.127)
		(layer "In2.Cu")
		(net "FT4232_I2C_SDA")
	)
	(segment
		(start 14.351 -76.16063)
		(end 14.478 -76.03363)
		(width 0.127)
		(layer "In2.Cu")
		(net "FT4232_I2C_SDA")
	)
	(segment
		(start 76.454 -44.323)
		(end 76.454 -40.767)
		(width 0.127)
		(layer "In2.Cu")
		(net "FT4232_I2C_SDA")
	)
	(segment
		(start 29.591 -72.39)
		(end 30.6705 -73.4695)
		(width 0.127)
		(layer "In2.Cu")
		(net "FT4232_I2C_SDA")
	)
	(segment
		(start 19.303746 -73.279)
		(end 20.192746 -72.39)
		(width 0.127)
		(layer "In2.Cu")
		(net "FT4232_I2C_SDA")
	)
	(segment
		(start 131.064 -21.59)
		(end 125.984 -21.59)
		(width 0.127)
		(layer "In7.Cu")
		(net "FT4232_I2C_SDA")
	)
	(segment
		(start 131.953 -19.177)
		(end 132.842 -20.066)
		(width 0.127)
		(layer "In7.Cu")
		(net "FT4232_I2C_SDA")
	)
	(segment
		(start 131.318 -21.336)
		(end 131.064 -21.59)
		(width 0.127)
		(layer "In7.Cu")
		(net "FT4232_I2C_SDA")
	)
	(segment
		(start 132.334 -21.336)
		(end 131.318 -21.336)
		(width 0.127)
		(layer "In7.Cu")
		(net "FT4232_I2C_SDA")
	)
	(segment
		(start 132.842 -20.828)
		(end 132.334 -21.336)
		(width 0.127)
		(layer "In7.Cu")
		(net "FT4232_I2C_SDA")
	)
	(segment
		(start 132.842 -20.066)
		(end 132.842 -20.828)
		(width 0.127)
		(layer "In7.Cu")
		(net "FT4232_I2C_SDA")
	)
	(segment
		(start 125.3998 -20.106894)
		(end 124.0917 -20.106894)
		(width 0.11938)
		(layer "F.Cu")
		(net "FT4232_I2C_SCL")
	)
	(segment
		(start 131.24688 -21.40712)
		(end 130.1623 -21.40712)
		(width 0.11938)
		(layer "F.Cu")
		(net "FT4232_I2C_SCL")
	)
	(segment
		(start 17.6276 -82.169)
		(end 16.764 -82.169)
		(width 0.11938)
		(layer "F.Cu")
		(net "FT4232_I2C_SCL")
	)
	(segment
		(start 17.8816 -82.423)
		(end 17.6276 -82.169)
		(width 0.11938)
		(layer "F.Cu")
		(net "FT4232_I2C_SCL")
	)
	(segment
		(start 131.953 -20.701)
		(end 131.24688 -21.40712)
		(width 0.11938)
		(layer "F.Cu")
		(net "FT4232_I2C_SCL")
	)
	(via
		(at 131.953 -20.701)
		(size 0.508)
		(drill 0.254)
		(layers "F.Cu" "B.Cu")
		(net "FT4232_I2C_SCL")
	)
	(via
		(at 91.948 -31.369)
		(size 0.508)
		(drill 0.254)
		(layers "F.Cu" "B.Cu")
		(net "FT4232_I2C_SCL")
	)
	(via
		(at 125.3998 -20.106894)
		(size 0.508)
		(drill 0.254)
		(layers "F.Cu" "B.Cu")
		(net "FT4232_I2C_SCL")
	)
	(via
		(at 16.764 -82.169)
		(size 0.508)
		(drill 0.254)
		(layers "F.Cu" "B.Cu")
		(net "FT4232_I2C_SCL")
	)
	(segment
		(start 87.053928 -19.752818)
		(end 85.725 -21.081746)
		(width 0.11938)
		(layer "B.Cu")
		(net "FT4232_I2C_SCL")
	)
	(segment
		(start 17.8816 -82.423)
		(end 17.6276 -82.169)
		(width 0.11938)
		(layer "B.Cu")
		(net "FT4232_I2C_SCL")
	)
	(segment
		(start 92.456 -30.099)
		(end 91.948 -30.607)
		(width 0.11938)
		(layer "B.Cu")
		(net "FT4232_I2C_SCL")
	)
	(segment
		(start 92.456 -25.273)
		(end 92.456 -30.099)
		(width 0.11938)
		(layer "B.Cu")
		(net "FT4232_I2C_SCL")
	)
	(segment
		(start 85.725 -22.479)
		(end 87.63 -24.384)
		(width 0.11938)
		(layer "B.Cu")
		(net "FT4232_I2C_SCL")
	)
	(segment
		(start 125.035818 -15.434818)
		(end 94.165928 -15.434818)
		(width 0.11938)
		(layer "B.Cu")
		(net "FT4232_I2C_SCL")
	)
	(segment
		(start 130.302 -20.701)
		(end 125.035818 -15.434818)
		(width 0.11938)
		(layer "B.Cu")
		(net "FT4232_I2C_SCL")
	)
	(segment
		(start 89.847928 -19.752818)
		(end 87.053928 -19.752818)
		(width 0.11938)
		(layer "B.Cu")
		(net "FT4232_I2C_SCL")
	)
	(segment
		(start 91.567 -24.384)
		(end 92.456 -25.273)
		(width 0.11938)
		(layer "B.Cu")
		(net "FT4232_I2C_SCL")
	)
	(segment
		(start 87.63 -24.384)
		(end 91.567 -24.384)
		(width 0.11938)
		(layer "B.Cu")
		(net "FT4232_I2C_SCL")
	)
	(segment
		(start 131.953 -20.701)
		(end 130.302 -20.701)
		(width 0.11938)
		(layer "B.Cu")
		(net "FT4232_I2C_SCL")
	)
	(segment
		(start 85.725 -21.081746)
		(end 85.725 -22.479)
		(width 0.11938)
		(layer "B.Cu")
		(net "FT4232_I2C_SCL")
	)
	(segment
		(start 94.165928 -15.434818)
		(end 89.847928 -19.752818)
		(width 0.11938)
		(layer "B.Cu")
		(net "FT4232_I2C_SCL")
	)
	(segment
		(start 91.948 -30.607)
		(end 91.948 -31.369)
		(width 0.11938)
		(layer "B.Cu")
		(net "FT4232_I2C_SCL")
	)
	(segment
		(start 17.6276 -82.169)
		(end 16.764 -82.169)
		(width 0.11938)
		(layer "B.Cu")
		(net "FT4232_I2C_SCL")
	)
	(segment
		(start 14.478 -72.644)
		(end 19.22018 -72.644)
		(width 0.127)
		(layer "In2.Cu")
		(net "FT4232_I2C_SCL")
	)
	(segment
		(start 86.329266 -32.288734)
		(end 87.884 -30.734)
		(width 0.127)
		(layer "In2.Cu")
		(net "FT4232_I2C_SCL")
	)
	(segment
		(start 75.946 -43.18)
		(end 75.946 -40.556434)
		(width 0.127)
		(layer "In2.Cu")
		(net "FT4232_I2C_SCL")
	)
	(segment
		(start 91.313 -30.734)
		(end 91.948 -31.369)
		(width 0.127)
		(layer "In2.Cu")
		(net "FT4232_I2C_SCL")
	)
	(segment
		(start 20.192492 -71.671688)
		(end 29.634688 -71.671688)
		(width 0.127)
		(layer "In2.Cu")
		(net "FT4232_I2C_SCL")
	)
	(segment
		(start 87.884 -30.734)
		(end 91.313 -30.734)
		(width 0.127)
		(layer "In2.Cu")
		(net "FT4232_I2C_SCL")
	)
	(segment
		(start 31.869634 -74.8792)
		(end 34.9758 -74.8792)
		(width 0.127)
		(layer "In2.Cu")
		(net "FT4232_I2C_SCL")
	)
	(segment
		(start 15.75816 -80.40116)
		(end 13.632688 -78.275688)
		(width 0.127)
		(layer "In2.Cu")
		(net "FT4232_I2C_SCL")
	)
	(segment
		(start 19.22018 -72.644)
		(end 20.192492 -71.671688)
		(width 0.127)
		(layer "In2.Cu")
		(net "FT4232_I2C_SCL")
	)
	(segment
		(start 73.108312 -72.306688)
		(end 76.001118 -69.413882)
		(width 0.127)
		(layer "In2.Cu")
		(net "FT4232_I2C_SCL")
	)
	(segment
		(start 13.632688 -73.489312)
		(end 14.478 -72.644)
		(width 0.127)
		(layer "In2.Cu")
		(net "FT4232_I2C_SCL")
	)
	(segment
		(start 13.632688 -78.275688)
		(end 13.632688 -73.489312)
		(width 0.127)
		(layer "In2.Cu")
		(net "FT4232_I2C_SCL")
	)
	(segment
		(start 76.001118 -69.413882)
		(end 76.001118 -51.998372)
		(width 0.127)
		(layer "In2.Cu")
		(net "FT4232_I2C_SCL")
	)
	(segment
		(start 31.1785 -74.188066)
		(end 31.869634 -74.8792)
		(width 0.127)
		(layer "In2.Cu")
		(net "FT4232_I2C_SCL")
	)
	(segment
		(start 37.548312 -72.306688)
		(end 73.108312 -72.306688)
		(width 0.127)
		(layer "In2.Cu")
		(net "FT4232_I2C_SCL")
	)
	(segment
		(start 34.9758 -74.8792)
		(end 37.548312 -72.306688)
		(width 0.127)
		(layer "In2.Cu")
		(net "FT4232_I2C_SCL")
	)
	(segment
		(start 29.634688 -71.671688)
		(end 31.1785 -73.2155)
		(width 0.127)
		(layer "In2.Cu")
		(net "FT4232_I2C_SCL")
	)
	(segment
		(start 16.764 -82.169)
		(end 15.75816 -81.16316)
		(width 0.127)
		(layer "In2.Cu")
		(net "FT4232_I2C_SCL")
	)
	(segment
		(start 73.3552 -49.352454)
		(end 73.3552 -45.7708)
		(width 0.127)
		(layer "In2.Cu")
		(net "FT4232_I2C_SCL")
	)
	(segment
		(start 15.75816 -81.16316)
		(end 15.75816 -80.40116)
		(width 0.127)
		(layer "In2.Cu")
		(net "FT4232_I2C_SCL")
	)
	(segment
		(start 31.1785 -73.2155)
		(end 31.1785 -74.188066)
		(width 0.127)
		(layer "In2.Cu")
		(net "FT4232_I2C_SCL")
	)
	(segment
		(start 75.946 -40.556434)
		(end 84.2137 -32.288734)
		(width 0.127)
		(layer "In2.Cu")
		(net "FT4232_I2C_SCL")
	)
	(segment
		(start 73.3552 -45.7708)
		(end 75.946 -43.18)
		(width 0.127)
		(layer "In2.Cu")
		(net "FT4232_I2C_SCL")
	)
	(segment
		(start 84.2137 -32.288734)
		(end 86.329266 -32.288734)
		(width 0.127)
		(layer "In2.Cu")
		(net "FT4232_I2C_SCL")
	)
	(segment
		(start 76.001118 -51.998372)
		(end 73.3552 -49.352454)
		(width 0.127)
		(layer "In2.Cu")
		(net "FT4232_I2C_SCL")
	)
	(segment
		(start 129.822448 -20.18284)
		(end 129.949448 -20.05584)
		(width 0.127)
		(layer "In7.Cu")
		(net "FT4232_I2C_SCL")
	)
	(segment
		(start 130.584448 -20.701)
		(end 131.953 -20.701)
		(width 0.127)
		(layer "In7.Cu")
		(net "FT4232_I2C_SCL")
	)
	(segment
		(start 129.187448 -20.18284)
		(end 129.187448 -20.574)
		(width 0.127)
		(layer "In7.Cu")
		(net "FT4232_I2C_SCL")
	)
	(segment
		(start 127.790448 -20.00758)
		(end 127.917448 -20.13458)
		(width 0.127)
		(layer "In7.Cu")
		(net "FT4232_I2C_SCL")
	)
	(segment
		(start 126.05512 -20.701)
		(end 127.155448 -20.701)
		(width 0.127)
		(layer "In7.Cu")
		(net "FT4232_I2C_SCL")
	)
	(segment
		(start 130.457448 -20.574)
		(end 130.584448 -20.701)
		(width 0.127)
		(layer "In7.Cu")
		(net "FT4232_I2C_SCL")
	)
	(segment
		(start 127.282448 -20.574)
		(end 127.282448 -20.13458)
		(width 0.127)
		(layer "In7.Cu")
		(net "FT4232_I2C_SCL")
	)
	(segment
		(start 128.044448 -20.701)
		(end 128.425448 -20.701)
		(width 0.127)
		(layer "In7.Cu")
		(net "FT4232_I2C_SCL")
	)
	(segment
		(start 130.330448 -20.05584)
		(end 130.457448 -20.18284)
		(width 0.127)
		(layer "In7.Cu")
		(net "FT4232_I2C_SCL")
	)
	(segment
		(start 125.3998 -20.106894)
		(end 125.461014 -20.106894)
		(width 0.127)
		(layer "In7.Cu")
		(net "FT4232_I2C_SCL")
	)
	(segment
		(start 127.155448 -20.701)
		(end 127.282448 -20.574)
		(width 0.127)
		(layer "In7.Cu")
		(net "FT4232_I2C_SCL")
	)
	(segment
		(start 129.314448 -20.701)
		(end 129.695448 -20.701)
		(width 0.127)
		(layer "In7.Cu")
		(net "FT4232_I2C_SCL")
	)
	(segment
		(start 127.917448 -20.13458)
		(end 127.917448 -20.574)
		(width 0.127)
		(layer "In7.Cu")
		(net "FT4232_I2C_SCL")
	)
	(segment
		(start 128.425448 -20.701)
		(end 128.552448 -20.574)
		(width 0.127)
		(layer "In7.Cu")
		(net "FT4232_I2C_SCL")
	)
	(segment
		(start 128.679448 -20.05584)
		(end 129.060448 -20.05584)
		(width 0.127)
		(layer "In7.Cu")
		(net "FT4232_I2C_SCL")
	)
	(segment
		(start 129.822448 -20.574)
		(end 129.822448 -20.18284)
		(width 0.127)
		(layer "In7.Cu")
		(net "FT4232_I2C_SCL")
	)
	(segment
		(start 128.552448 -20.574)
		(end 128.552448 -20.18284)
		(width 0.127)
		(layer "In7.Cu")
		(net "FT4232_I2C_SCL")
	)
	(segment
		(start 127.282448 -20.13458)
		(end 127.409448 -20.00758)
		(width 0.127)
		(layer "In7.Cu")
		(net "FT4232_I2C_SCL")
	)
	(segment
		(start 127.917448 -20.574)
		(end 128.044448 -20.701)
		(width 0.127)
		(layer "In7.Cu")
		(net "FT4232_I2C_SCL")
	)
	(segment
		(start 128.552448 -20.18284)
		(end 128.679448 -20.05584)
		(width 0.127)
		(layer "In7.Cu")
		(net "FT4232_I2C_SCL")
	)
	(segment
		(start 125.461014 -20.106894)
		(end 126.05512 -20.701)
		(width 0.127)
		(layer "In7.Cu")
		(net "FT4232_I2C_SCL")
	)
	(segment
		(start 129.695448 -20.701)
		(end 129.822448 -20.574)
		(width 0.127)
		(layer "In7.Cu")
		(net "FT4232_I2C_SCL")
	)
	(segment
		(start 130.457448 -20.18284)
		(end 130.457448 -20.574)
		(width 0.127)
		(layer "In7.Cu")
		(net "FT4232_I2C_SCL")
	)
	(segment
		(start 129.060448 -20.05584)
		(end 129.187448 -20.18284)
		(width 0.127)
		(layer "In7.Cu")
		(net "FT4232_I2C_SCL")
	)
	(segment
		(start 127.409448 -20.00758)
		(end 127.790448 -20.00758)
		(width 0.127)
		(layer "In7.Cu")
		(net "FT4232_I2C_SCL")
	)
	(segment
		(start 129.187448 -20.574)
		(end 129.314448 -20.701)
		(width 0.127)
		(layer "In7.Cu")
		(net "FT4232_I2C_SCL")
	)
	(segment
		(start 129.949448 -20.05584)
		(end 130.330448 -20.05584)
		(width 0.127)
		(layer "In7.Cu")
		(net "FT4232_I2C_SCL")
	)
	(segment
		(start 107.188 -96.393)
		(end 107.188 -94.742254)
		(width 0.11938)
		(layer "F.Cu")
		(net "FT4232_FPGA_TMS")
	)
	(segment
		(start 106.807 -96.774)
		(end 107.188 -96.393)
		(width 0.11938)
		(layer "F.Cu")
		(net "FT4232_FPGA_TMS")
	)
	(segment
		(start 107.610148 -94.320106)
		(end 108.5723 -94.320106)
		(width 0.11938)
		(layer "F.Cu")
		(net "FT4232_FPGA_TMS")
	)
	(segment
		(start 107.188 -94.742254)
		(end 107.610148 -94.320106)
		(width 0.11938)
		(layer "F.Cu")
		(net "FT4232_FPGA_TMS")
	)
	(segment
		(start 145.048224 -71.6534)
		(end 147.6756 -71.6534)
		(width 0.11938)
		(layer "F.Cu")
		(net "FT4232_FPGA_TMS")
	)
	(via
		(at 106.807 -96.774)
		(size 0.508)
		(drill 0.254)
		(layers "F.Cu" "B.Cu")
		(net "FT4232_FPGA_TMS")
	)
	(via
		(at 147.6756 -71.6534)
		(size 0.4572)
		(drill 0.2032)
		(layers "F.Cu" "B.Cu")
		(net "FT4232_FPGA_TMS")
	)
	(segment
		(start 144.0307 -73.3679)
		(end 145.2626 -72.136)
		(width 0.11938)
		(layer "B.Cu")
		(net "FT4232_FPGA_TMS")
	)
	(segment
		(start 145.2626 -72.136)
		(end 147.193 -72.136)
		(width 0.11938)
		(layer "B.Cu")
		(net "FT4232_FPGA_TMS")
	)
	(segment
		(start 144.0307 -74.2315)
		(end 144.0307 -73.3679)
		(width 0.11938)
		(layer "B.Cu")
		(net "FT4232_FPGA_TMS")
	)
	(segment
		(start 144.0307 -74.2315)
		(end 140.8176 -74.2315)
		(width 0.11938)
		(layer "B.Cu")
		(net "FT4232_FPGA_TMS")
	)
	(segment
		(start 147.193 -72.136)
		(end 147.6756 -71.6534)
		(width 0.11938)
		(layer "B.Cu")
		(net "FT4232_FPGA_TMS")
	)
	(segment
		(start 146.177 -73.462642)
		(end 146.177 -73.843642)
		(width 0.127)
		(layer "In7.Cu")
		(net "FT4232_FPGA_TMS")
	)
	(segment
		(start 115.062 -98.044)
		(end 113.167414 -98.044)
		(width 0.127)
		(layer "In7.Cu")
		(net "FT4232_FPGA_TMS")
	)
	(segment
		(start 108.93044 -97.4725)
		(end 108.86694 -97.536)
		(width 0.127)
		(layer "In7.Cu")
		(net "FT4232_FPGA_TMS")
	)
	(segment
		(start 145.288 -75.240642)
		(end 145.161 -75.367642)
		(width 0.127)
		(layer "In7.Cu")
		(net "FT4232_FPGA_TMS")
	)
	(segment
		(start 146.177 -74.732642)
		(end 146.177 -75.113642)
		(width 0.127)
		(layer "In7.Cu")
		(net "FT4232_FPGA_TMS")
	)
	(segment
		(start 145.288 -73.970642)
		(end 145.161 -74.097642)
		(width 0.127)
		(layer "In7.Cu")
		(net "FT4232_FPGA_TMS")
	)
	(segment
		(start 145.161 -75.748642)
		(end 145.288 -75.875642)
		(width 0.127)
		(layer "In7.Cu")
		(net "FT4232_FPGA_TMS")
	)
	(segment
		(start 145.161 -77.470254)
		(end 143.51 -79.121254)
		(width 0.127)
		(layer "In7.Cu")
		(net "FT4232_FPGA_TMS")
	)
	(segment
		(start 109.57306 -97.536)
		(end 109.50956 -97.4725)
		(width 0.127)
		(layer "In7.Cu")
		(net "FT4232_FPGA_TMS")
	)
	(segment
		(start 126.14529 -95.002604)
		(end 118.103396 -95.002604)
		(width 0.127)
		(layer "In7.Cu")
		(net "FT4232_FPGA_TMS")
	)
	(segment
		(start 145.161 -76.637642)
		(end 145.161 -77.470254)
		(width 0.127)
		(layer "In7.Cu")
		(net "FT4232_FPGA_TMS")
	)
	(segment
		(start 145.288 -74.605642)
		(end 146.05 -74.605642)
		(width 0.127)
		(layer "In7.Cu")
		(net "FT4232_FPGA_TMS")
	)
	(segment
		(start 108.86694 -97.536)
		(end 107.569 -97.536)
		(width 0.127)
		(layer "In7.Cu")
		(net "FT4232_FPGA_TMS")
	)
	(segment
		(start 145.161 -74.097642)
		(end 145.161 -74.478642)
		(width 0.127)
		(layer "In7.Cu")
		(net "FT4232_FPGA_TMS")
	)
	(segment
		(start 146.05 -73.335642)
		(end 146.177 -73.462642)
		(width 0.127)
		(layer "In7.Cu")
		(net "FT4232_FPGA_TMS")
	)
	(segment
		(start 145.161 -73.208642)
		(end 145.288 -73.335642)
		(width 0.127)
		(layer "In7.Cu")
		(net "FT4232_FPGA_TMS")
	)
	(segment
		(start 118.103396 -95.002604)
		(end 115.062 -98.044)
		(width 0.127)
		(layer "In7.Cu")
		(net "FT4232_FPGA_TMS")
	)
	(segment
		(start 110.109254 -97.536)
		(end 109.57306 -97.536)
		(width 0.127)
		(layer "In7.Cu")
		(net "FT4232_FPGA_TMS")
	)
	(segment
		(start 146.05 -75.240642)
		(end 145.288 -75.240642)
		(width 0.127)
		(layer "In7.Cu")
		(net "FT4232_FPGA_TMS")
	)
	(segment
		(start 109.50956 -97.4725)
		(end 108.93044 -97.4725)
		(width 0.127)
		(layer "In7.Cu")
		(net "FT4232_FPGA_TMS")
	)
	(segment
		(start 110.363254 -97.79)
		(end 110.109254 -97.536)
		(width 0.127)
		(layer "In7.Cu")
		(net "FT4232_FPGA_TMS")
	)
	(segment
		(start 143.51 -79.121254)
		(end 143.51 -86.685374)
		(width 0.127)
		(layer "In7.Cu")
		(net "FT4232_FPGA_TMS")
	)
	(segment
		(start 112.748314 -97.6249)
		(end 112.051846 -97.6249)
		(width 0.127)
		(layer "In7.Cu")
		(net "FT4232_FPGA_TMS")
	)
	(segment
		(start 111.886746 -97.79)
		(end 110.363254 -97.79)
		(width 0.127)
		(layer "In7.Cu")
		(net "FT4232_FPGA_TMS")
	)
	(segment
		(start 113.167414 -98.044)
		(end 112.748314 -97.6249)
		(width 0.127)
		(layer "In7.Cu")
		(net "FT4232_FPGA_TMS")
	)
	(segment
		(start 145.161 -75.367642)
		(end 145.161 -75.748642)
		(width 0.127)
		(layer "In7.Cu")
		(net "FT4232_FPGA_TMS")
	)
	(segment
		(start 145.161 -74.478642)
		(end 145.288 -74.605642)
		(width 0.127)
		(layer "In7.Cu")
		(net "FT4232_FPGA_TMS")
	)
	(segment
		(start 145.288 -76.510642)
		(end 145.161 -76.637642)
		(width 0.127)
		(layer "In7.Cu")
		(net "FT4232_FPGA_TMS")
	)
	(segment
		(start 146.05 -73.970642)
		(end 145.288 -73.970642)
		(width 0.127)
		(layer "In7.Cu")
		(net "FT4232_FPGA_TMS")
	)
	(segment
		(start 146.05 -75.875642)
		(end 146.177 -76.002642)
		(width 0.127)
		(layer "In7.Cu")
		(net "FT4232_FPGA_TMS")
	)
	(segment
		(start 146.05 -76.510642)
		(end 145.288 -76.510642)
		(width 0.127)
		(layer "In7.Cu")
		(net "FT4232_FPGA_TMS")
	)
	(segment
		(start 146.177 -75.113642)
		(end 146.05 -75.240642)
		(width 0.127)
		(layer "In7.Cu")
		(net "FT4232_FPGA_TMS")
	)
	(segment
		(start 107.569 -97.536)
		(end 106.807 -96.774)
		(width 0.127)
		(layer "In7.Cu")
		(net "FT4232_FPGA_TMS")
	)
	(segment
		(start 146.1516 -71.6534)
		(end 145.161 -72.644)
		(width 0.127)
		(layer "In7.Cu")
		(net "FT4232_FPGA_TMS")
	)
	(segment
		(start 146.177 -73.843642)
		(end 146.05 -73.970642)
		(width 0.127)
		(layer "In7.Cu")
		(net "FT4232_FPGA_TMS")
	)
	(segment
		(start 141.841474 -88.3539)
		(end 132.793994 -88.3539)
		(width 0.127)
		(layer "In7.Cu")
		(net "FT4232_FPGA_TMS")
	)
	(segment
		(start 146.05 -74.605642)
		(end 146.177 -74.732642)
		(width 0.127)
		(layer "In7.Cu")
		(net "FT4232_FPGA_TMS")
	)
	(segment
		(start 112.051846 -97.6249)
		(end 111.886746 -97.79)
		(width 0.127)
		(layer "In7.Cu")
		(net "FT4232_FPGA_TMS")
	)
	(segment
		(start 147.6756 -71.6534)
		(end 146.1516 -71.6534)
		(width 0.127)
		(layer "In7.Cu")
		(net "FT4232_FPGA_TMS")
	)
	(segment
		(start 132.793994 -88.3539)
		(end 126.14529 -95.002604)
		(width 0.127)
		(layer "In7.Cu")
		(net "FT4232_FPGA_TMS")
	)
	(segment
		(start 145.288 -73.335642)
		(end 146.05 -73.335642)
		(width 0.127)
		(layer "In7.Cu")
		(net "FT4232_FPGA_TMS")
	)
	(segment
		(start 146.177 -76.383642)
		(end 146.05 -76.510642)
		(width 0.127)
		(layer "In7.Cu")
		(net "FT4232_FPGA_TMS")
	)
	(segment
		(start 143.51 -86.685374)
		(end 141.841474 -88.3539)
		(width 0.127)
		(layer "In7.Cu")
		(net "FT4232_FPGA_TMS")
	)
	(segment
		(start 145.288 -75.875642)
		(end 146.05 -75.875642)
		(width 0.127)
		(layer "In7.Cu")
		(net "FT4232_FPGA_TMS")
	)
	(segment
		(start 146.177 -76.002642)
		(end 146.177 -76.383642)
		(width 0.127)
		(layer "In7.Cu")
		(net "FT4232_FPGA_TMS")
	)
	(segment
		(start 145.161 -72.644)
		(end 145.161 -73.208642)
		(width 0.127)
		(layer "In7.Cu")
		(net "FT4232_FPGA_TMS")
	)
	(segment
		(start 106.426 -94.869)
		(end 105.664 -94.107)
		(width 0.11938)
		(layer "F.Cu")
		(net "FT4232_FPGA_TDO")
	)
	(segment
		(start 105.664 -94.107)
		(end 105.664 -92.71)
		(width 0.11938)
		(layer "F.Cu")
		(net "FT4232_FPGA_TDO")
	)
	(segment
		(start 145.048224 -69.1134)
		(end 147.6756 -69.1134)
		(width 0.11938)
		(layer "F.Cu")
		(net "FT4232_FPGA_TDO")
	)
	(segment
		(start 105.664 -92.71)
		(end 106.004106 -92.369894)
		(width 0.11938)
		(layer "F.Cu")
		(net "FT4232_FPGA_TDO")
	)
	(segment
		(start 106.004106 -92.369894)
		(end 108.5723 -92.369894)
		(width 0.11938)
		(layer "F.Cu")
		(net "FT4232_FPGA_TDO")
	)
	(via
		(at 106.426 -94.869)
		(size 0.508)
		(drill 0.254)
		(layers "F.Cu" "B.Cu")
		(net "FT4232_FPGA_TDO")
	)
	(via
		(at 147.6756 -69.1134)
		(size 0.4572)
		(drill 0.2032)
		(layers "F.Cu" "B.Cu")
		(net "FT4232_FPGA_TDO")
	)
	(segment
		(start 144.1577 -70.1167)
		(end 144.1577 -69.2023)
		(width 0.11938)
		(layer "B.Cu")
		(net "FT4232_FPGA_TDO")
	)
	(segment
		(start 140.8684 -70.358)
		(end 141.537944 -70.358)
		(width 0.11938)
		(layer "B.Cu")
		(net "FT4232_FPGA_TDO")
	)
	(segment
		(start 141.537944 -70.358)
		(end 141.563344 -70.3834)
		(width 0.11938)
		(layer "B.Cu")
		(net "FT4232_FPGA_TDO")
	)
	(segment
		(start 147.193 -70.612)
		(end 144.653 -70.612)
		(width 0.11938)
		(layer "B.Cu")
		(net "FT4232_FPGA_TDO")
	)
	(segment
		(start 147.6756 -70.1294)
		(end 147.193 -70.612)
		(width 0.11938)
		(layer "B.Cu")
		(net "FT4232_FPGA_TDO")
	)
	(segment
		(start 141.8336 -70.3834)
		(end 143.0147 -69.2023)
		(width 0.11938)
		(layer "B.Cu")
		(net "FT4232_FPGA_TDO")
	)
	(segment
		(start 144.653 -70.612)
		(end 144.1577 -70.1167)
		(width 0.11938)
		(layer "B.Cu")
		(net "FT4232_FPGA_TDO")
	)
	(segment
		(start 143.0147 -69.2023)
		(end 144.1577 -69.2023)
		(width 0.11938)
		(layer "B.Cu")
		(net "FT4232_FPGA_TDO")
	)
	(segment
		(start 141.563344 -70.3834)
		(end 141.8336 -70.3834)
		(width 0.11938)
		(layer "B.Cu")
		(net "FT4232_FPGA_TDO")
	)
	(segment
		(start 147.6756 -69.1134)
		(end 147.6756 -70.1294)
		(width 0.11938)
		(layer "B.Cu")
		(net "FT4232_FPGA_TDO")
	)
	(segment
		(start 144.399 -72.009)
		(end 147.2946 -69.1134)
		(width 0.127)
		(layer "In7.Cu")
		(net "FT4232_FPGA_TDO")
	)
	(segment
		(start 141.622272 -76.99756)
		(end 141.91234 -77.287628)
		(width 0.127)
		(layer "In7.Cu")
		(net "FT4232_FPGA_TDO")
	)
	(segment
		(start 141.194028 -78.185772)
		(end 141.463268 -77.916532)
		(width 0.127)
		(layer "In7.Cu")
		(net "FT4232_FPGA_TDO")
	)
	(segment
		(start 142.071344 -76.368656)
		(end 142.340584 -76.099416)
		(width 0.127)
		(layer "In7.Cu")
		(net "FT4232_FPGA_TDO")
	)
	(segment
		(start 142.361412 -76.838556)
		(end 142.071344 -76.548488)
		(width 0.127)
		(layer "In7.Cu")
		(net "FT4232_FPGA_TDO")
	)
	(segment
		(start 114.380518 -96.901)
		(end 114.952018 -96.3295)
		(width 0.127)
		(layer "In7.Cu")
		(net "FT4232_FPGA_TDO")
	)
	(segment
		(start 143.88846 -75.49134)
		(end 144.1577 -75.2221)
		(width 0.127)
		(layer "In7.Cu")
		(net "FT4232_FPGA_TDO")
	)
	(segment
		(start 142.990316 -76.389484)
		(end 143.259556 -76.120244)
		(width 0.127)
		(layer "In7.Cu")
		(net "FT4232_FPGA_TDO")
	)
	(segment
		(start 126.03988 -94.389448)
		(end 132.5372 -87.892128)
		(width 0.127)
		(layer "In7.Cu")
		(net "FT4232_FPGA_TDO")
	)
	(segment
		(start 141.014196 -78.185772)
		(end 141.194028 -78.185772)
		(width 0.127)
		(layer "In7.Cu")
		(net "FT4232_FPGA_TDO")
	)
	(segment
		(start 141.463268 -77.916532)
		(end 141.463268 -77.7367)
		(width 0.127)
		(layer "In7.Cu")
		(net "FT4232_FPGA_TDO")
	)
	(segment
		(start 142.969488 -75.650344)
		(end 142.969488 -75.470512)
		(width 0.127)
		(layer "In7.Cu")
		(net "FT4232_FPGA_TDO")
	)
	(segment
		(start 117.998494 -94.389448)
		(end 126.03988 -94.389448)
		(width 0.127)
		(layer "In7.Cu")
		(net "FT4232_FPGA_TDO")
	)
	(segment
		(start 142.810484 -76.389484)
		(end 142.990316 -76.389484)
		(width 0.127)
		(layer "In7.Cu")
		(net "FT4232_FPGA_TDO")
	)
	(segment
		(start 132.5372 -80.5688)
		(end 133.604 -79.502)
		(width 0.127)
		(layer "In7.Cu")
		(net "FT4232_FPGA_TDO")
	)
	(segment
		(start 143.708628 -75.49134)
		(end 143.88846 -75.49134)
		(width 0.127)
		(layer "In7.Cu")
		(net "FT4232_FPGA_TDO")
	)
	(segment
		(start 138.938 -79.502)
		(end 140.544296 -77.895704)
		(width 0.127)
		(layer "In7.Cu")
		(net "FT4232_FPGA_TDO")
	)
	(segment
		(start 143.259556 -76.120244)
		(end 143.259556 -75.940412)
		(width 0.127)
		(layer "In7.Cu")
		(net "FT4232_FPGA_TDO")
	)
	(segment
		(start 144.1577 -75.042268)
		(end 143.867632 -74.7522)
		(width 0.127)
		(layer "In7.Cu")
		(net "FT4232_FPGA_TDO")
	)
	(segment
		(start 140.544296 -77.895704)
		(end 140.724128 -77.895704)
		(width 0.127)
		(layer "In7.Cu")
		(net "FT4232_FPGA_TDO")
	)
	(segment
		(start 106.426 -94.869)
		(end 107.7595 -96.2025)
		(width 0.127)
		(layer "In7.Cu")
		(net "FT4232_FPGA_TDO")
	)
	(segment
		(start 116.057934 -96.3295)
		(end 117.997732 -94.389702)
		(width 0.127)
		(layer "In7.Cu")
		(net "FT4232_FPGA_TDO")
	)
	(segment
		(start 143.867632 -74.572368)
		(end 144.399 -74.041)
		(width 0.127)
		(layer "In7.Cu")
		(net "FT4232_FPGA_TDO")
	)
	(segment
		(start 147.2946 -69.1134)
		(end 147.6756 -69.1134)
		(width 0.127)
		(layer "In7.Cu")
		(net "FT4232_FPGA_TDO")
	)
	(segment
		(start 142.969488 -75.470512)
		(end 143.238728 -75.201272)
		(width 0.127)
		(layer "In7.Cu")
		(net "FT4232_FPGA_TDO")
	)
	(segment
		(start 141.463268 -77.7367)
		(end 141.1732 -77.446632)
		(width 0.127)
		(layer "In7.Cu")
		(net "FT4232_FPGA_TDO")
	)
	(segment
		(start 141.91234 -77.287628)
		(end 142.092172 -77.287628)
		(width 0.127)
		(layer "In7.Cu")
		(net "FT4232_FPGA_TDO")
	)
	(segment
		(start 142.520416 -76.099416)
		(end 142.810484 -76.389484)
		(width 0.127)
		(layer "In7.Cu")
		(net "FT4232_FPGA_TDO")
	)
	(segment
		(start 142.361412 -77.018388)
		(end 142.361412 -76.838556)
		(width 0.127)
		(layer "In7.Cu")
		(net "FT4232_FPGA_TDO")
	)
	(segment
		(start 143.259556 -75.940412)
		(end 142.969488 -75.650344)
		(width 0.127)
		(layer "In7.Cu")
		(net "FT4232_FPGA_TDO")
	)
	(segment
		(start 140.724128 -77.895704)
		(end 141.014196 -78.185772)
		(width 0.127)
		(layer "In7.Cu")
		(net "FT4232_FPGA_TDO")
	)
	(segment
		(start 111.933482 -96.901)
		(end 114.380518 -96.901)
		(width 0.127)
		(layer "In7.Cu")
		(net "FT4232_FPGA_TDO")
	)
	(segment
		(start 133.604 -79.502)
		(end 138.938 -79.502)
		(width 0.127)
		(layer "In7.Cu")
		(net "FT4232_FPGA_TDO")
	)
	(segment
		(start 117.997732 -94.389702)
		(end 117.998494 -94.389448)
		(width 0.127)
		(layer "In7.Cu")
		(net "FT4232_FPGA_TDO")
	)
	(segment
		(start 144.1577 -75.2221)
		(end 144.1577 -75.042268)
		(width 0.127)
		(layer "In7.Cu")
		(net "FT4232_FPGA_TDO")
	)
	(segment
		(start 114.952018 -96.3295)
		(end 116.057934 -96.3295)
		(width 0.127)
		(layer "In7.Cu")
		(net "FT4232_FPGA_TDO")
	)
	(segment
		(start 142.340584 -76.099416)
		(end 142.520416 -76.099416)
		(width 0.127)
		(layer "In7.Cu")
		(net "FT4232_FPGA_TDO")
	)
	(segment
		(start 132.5372 -87.892128)
		(end 132.5372 -80.5688)
		(width 0.127)
		(layer "In7.Cu")
		(net "FT4232_FPGA_TDO")
	)
	(segment
		(start 141.1732 -77.2668)
		(end 141.44244 -76.99756)
		(width 0.127)
		(layer "In7.Cu")
		(net "FT4232_FPGA_TDO")
	)
	(segment
		(start 142.071344 -76.548488)
		(end 142.071344 -76.368656)
		(width 0.127)
		(layer "In7.Cu")
		(net "FT4232_FPGA_TDO")
	)
	(segment
		(start 144.399 -74.041)
		(end 144.399 -72.009)
		(width 0.127)
		(layer "In7.Cu")
		(net "FT4232_FPGA_TDO")
	)
	(segment
		(start 143.41856 -75.201272)
		(end 143.708628 -75.49134)
		(width 0.127)
		(layer "In7.Cu")
		(net "FT4232_FPGA_TDO")
	)
	(segment
		(start 107.7595 -96.2025)
		(end 111.234982 -96.2025)
		(width 0.127)
		(layer "In7.Cu")
		(net "FT4232_FPGA_TDO")
	)
	(segment
		(start 141.44244 -76.99756)
		(end 141.622272 -76.99756)
		(width 0.127)
		(layer "In7.Cu")
		(net "FT4232_FPGA_TDO")
	)
	(segment
		(start 142.092172 -77.287628)
		(end 142.361412 -77.018388)
		(width 0.127)
		(layer "In7.Cu")
		(net "FT4232_FPGA_TDO")
	)
	(segment
		(start 143.238728 -75.201272)
		(end 143.41856 -75.201272)
		(width 0.127)
		(layer "In7.Cu")
		(net "FT4232_FPGA_TDO")
	)
	(segment
		(start 111.234982 -96.2025)
		(end 111.933482 -96.901)
		(width 0.127)
		(layer "In7.Cu")
		(net "FT4232_FPGA_TDO")
	)
	(segment
		(start 141.1732 -77.446632)
		(end 141.1732 -77.2668)
		(width 0.127)
		(layer "In7.Cu")
		(net "FT4232_FPGA_TDO")
	)
	(segment
		(start 143.867632 -74.7522)
		(end 143.867632 -74.572368)
		(width 0.127)
		(layer "In7.Cu")
		(net "FT4232_FPGA_TDO")
	)
	(segment
		(start 145.048224 -76.7334)
		(end 147.701 -76.7334)
		(width 0.11938)
		(layer "F.Cu")
		(net "FT4232_FPGA_TDI")
	)
	(segment
		(start 98.933 -93.599)
		(end 99.515168 -93.016832)
		(width 0.11938)
		(layer "F.Cu")
		(net "FT4232_FPGA_TDI")
	)
	(segment
		(start 98.933 -93.98)
		(end 98.933 -93.599)
		(width 0.11938)
		(layer "F.Cu")
		(net "FT4232_FPGA_TDI")
	)
	(segment
		(start 100.352352 -93.016832)
		(end 100.3554 -93.01988)
		(width 0.11938)
		(layer "F.Cu")
		(net "FT4232_FPGA_TDI")
	)
	(segment
		(start 99.515168 -93.016832)
		(end 100.352352 -93.016832)
		(width 0.11938)
		(layer "F.Cu")
		(net "FT4232_FPGA_TDI")
	)
	(segment
		(start 100.3554 -93.01988)
		(end 102.5017 -93.01988)
		(width 0.11938)
		(layer "F.Cu")
		(net "FT4232_FPGA_TDI")
	)
	(via
		(at 98.933 -93.98)
		(size 0.508)
		(drill 0.254)
		(layers "F.Cu" "B.Cu")
		(net "FT4232_FPGA_TDI")
	)
	(via
		(at 147.701 -76.7334)
		(size 0.4572)
		(drill 0.2032)
		(layers "F.Cu" "B.Cu")
		(net "FT4232_FPGA_TDI")
	)
	(segment
		(start 144.0307 -76.4413)
		(end 144.0307 -77.4827)
		(width 0.11938)
		(layer "B.Cu")
		(net "FT4232_FPGA_TDI")
	)
	(segment
		(start 144.0307 -77.4827)
		(end 144.2974 -77.7494)
		(width 0.11938)
		(layer "B.Cu")
		(net "FT4232_FPGA_TDI")
	)
	(segment
		(start 142.2908 -76.6826)
		(end 142.5321 -76.4413)
		(width 0.11938)
		(layer "B.Cu")
		(net "FT4232_FPGA_TDI")
	)
	(segment
		(start 146.685 -77.7494)
		(end 147.701 -76.7334)
		(width 0.11938)
		(layer "B.Cu")
		(net "FT4232_FPGA_TDI")
	)
	(segment
		(start 144.2974 -77.7494)
		(end 146.685 -77.7494)
		(width 0.11938)
		(layer "B.Cu")
		(net "FT4232_FPGA_TDI")
	)
	(segment
		(start 142.5321 -76.4413)
		(end 144.0307 -76.4413)
		(width 0.11938)
		(layer "B.Cu")
		(net "FT4232_FPGA_TDI")
	)
	(segment
		(start 141.537944 -76.708)
		(end 141.563344 -76.6826)
		(width 0.11938)
		(layer "B.Cu")
		(net "FT4232_FPGA_TDI")
	)
	(segment
		(start 141.563344 -76.6826)
		(end 142.2908 -76.6826)
		(width 0.11938)
		(layer "B.Cu")
		(net "FT4232_FPGA_TDI")
	)
	(segment
		(start 140.8684 -76.708)
		(end 141.537944 -76.708)
		(width 0.11938)
		(layer "B.Cu")
		(net "FT4232_FPGA_TDI")
	)
	(segment
		(start 144.018 -86.89594)
		(end 144.018 -79.502)
		(width 0.127)
		(layer "In7.Cu")
		(net "FT4232_FPGA_TDI")
	)
	(segment
		(start 146.7866 -76.7334)
		(end 147.701 -76.7334)
		(width 0.127)
		(layer "In7.Cu")
		(net "FT4232_FPGA_TDI")
	)
	(segment
		(start 144.018 -79.502)
		(end 146.7866 -76.7334)
		(width 0.127)
		(layer "In7.Cu")
		(net "FT4232_FPGA_TDI")
	)
	(segment
		(start 142.01394 -88.9)
		(end 144.018 -86.89594)
		(width 0.127)
		(layer "In7.Cu")
		(net "FT4232_FPGA_TDI")
	)
	(segment
		(start 126.23546 -95.631)
		(end 132.96646 -88.9)
		(width 0.127)
		(layer "In7.Cu")
		(net "FT4232_FPGA_TDI")
	)
	(segment
		(start 98.933 -93.98)
		(end 98.933 -94.107)
		(width 0.127)
		(layer "In7.Cu")
		(net "FT4232_FPGA_TDI")
	)
	(segment
		(start 132.96646 -88.9)
		(end 142.01394 -88.9)
		(width 0.127)
		(layer "In7.Cu")
		(net "FT4232_FPGA_TDI")
	)
	(segment
		(start 100.457 -95.631)
		(end 104.775 -95.631)
		(width 0.127)
		(layer "In7.Cu")
		(net "FT4232_FPGA_TDI")
	)
	(segment
		(start 118.364 -95.631)
		(end 126.23546 -95.631)
		(width 0.127)
		(layer "In7.Cu")
		(net "FT4232_FPGA_TDI")
	)
	(segment
		(start 104.775 -95.631)
		(end 108.077 -98.933)
		(width 0.127)
		(layer "In7.Cu")
		(net "FT4232_FPGA_TDI")
	)
	(segment
		(start 98.933 -94.107)
		(end 100.457 -95.631)
		(width 0.127)
		(layer "In7.Cu")
		(net "FT4232_FPGA_TDI")
	)
	(segment
		(start 108.077 -98.933)
		(end 115.062 -98.933)
		(width 0.127)
		(layer "In7.Cu")
		(net "FT4232_FPGA_TDI")
	)
	(segment
		(start 115.062 -98.933)
		(end 118.364 -95.631)
		(width 0.127)
		(layer "In7.Cu")
		(net "FT4232_FPGA_TDI")
	)
	(segment
		(start 145.048224 -66.5734)
		(end 147.6756 -66.5734)
		(width 0.11938)
		(layer "F.Cu")
		(net "FT4232_FPGA_TCK")
	)
	(segment
		(start 104.521 -94.869)
		(end 104.419908 -94.970092)
		(width 0.11938)
		(layer "F.Cu")
		(net "FT4232_FPGA_TCK")
	)
	(segment
		(start 105.029 -94.869)
		(end 104.521 -94.869)
		(width 0.11938)
		(layer "F.Cu")
		(net "FT4232_FPGA_TCK")
	)
	(segment
		(start 104.419908 -94.970092)
		(end 102.5017 -94.970092)
		(width 0.11938)
		(layer "F.Cu")
		(net "FT4232_FPGA_TCK")
	)
	(via
		(at 147.6756 -66.5734)
		(size 0.4572)
		(drill 0.2032)
		(layers "F.Cu" "B.Cu")
		(net "FT4232_FPGA_TCK")
	)
	(via
		(at 105.029 -94.869)
		(size 0.508)
		(drill 0.254)
		(layers "F.Cu" "B.Cu")
		(net "FT4232_FPGA_TCK")
	)
	(segment
		(start 146.939 -65.278)
		(end 144.6784 -65.278)
		(width 0.11938)
		(layer "B.Cu")
		(net "FT4232_FPGA_TCK")
	)
	(segment
		(start 141.537944 -67.056)
		(end 140.8684 -67.056)
		(width 0.11938)
		(layer "B.Cu")
		(net "FT4232_FPGA_TCK")
	)
	(segment
		(start 144.1577 -66.9925)
		(end 141.601444 -66.9925)
		(width 0.11938)
		(layer "B.Cu")
		(net "FT4232_FPGA_TCK")
	)
	(segment
		(start 144.6784 -65.278)
		(end 144.1577 -65.7987)
		(width 0.11938)
		(layer "B.Cu")
		(net "FT4232_FPGA_TCK")
	)
	(segment
		(start 144.1577 -65.7987)
		(end 144.1577 -66.9925)
		(width 0.11938)
		(layer "B.Cu")
		(net "FT4232_FPGA_TCK")
	)
	(segment
		(start 147.6756 -66.5734)
		(end 147.6756 -66.0146)
		(width 0.11938)
		(layer "B.Cu")
		(net "FT4232_FPGA_TCK")
	)
	(segment
		(start 141.601444 -66.9925)
		(end 141.537944 -67.056)
		(width 0.11938)
		(layer "B.Cu")
		(net "FT4232_FPGA_TCK")
	)
	(segment
		(start 147.6756 -66.0146)
		(end 146.939 -65.278)
		(width 0.11938)
		(layer "B.Cu")
		(net "FT4232_FPGA_TCK")
	)
	(segment
		(start 108.1405 -95.6945)
		(end 115.974114 -95.6945)
		(width 0.127)
		(layer "In7.Cu")
		(net "FT4232_FPGA_TCK")
	)
	(segment
		(start 116.714016 -93.395292)
		(end 116.983764 -93.125544)
		(width 0.127)
		(layer "In7.Cu")
		(net "FT4232_FPGA_TCK")
	)
	(segment
		(start 116.264944 -94.023688)
		(end 116.8654 -94.62389)
		(width 0.127)
		(layer "In7.Cu")
		(net "FT4232_FPGA_TCK")
	)
	(segment
		(start 106.68 -94.234)
		(end 108.1405 -95.6945)
		(width 0.127)
		(layer "In7.Cu")
		(net "FT4232_FPGA_TCK")
	)
	(segment
		(start 118.371366 -93.297248)
		(end 119.723662 -93.297248)
		(width 0.127)
		(layer "In7.Cu")
		(net "FT4232_FPGA_TCK")
	)
	(segment
		(start 138.557 -78.994)
		(end 143.891 -73.66)
		(width 0.127)
		(layer "In7.Cu")
		(net "FT4232_FPGA_TCK")
	)
	(segment
		(start 119.723662 -93.297248)
		(end 120.261888 -93.835474)
		(width 0.127)
		(layer "In7.Cu")
		(net "FT4232_FPGA_TCK")
	)
	(segment
		(start 147.066 -67.183)
		(end 147.6756 -66.5734)
		(width 0.127)
		(layer "In7.Cu")
		(net "FT4232_FPGA_TCK")
	)
	(segment
		(start 105.029 -94.869)
		(end 105.664 -94.234)
		(width 0.127)
		(layer "In7.Cu")
		(net "FT4232_FPGA_TCK")
	)
	(segment
		(start 115.815872 -94.293436)
		(end 116.08562 -94.023688)
		(width 0.127)
		(layer "In7.Cu")
		(net "FT4232_FPGA_TCK")
	)
	(segment
		(start 133.263386 -78.994)
		(end 138.557 -78.994)
		(width 0.127)
		(layer "In7.Cu")
		(net "FT4232_FPGA_TCK")
	)
	(segment
		(start 115.815872 -94.47276)
		(end 115.815872 -94.293436)
		(width 0.127)
		(layer "In7.Cu")
		(net "FT4232_FPGA_TCK")
	)
	(segment
		(start 147.066 -68.326)
		(end 147.066 -67.183)
		(width 0.127)
		(layer "In7.Cu")
		(net "FT4232_FPGA_TCK")
	)
	(segment
		(start 143.891 -71.501)
		(end 147.066 -68.326)
		(width 0.127)
		(layer "In7.Cu")
		(net "FT4232_FPGA_TCK")
	)
	(segment
		(start 120.261888 -93.835474)
		(end 125.875288 -93.835474)
		(width 0.127)
		(layer "In7.Cu")
		(net "FT4232_FPGA_TCK")
	)
	(segment
		(start 117.044724 -94.62389)
		(end 117.314472 -94.354142)
		(width 0.127)
		(layer "In7.Cu")
		(net "FT4232_FPGA_TCK")
	)
	(segment
		(start 117.314472 -94.174818)
		(end 116.714016 -93.574616)
		(width 0.127)
		(layer "In7.Cu")
		(net "FT4232_FPGA_TCK")
	)
	(segment
		(start 116.983764 -93.125544)
		(end 117.163088 -93.125544)
		(width 0.127)
		(layer "In7.Cu")
		(net "FT4232_FPGA_TCK")
	)
	(segment
		(start 116.8654 -94.62389)
		(end 117.044724 -94.62389)
		(width 0.127)
		(layer "In7.Cu")
		(net "FT4232_FPGA_TCK")
	)
	(segment
		(start 116.714016 -93.574616)
		(end 116.714016 -93.395292)
		(width 0.127)
		(layer "In7.Cu")
		(net "FT4232_FPGA_TCK")
	)
	(segment
		(start 117.942868 -93.725746)
		(end 118.371366 -93.297248)
		(width 0.127)
		(layer "In7.Cu")
		(net "FT4232_FPGA_TCK")
	)
	(segment
		(start 143.891 -73.66)
		(end 143.891 -71.501)
		(width 0.127)
		(layer "In7.Cu")
		(net "FT4232_FPGA_TCK")
	)
	(segment
		(start 132.0292 -80.228186)
		(end 133.263386 -78.994)
		(width 0.127)
		(layer "In7.Cu")
		(net "FT4232_FPGA_TCK")
	)
	(segment
		(start 116.08562 -94.023688)
		(end 116.264944 -94.023688)
		(width 0.127)
		(layer "In7.Cu")
		(net "FT4232_FPGA_TCK")
	)
	(segment
		(start 105.664 -94.234)
		(end 106.68 -94.234)
		(width 0.127)
		(layer "In7.Cu")
		(net "FT4232_FPGA_TCK")
	)
	(segment
		(start 125.875288 -93.835474)
		(end 132.0292 -87.681562)
		(width 0.127)
		(layer "In7.Cu")
		(net "FT4232_FPGA_TCK")
	)
	(segment
		(start 132.0292 -87.681562)
		(end 132.0292 -80.228186)
		(width 0.127)
		(layer "In7.Cu")
		(net "FT4232_FPGA_TCK")
	)
	(segment
		(start 117.163088 -93.125544)
		(end 117.763544 -93.725746)
		(width 0.127)
		(layer "In7.Cu")
		(net "FT4232_FPGA_TCK")
	)
	(segment
		(start 116.416328 -95.072962)
		(end 115.815872 -94.47276)
		(width 0.127)
		(layer "In7.Cu")
		(net "FT4232_FPGA_TCK")
	)
	(segment
		(start 117.314472 -94.354142)
		(end 117.314472 -94.174818)
		(width 0.127)
		(layer "In7.Cu")
		(net "FT4232_FPGA_TCK")
	)
	(segment
		(start 117.763544 -93.725746)
		(end 117.942868 -93.725746)
		(width 0.127)
		(layer "In7.Cu")
		(net "FT4232_FPGA_TCK")
	)
	(segment
		(start 116.416328 -95.252286)
		(end 116.416328 -95.072962)
		(width 0.127)
		(layer "In7.Cu")
		(net "FT4232_FPGA_TCK")
	)
	(segment
		(start 115.974114 -95.6945)
		(end 116.416328 -95.252286)
		(width 0.127)
		(layer "In7.Cu")
		(net "FT4232_FPGA_TCK")
	)
	(segment
		(start 160.782 -66.675)
		(end 160.782 -67.818)
		(width 0.11938)
		(layer "F.Cu")
		(net "FT4232_CHD_TX")
	)
	(segment
		(start 158.078424 -66.421)
		(end 160.528 -66.421)
		(width 0.11938)
		(layer "F.Cu")
		(net "FT4232_CHD_TX")
	)
	(segment
		(start 160.66262 -68.961)
		(end 158.078424 -68.961)
		(width 0.11938)
		(layer "F.Cu")
		(net "FT4232_CHD_TX")
	)
	(segment
		(start 160.528 -66.421)
		(end 160.782 -66.675)
		(width 0.11938)
		(layer "F.Cu")
		(net "FT4232_CHD_TX")
	)
	(segment
		(start 160.782 -67.818)
		(end 160.782 -68.84162)
		(width 0.11938)
		(layer "F.Cu")
		(net "FT4232_CHD_TX")
	)
	(segment
		(start 160.782 -68.84162)
		(end 160.66262 -68.961)
		(width 0.11938)
		(layer "F.Cu")
		(net "FT4232_CHD_TX")
	)
	(via
		(at 34.29 -79.248)
		(size 0.508)
		(drill 0.254)
		(layers "F.Cu" "B.Cu")
		(net "FT4232_CHD_TX")
	)
	(via
		(at 128.143 -86.487)
		(size 0.508)
		(drill 0.254)
		(layers "F.Cu" "B.Cu")
		(net "FT4232_CHD_TX")
	)
	(via
		(at 58.42 -88.265)
		(size 0.508)
		(drill 0.254)
		(layers "F.Cu" "B.Cu")
		(net "FT4232_CHD_TX")
	)
	(via
		(at 160.782 -67.818)
		(size 0.4572)
		(drill 0.2032)
		(layers "F.Cu" "B.Cu")
		(net "FT4232_CHD_TX")
	)
	(segment
		(start 33.6296 -78.5876)
		(end 32.512 -78.5876)
		(width 0.11938)
		(layer "B.Cu")
		(net "FT4232_CHD_TX")
	)
	(segment
		(start 34.29 -79.248)
		(end 33.6296 -78.5876)
		(width 0.11938)
		(layer "B.Cu")
		(net "FT4232_CHD_TX")
	)
	(segment
		(start 34.8615 -81.4705)
		(end 34.8615 -84.6455)
		(width 0.127)
		(layer "In2.Cu")
		(net "FT4232_CHD_TX")
	)
	(segment
		(start 53.056282 -90.043)
		(end 56.642 -90.043)
		(width 0.127)
		(layer "In2.Cu")
		(net "FT4232_CHD_TX")
	)
	(segment
		(start 56.642 -90.043)
		(end 58.42 -88.265)
		(width 0.127)
		(layer "In2.Cu")
		(net "FT4232_CHD_TX")
	)
	(segment
		(start 155.194 -78.232)
		(end 149.479 -78.232)
		(width 0.127)
		(layer "In2.Cu")
		(net "FT4232_CHD_TX")
	)
	(segment
		(start 34.29 -80.899)
		(end 34.8615 -81.4705)
		(width 0.127)
		(layer "In2.Cu")
		(net "FT4232_CHD_TX")
	)
	(segment
		(start 37.16782 -85.852)
		(end 38.06952 -86.7537)
		(width 0.127)
		(layer "In2.Cu")
		(net "FT4232_CHD_TX")
	)
	(segment
		(start 52.306982 -89.2937)
		(end 53.056282 -90.043)
		(width 0.127)
		(layer "In2.Cu")
		(net "FT4232_CHD_TX")
	)
	(segment
		(start 158.877 -74.549)
		(end 155.194 -78.232)
		(width 0.127)
		(layer "In2.Cu")
		(net "FT4232_CHD_TX")
	)
	(segment
		(start 158.877 -68.326)
		(end 158.877 -74.549)
		(width 0.127)
		(layer "In2.Cu")
		(net "FT4232_CHD_TX")
	)
	(segment
		(start 50.00752 -89.2937)
		(end 52.306982 -89.2937)
		(width 0.127)
		(layer "In2.Cu")
		(net "FT4232_CHD_TX")
	)
	(segment
		(start 42.578782 -86.7537)
		(end 44.852082 -89.027)
		(width 0.127)
		(layer "In2.Cu")
		(net "FT4232_CHD_TX")
	)
	(segment
		(start 159.385 -67.818)
		(end 158.877 -68.326)
		(width 0.127)
		(layer "In2.Cu")
		(net "FT4232_CHD_TX")
	)
	(segment
		(start 44.852082 -89.027)
		(end 49.74082 -89.027)
		(width 0.127)
		(layer "In2.Cu")
		(net "FT4232_CHD_TX")
	)
	(segment
		(start 148.082 -79.629)
		(end 133.136132 -79.629)
		(width 0.127)
		(layer "In2.Cu")
		(net "FT4232_CHD_TX")
	)
	(segment
		(start 133.136132 -79.629)
		(end 130.302 -82.463132)
		(width 0.127)
		(layer "In2.Cu")
		(net "FT4232_CHD_TX")
	)
	(segment
		(start 149.479 -78.232)
		(end 148.082 -79.629)
		(width 0.127)
		(layer "In2.Cu")
		(net "FT4232_CHD_TX")
	)
	(segment
		(start 38.06952 -86.7537)
		(end 42.578782 -86.7537)
		(width 0.127)
		(layer "In2.Cu")
		(net "FT4232_CHD_TX")
	)
	(segment
		(start 34.29 -79.248)
		(end 34.29 -80.899)
		(width 0.127)
		(layer "In2.Cu")
		(net "FT4232_CHD_TX")
	)
	(segment
		(start 130.302 -82.463132)
		(end 130.302 -84.328)
		(width 0.127)
		(layer "In2.Cu")
		(net "FT4232_CHD_TX")
	)
	(segment
		(start 130.302 -84.328)
		(end 128.143 -86.487)
		(width 0.127)
		(layer "In2.Cu")
		(net "FT4232_CHD_TX")
	)
	(segment
		(start 36.068 -85.852)
		(end 37.16782 -85.852)
		(width 0.127)
		(layer "In2.Cu")
		(net "FT4232_CHD_TX")
	)
	(segment
		(start 49.74082 -89.027)
		(end 50.00752 -89.2937)
		(width 0.127)
		(layer "In2.Cu")
		(net "FT4232_CHD_TX")
	)
	(segment
		(start 160.782 -67.818)
		(end 159.385 -67.818)
		(width 0.127)
		(layer "In2.Cu")
		(net "FT4232_CHD_TX")
	)
	(segment
		(start 34.8615 -84.6455)
		(end 36.068 -85.852)
		(width 0.127)
		(layer "In2.Cu")
		(net "FT4232_CHD_TX")
	)
	(segment
		(start 113.665 -89.154)
		(end 111.76 -89.154)
		(width 0.127)
		(layer "In7.Cu")
		(net "FT4232_CHD_TX")
	)
	(segment
		(start 128.143 -86.487)
		(end 128.016 -86.487)
		(width 0.127)
		(layer "In7.Cu")
		(net "FT4232_CHD_TX")
	)
	(segment
		(start 108.966 -89.916)
		(end 108.966 -88.9)
		(width 0.127)
		(layer "In7.Cu")
		(net "FT4232_CHD_TX")
	)
	(segment
		(start 115.697 -87.122)
		(end 113.665 -89.154)
		(width 0.127)
		(layer "In7.Cu")
		(net "FT4232_CHD_TX")
	)
	(segment
		(start 109.4105 -90.3605)
		(end 108.966 -89.916)
		(width 0.127)
		(layer "In7.Cu")
		(net "FT4232_CHD_TX")
	)
	(segment
		(start 119.888 -87.122)
		(end 115.697 -87.122)
		(width 0.127)
		(layer "In7.Cu")
		(net "FT4232_CHD_TX")
	)
	(segment
		(start 89.705434 -88.392)
		(end 58.547 -88.392)
		(width 0.127)
		(layer "In7.Cu")
		(net "FT4232_CHD_TX")
	)
	(segment
		(start 97.409 -90.932)
		(end 92.245434 -90.932)
		(width 0.127)
		(layer "In7.Cu")
		(net "FT4232_CHD_TX")
	)
	(segment
		(start 125.984 -88.519)
		(end 121.285 -88.519)
		(width 0.127)
		(layer "In7.Cu")
		(net "FT4232_CHD_TX")
	)
	(segment
		(start 121.285 -88.519)
		(end 119.888 -87.122)
		(width 0.127)
		(layer "In7.Cu")
		(net "FT4232_CHD_TX")
	)
	(segment
		(start 111.76 -89.154)
		(end 110.5535 -90.3605)
		(width 0.127)
		(layer "In7.Cu")
		(net "FT4232_CHD_TX")
	)
	(segment
		(start 128.016 -86.487)
		(end 125.984 -88.519)
		(width 0.127)
		(layer "In7.Cu")
		(net "FT4232_CHD_TX")
	)
	(segment
		(start 100.203 -88.138)
		(end 97.409 -90.932)
		(width 0.127)
		(layer "In7.Cu")
		(net "FT4232_CHD_TX")
	)
	(segment
		(start 108.204 -88.138)
		(end 100.203 -88.138)
		(width 0.127)
		(layer "In7.Cu")
		(net "FT4232_CHD_TX")
	)
	(segment
		(start 58.547 -88.392)
		(end 58.42 -88.265)
		(width 0.127)
		(layer "In7.Cu")
		(net "FT4232_CHD_TX")
	)
	(segment
		(start 108.966 -88.9)
		(end 108.204 -88.138)
		(width 0.127)
		(layer "In7.Cu")
		(net "FT4232_CHD_TX")
	)
	(segment
		(start 110.5535 -90.3605)
		(end 109.4105 -90.3605)
		(width 0.127)
		(layer "In7.Cu")
		(net "FT4232_CHD_TX")
	)
	(segment
		(start 92.245434 -90.932)
		(end 89.705434 -88.392)
		(width 0.127)
		(layer "In7.Cu")
		(net "FT4232_CHD_TX")
	)
	(segment
		(start 160.782 -73.66)
		(end 160.401 -74.041)
		(width 0.11938)
		(layer "F.Cu")
		(net "FT4232_CHD_RX")
	)
	(segment
		(start 160.401 -74.041)
		(end 158.078424 -74.041)
		(width 0.11938)
		(layer "F.Cu")
		(net "FT4232_CHD_RX")
	)
	(segment
		(start 160.401 -71.501)
		(end 160.782 -71.882)
		(width 0.11938)
		(layer "F.Cu")
		(net "FT4232_CHD_RX")
	)
	(segment
		(start 158.078424 -71.501)
		(end 160.401 -71.501)
		(width 0.11938)
		(layer "F.Cu")
		(net "FT4232_CHD_RX")
	)
	(segment
		(start 160.782 -72.771)
		(end 160.782 -73.66)
		(width 0.11938)
		(layer "F.Cu")
		(net "FT4232_CHD_RX")
	)
	(segment
		(start 160.782 -71.882)
		(end 160.782 -72.771)
		(width 0.11938)
		(layer "F.Cu")
		(net "FT4232_CHD_RX")
	)
	(via
		(at 57.277 -88.265)
		(size 0.508)
		(drill 0.254)
		(layers "F.Cu" "B.Cu")
		(net "FT4232_CHD_RX")
	)
	(via
		(at 129.286 -86.487)
		(size 0.508)
		(drill 0.254)
		(layers "F.Cu" "B.Cu")
		(net "FT4232_CHD_RX")
	)
	(via
		(at 160.782 -72.771)
		(size 0.508)
		(drill 0.254)
		(layers "F.Cu" "B.Cu")
		(net "FT4232_CHD_RX")
	)
	(via
		(at 37.084 -84.836)
		(size 0.508)
		(drill 0.254)
		(layers "F.Cu" "B.Cu")
		(net "FT4232_CHD_RX")
	)
	(segment
		(start 35.56 -83.312)
		(end 35.0774 -83.312)
		(width 0.11938)
		(layer "B.Cu")
		(net "FT4232_CHD_RX")
	)
	(segment
		(start 37.084 -84.836)
		(end 35.56 -83.312)
		(width 0.11938)
		(layer "B.Cu")
		(net "FT4232_CHD_RX")
	)
	(segment
		(start 47.272956 -88.0237)
		(end 47.145956 -87.8967)
		(width 0.127)
		(layer "In2.Cu")
		(net "FT4232_CHD_RX")
	)
	(segment
		(start 39.172642 -85.4837)
		(end 39.045642 -85.6107)
		(width 0.127)
		(layer "In2.Cu")
		(net "FT4232_CHD_RX")
	)
	(segment
		(start 48.415956 -87.503)
		(end 48.288956 -87.376)
		(width 0.127)
		(layer "In2.Cu")
		(net "FT4232_CHD_RX")
	)
	(segment
		(start 46.510956 -87.503)
		(end 46.510956 -87.8967)
		(width 0.127)
		(layer "In2.Cu")
		(net "FT4232_CHD_RX")
	)
	(segment
		(start 39.045642 -85.6107)
		(end 39.045642 -86.106)
		(width 0.127)
		(layer "In2.Cu")
		(net "FT4232_CHD_RX")
	)
	(segment
		(start 39.045642 -86.106)
		(end 38.918642 -86.233)
		(width 0.127)
		(layer "In2.Cu")
		(net "FT4232_CHD_RX")
	)
	(segment
		(start 50.320956 -87.8967)
		(end 50.193956 -88.0237)
		(width 0.127)
		(layer "In2.Cu")
		(net "FT4232_CHD_RX")
	)
	(segment
		(start 49.558956 -87.376)
		(end 49.177956 -87.376)
		(width 0.127)
		(layer "In2.Cu")
		(net "FT4232_CHD_RX")
	)
	(segment
		(start 39.807642 -86.233)
		(end 39.680642 -86.106)
		(width 0.127)
		(layer "In2.Cu")
		(net "FT4232_CHD_RX")
	)
	(segment
		(start 46.383956 -88.0237)
		(end 45.118782 -88.0237)
		(width 0.127)
		(layer "In2.Cu")
		(net "FT4232_CHD_RX")
	)
	(segment
		(start 133.346698 -80.137)
		(end 130.81 -82.673698)
		(width 0.127)
		(layer "In2.Cu")
		(net "FT4232_CHD_RX")
	)
	(segment
		(start 40.188642 -86.233)
		(end 39.807642 -86.233)
		(width 0.127)
		(layer "In2.Cu")
		(net "FT4232_CHD_RX")
	)
	(segment
		(start 38.410642 -85.6107)
		(end 38.283642 -85.4837)
		(width 0.127)
		(layer "In2.Cu")
		(net "FT4232_CHD_RX")
	)
	(segment
		(start 39.680642 -85.6107)
		(end 39.553642 -85.4837)
		(width 0.127)
		(layer "In2.Cu")
		(net "FT4232_CHD_RX")
	)
	(segment
		(start 47.145956 -87.8967)
		(end 47.145956 -87.503)
		(width 0.127)
		(layer "In2.Cu")
		(net "FT4232_CHD_RX")
	)
	(segment
		(start 47.780956 -87.503)
		(end 47.780956 -87.8967)
		(width 0.127)
		(layer "In2.Cu")
		(net "FT4232_CHD_RX")
	)
	(segment
		(start 50.828956 -87.376)
		(end 50.447956 -87.376)
		(width 0.127)
		(layer "In2.Cu")
		(net "FT4232_CHD_RX")
	)
	(segment
		(start 38.283642 -85.4837)
		(end 37.7317 -85.4837)
		(width 0.127)
		(layer "In2.Cu")
		(net "FT4232_CHD_RX")
	)
	(segment
		(start 47.653956 -88.0237)
		(end 47.272956 -88.0237)
		(width 0.127)
		(layer "In2.Cu")
		(net "FT4232_CHD_RX")
	)
	(segment
		(start 56.261 -89.281)
		(end 53.564282 -89.281)
		(width 0.127)
		(layer "In2.Cu")
		(net "FT4232_CHD_RX")
	)
	(segment
		(start 49.177956 -87.376)
		(end 49.050956 -87.503)
		(width 0.127)
		(layer "In2.Cu")
		(net "FT4232_CHD_RX")
	)
	(segment
		(start 40.442642 -85.4837)
		(end 40.315642 -85.6107)
		(width 0.127)
		(layer "In2.Cu")
		(net "FT4232_CHD_RX")
	)
	(segment
		(start 48.415956 -87.8967)
		(end 48.415956 -87.503)
		(width 0.127)
		(layer "In2.Cu")
		(net "FT4232_CHD_RX")
	)
	(segment
		(start 37.7317 -85.4837)
		(end 37.084 -84.836)
		(width 0.127)
		(layer "In2.Cu")
		(net "FT4232_CHD_RX")
	)
	(segment
		(start 57.277 -88.265)
		(end 56.261 -89.281)
		(width 0.127)
		(layer "In2.Cu")
		(net "FT4232_CHD_RX")
	)
	(segment
		(start 160.782 -73.66)
		(end 155.491688 -78.950312)
		(width 0.127)
		(layer "In2.Cu")
		(net "FT4232_CHD_RX")
	)
	(segment
		(start 40.315642 -85.6107)
		(end 40.315642 -86.106)
		(width 0.127)
		(layer "In2.Cu")
		(net "FT4232_CHD_RX")
	)
	(segment
		(start 50.193956 -88.0237)
		(end 49.812956 -88.0237)
		(width 0.127)
		(layer "In2.Cu")
		(net "FT4232_CHD_RX")
	)
	(segment
		(start 47.018956 -87.376)
		(end 46.637956 -87.376)
		(width 0.127)
		(layer "In2.Cu")
		(net "FT4232_CHD_RX")
	)
	(segment
		(start 53.564282 -89.281)
		(end 52.306982 -88.0237)
		(width 0.127)
		(layer "In2.Cu")
		(net "FT4232_CHD_RX")
	)
	(segment
		(start 50.955956 -87.8967)
		(end 50.955956 -87.503)
		(width 0.127)
		(layer "In2.Cu")
		(net "FT4232_CHD_RX")
	)
	(segment
		(start 48.288956 -87.376)
		(end 47.907956 -87.376)
		(width 0.127)
		(layer "In2.Cu")
		(net "FT4232_CHD_RX")
	)
	(segment
		(start 48.542956 -88.0237)
		(end 48.415956 -87.8967)
		(width 0.127)
		(layer "In2.Cu")
		(net "FT4232_CHD_RX")
	)
	(segment
		(start 46.510956 -87.8967)
		(end 46.383956 -88.0237)
		(width 0.127)
		(layer "In2.Cu")
		(net "FT4232_CHD_RX")
	)
	(segment
		(start 49.685956 -87.503)
		(end 49.558956 -87.376)
		(width 0.127)
		(layer "In2.Cu")
		(net "FT4232_CHD_RX")
	)
	(segment
		(start 48.923956 -88.0237)
		(end 48.542956 -88.0237)
		(width 0.127)
		(layer "In2.Cu")
		(net "FT4232_CHD_RX")
	)
	(segment
		(start 160.782 -72.771)
		(end 160.782 -73.66)
		(width 0.127)
		(layer "In2.Cu")
		(net "FT4232_CHD_RX")
	)
	(segment
		(start 39.680642 -86.106)
		(end 39.680642 -85.6107)
		(width 0.127)
		(layer "In2.Cu")
		(net "FT4232_CHD_RX")
	)
	(segment
		(start 148.59 -80.137)
		(end 133.346698 -80.137)
		(width 0.127)
		(layer "In2.Cu")
		(net "FT4232_CHD_RX")
	)
	(segment
		(start 52.306982 -88.0237)
		(end 51.082956 -88.0237)
		(width 0.127)
		(layer "In2.Cu")
		(net "FT4232_CHD_RX")
	)
	(segment
		(start 47.780956 -87.8967)
		(end 47.653956 -88.0237)
		(width 0.127)
		(layer "In2.Cu")
		(net "FT4232_CHD_RX")
	)
	(segment
		(start 38.410642 -86.106)
		(end 38.410642 -85.6107)
		(width 0.127)
		(layer "In2.Cu")
		(net "FT4232_CHD_RX")
	)
	(segment
		(start 38.537642 -86.233)
		(end 38.410642 -86.106)
		(width 0.127)
		(layer "In2.Cu")
		(net "FT4232_CHD_RX")
	)
	(segment
		(start 49.685956 -87.8967)
		(end 49.685956 -87.503)
		(width 0.127)
		(layer "In2.Cu")
		(net "FT4232_CHD_RX")
	)
	(segment
		(start 47.145956 -87.503)
		(end 47.018956 -87.376)
		(width 0.127)
		(layer "In2.Cu")
		(net "FT4232_CHD_RX")
	)
	(segment
		(start 149.776688 -78.950312)
		(end 148.59 -80.137)
		(width 0.127)
		(layer "In2.Cu")
		(net "FT4232_CHD_RX")
	)
	(segment
		(start 40.315642 -86.106)
		(end 40.188642 -86.233)
		(width 0.127)
		(layer "In2.Cu")
		(net "FT4232_CHD_RX")
	)
	(segment
		(start 49.050956 -87.503)
		(end 49.050956 -87.8967)
		(width 0.127)
		(layer "In2.Cu")
		(net "FT4232_CHD_RX")
	)
	(segment
		(start 45.118782 -88.0237)
		(end 42.578782 -85.4837)
		(width 0.127)
		(layer "In2.Cu")
		(net "FT4232_CHD_RX")
	)
	(segment
		(start 47.907956 -87.376)
		(end 47.780956 -87.503)
		(width 0.127)
		(layer "In2.Cu")
		(net "FT4232_CHD_RX")
	)
	(segment
		(start 42.578782 -85.4837)
		(end 40.442642 -85.4837)
		(width 0.127)
		(layer "In2.Cu")
		(net "FT4232_CHD_RX")
	)
	(segment
		(start 50.320956 -87.503)
		(end 50.320956 -87.8967)
		(width 0.127)
		(layer "In2.Cu")
		(net "FT4232_CHD_RX")
	)
	(segment
		(start 50.447956 -87.376)
		(end 50.320956 -87.503)
		(width 0.127)
		(layer "In2.Cu")
		(net "FT4232_CHD_RX")
	)
	(segment
		(start 49.050956 -87.8967)
		(end 48.923956 -88.0237)
		(width 0.127)
		(layer "In2.Cu")
		(net "FT4232_CHD_RX")
	)
	(segment
		(start 38.918642 -86.233)
		(end 38.537642 -86.233)
		(width 0.127)
		(layer "In2.Cu")
		(net "FT4232_CHD_RX")
	)
	(segment
		(start 51.082956 -88.0237)
		(end 50.955956 -87.8967)
		(width 0.127)
		(layer "In2.Cu")
		(net "FT4232_CHD_RX")
	)
	(segment
		(start 39.553642 -85.4837)
		(end 39.172642 -85.4837)
		(width 0.127)
		(layer "In2.Cu")
		(net "FT4232_CHD_RX")
	)
	(segment
		(start 130.81 -84.963)
		(end 129.286 -86.487)
		(width 0.127)
		(layer "In2.Cu")
		(net "FT4232_CHD_RX")
	)
	(segment
		(start 50.955956 -87.503)
		(end 50.828956 -87.376)
		(width 0.127)
		(layer "In2.Cu")
		(net "FT4232_CHD_RX")
	)
	(segment
		(start 155.491688 -78.950312)
		(end 149.776688 -78.950312)
		(width 0.127)
		(layer "In2.Cu")
		(net "FT4232_CHD_RX")
	)
	(segment
		(start 46.637956 -87.376)
		(end 46.510956 -87.503)
		(width 0.127)
		(layer "In2.Cu")
		(net "FT4232_CHD_RX")
	)
	(segment
		(start 49.812956 -88.0237)
		(end 49.685956 -87.8967)
		(width 0.127)
		(layer "In2.Cu")
		(net "FT4232_CHD_RX")
	)
	(segment
		(start 130.81 -82.673698)
		(end 130.81 -84.963)
		(width 0.127)
		(layer "In2.Cu")
		(net "FT4232_CHD_RX")
	)
	(segment
		(start 96.069912 -93.091)
		(end 95.942912 -93.218)
		(width 0.127)
		(layer "In7.Cu")
		(net "FT4232_CHD_RX")
	)
	(segment
		(start 95.561912 -93.218)
		(end 95.434912 -93.091)
		(width 0.127)
		(layer "In7.Cu")
		(net "FT4232_CHD_RX")
	)
	(segment
		(start 108.077 -89.408)
		(end 107.315 -88.646)
		(width 0.127)
		(layer "In7.Cu")
		(net "FT4232_CHD_RX")
	)
	(segment
		(start 128.163066 -87.0585)
		(end 126.194566 -89.027)
		(width 0.127)
		(layer "In7.Cu")
		(net "FT4232_CHD_RX")
	)
	(segment
		(start 93.391736 -91.44)
		(end 93.264736 -91.567)
		(width 0.127)
		(layer "In7.Cu")
		(net "FT4232_CHD_RX")
	)
	(segment
		(start 120.820434 -88.773)
		(end 114.808 -88.773)
		(width 0.127)
		(layer "In7.Cu")
		(net "FT4232_CHD_RX")
	)
	(segment
		(start 95.307912 -91.44)
		(end 94.926912 -91.44)
		(width 0.127)
		(layer "In7.Cu")
		(net "FT4232_CHD_RX")
	)
	(segment
		(start 96.196912 -91.44)
		(end 96.069912 -91.567)
		(width 0.127)
		(layer "In7.Cu")
		(net "FT4232_CHD_RX")
	)
	(segment
		(start 94.164912 -91.567)
		(end 94.037912 -91.44)
		(width 0.127)
		(layer "In7.Cu")
		(net "FT4232_CHD_RX")
	)
	(segment
		(start 112.141 -89.662)
		(end 110.9345 -90.8685)
		(width 0.127)
		(layer "In7.Cu")
		(net "FT4232_CHD_RX")
	)
	(segment
		(start 92.034868 -91.44)
		(end 89.525602 -88.930734)
		(width 0.127)
		(layer "In7.Cu")
		(net "FT4232_CHD_RX")
	)
	(segment
		(start 121.074434 -89.027)
		(end 120.820434 -88.773)
		(width 0.127)
		(layer "In7.Cu")
		(net "FT4232_CHD_RX")
	)
	(segment
		(start 93.264736 -91.567)
		(end 93.264736 -91.948)
		(width 0.127)
		(layer "In7.Cu")
		(net "FT4232_CHD_RX")
	)
	(segment
		(start 108.077 -89.789)
		(end 108.077 -89.408)
		(width 0.127)
		(layer "In7.Cu")
		(net "FT4232_CHD_RX")
	)
	(segment
		(start 100.457 -88.646)
		(end 97.663 -91.44)
		(width 0.127)
		(layer "In7.Cu")
		(net "FT4232_CHD_RX")
	)
	(segment
		(start 92.629736 -91.567)
		(end 92.502736 -91.44)
		(width 0.127)
		(layer "In7.Cu")
		(net "FT4232_CHD_RX")
	)
	(segment
		(start 94.799912 -93.091)
		(end 94.672912 -93.218)
		(width 0.127)
		(layer "In7.Cu")
		(net "FT4232_CHD_RX")
	)
	(segment
		(start 94.799912 -91.567)
		(end 94.799912 -93.091)
		(width 0.127)
		(layer "In7.Cu")
		(net "FT4232_CHD_RX")
	)
	(segment
		(start 95.434912 -93.091)
		(end 95.434912 -91.567)
		(width 0.127)
		(layer "In7.Cu")
		(net "FT4232_CHD_RX")
	)
	(segment
		(start 113.919 -89.662)
		(end 112.141 -89.662)
		(width 0.127)
		(layer "In7.Cu")
		(net "FT4232_CHD_RX")
	)
	(segment
		(start 92.756736 -92.075)
		(end 92.629736 -91.948)
		(width 0.127)
		(layer "In7.Cu")
		(net "FT4232_CHD_RX")
	)
	(segment
		(start 95.434912 -91.567)
		(end 95.307912 -91.44)
		(width 0.127)
		(layer "In7.Cu")
		(net "FT4232_CHD_RX")
	)
	(segment
		(start 97.663 -91.44)
		(end 96.196912 -91.44)
		(width 0.127)
		(layer "In7.Cu")
		(net "FT4232_CHD_RX")
	)
	(segment
		(start 96.069912 -91.567)
		(end 96.069912 -93.091)
		(width 0.127)
		(layer "In7.Cu")
		(net "FT4232_CHD_RX")
	)
	(segment
		(start 95.942912 -93.218)
		(end 95.561912 -93.218)
		(width 0.127)
		(layer "In7.Cu")
		(net "FT4232_CHD_RX")
	)
	(segment
		(start 107.315 -88.646)
		(end 100.457 -88.646)
		(width 0.127)
		(layer "In7.Cu")
		(net "FT4232_CHD_RX")
	)
	(segment
		(start 89.525602 -88.930734)
		(end 57.942734 -88.930734)
		(width 0.127)
		(layer "In7.Cu")
		(net "FT4232_CHD_RX")
	)
	(segment
		(start 109.1565 -90.8685)
		(end 108.077 -89.789)
		(width 0.127)
		(layer "In7.Cu")
		(net "FT4232_CHD_RX")
	)
	(segment
		(start 94.926912 -91.44)
		(end 94.799912 -91.567)
		(width 0.127)
		(layer "In7.Cu")
		(net "FT4232_CHD_RX")
	)
	(segment
		(start 93.137736 -92.075)
		(end 92.756736 -92.075)
		(width 0.127)
		(layer "In7.Cu")
		(net "FT4232_CHD_RX")
	)
	(segment
		(start 93.264736 -91.948)
		(end 93.137736 -92.075)
		(width 0.127)
		(layer "In7.Cu")
		(net "FT4232_CHD_RX")
	)
	(segment
		(start 94.291912 -93.218)
		(end 94.164912 -93.091)
		(width 0.127)
		(layer "In7.Cu")
		(net "FT4232_CHD_RX")
	)
	(segment
		(start 129.286 -86.487)
		(end 128.7145 -87.0585)
		(width 0.127)
		(layer "In7.Cu")
		(net "FT4232_CHD_RX")
	)
	(segment
		(start 94.164912 -93.091)
		(end 94.164912 -91.567)
		(width 0.127)
		(layer "In7.Cu")
		(net "FT4232_CHD_RX")
	)
	(segment
		(start 114.808 -88.773)
		(end 113.919 -89.662)
		(width 0.127)
		(layer "In7.Cu")
		(net "FT4232_CHD_RX")
	)
	(segment
		(start 110.9345 -90.8685)
		(end 109.1565 -90.8685)
		(width 0.127)
		(layer "In7.Cu")
		(net "FT4232_CHD_RX")
	)
	(segment
		(start 128.7145 -87.0585)
		(end 128.163066 -87.0585)
		(width 0.127)
		(layer "In7.Cu")
		(net "FT4232_CHD_RX")
	)
	(segment
		(start 57.942734 -88.930734)
		(end 57.277 -88.265)
		(width 0.127)
		(layer "In7.Cu")
		(net "FT4232_CHD_RX")
	)
	(segment
		(start 92.629736 -91.948)
		(end 92.629736 -91.567)
		(width 0.127)
		(layer "In7.Cu")
		(net "FT4232_CHD_RX")
	)
	(segment
		(start 94.672912 -93.218)
		(end 94.291912 -93.218)
		(width 0.127)
		(layer "In7.Cu")
		(net "FT4232_CHD_RX")
	)
	(segment
		(start 92.502736 -91.44)
		(end 92.034868 -91.44)
		(width 0.127)
		(layer "In7.Cu")
		(net "FT4232_CHD_RX")
	)
	(segment
		(start 94.037912 -91.44)
		(end 93.391736 -91.44)
		(width 0.127)
		(layer "In7.Cu")
		(net "FT4232_CHD_RX")
	)
	(segment
		(start 126.194566 -89.027)
		(end 121.074434 -89.027)
		(width 0.127)
		(layer "In7.Cu")
		(net "FT4232_CHD_RX")
	)
	(segment
		(start 122.174 -21.971)
		(end 122.910092 -22.707092)
		(width 0.11938)
		(layer "F.Cu")
		(net "FPGA_PCA9546_I2C_SDA")
	)
	(segment
		(start 120.2944 -21.971)
		(end 122.174 -21.971)
		(width 0.11938)
		(layer "F.Cu")
		(net "FPGA_PCA9546_I2C_SDA")
	)
	(segment
		(start 120.2944 -21.7424)
		(end 120.2944 -21.971)
		(width 0.11938)
		(layer "F.Cu")
		(net "FPGA_PCA9546_I2C_SDA")
	)
	(segment
		(start 122.910092 -22.707092)
		(end 124.0917 -22.707092)
		(width 0.11938)
		(layer "F.Cu")
		(net "FPGA_PCA9546_I2C_SDA")
	)
	(segment
		(start 113.847118 -48.823118)
		(end 114.34699 -49.32299)
		(width 0.11938)
		(layer "F.Cu")
		(net "FPGA_PCA9546_I2C_SDA")
	)
	(segment
		(start 119.507 -20.955)
		(end 120.2944 -21.7424)
		(width 0.11938)
		(layer "F.Cu")
		(net "FPGA_PCA9546_I2C_SDA")
	)
	(via
		(at 119.507 -20.955)
		(size 0.508)
		(drill 0.254)
		(layers "F.Cu" "B.Cu")
		(net "FPGA_PCA9546_I2C_SDA")
	)
	(via
		(at 116.205 -56.769)
		(size 0.508)
		(drill 0.254)
		(layers "F.Cu" "B.Cu")
		(net "FPGA_PCA9546_I2C_SDA")
	)
	(via
		(at 114.34699 -49.32299)
		(size 0.4572)
		(drill 0.2032)
		(layers "F.Cu" "B.Cu")
		(net "FPGA_PCA9546_I2C_SDA")
	)
	(segment
		(start 125.857254 -53.213)
		(end 124.46 -53.213)
		(width 0.11938)
		(layer "B.Cu")
		(net "FPGA_PCA9546_I2C_SDA")
	)
	(segment
		(start 128.71069 -37.505386)
		(end 128.71069 -44.509436)
		(width 0.11938)
		(layer "B.Cu")
		(net "FPGA_PCA9546_I2C_SDA")
	)
	(segment
		(start 124.34443 -25.944576)
		(end 124.513086 -25.944576)
		(width 0.11938)
		(layer "B.Cu")
		(net "FPGA_PCA9546_I2C_SDA")
	)
	(segment
		(start 126.492 -26.923746)
		(end 126.492 -29.150818)
		(width 0.11938)
		(layer "B.Cu")
		(net "FPGA_PCA9546_I2C_SDA")
	)
	(segment
		(start 124.069348 -25.500838)
		(end 124.069348 -25.669494)
		(width 0.11938)
		(layer "B.Cu")
		(net "FPGA_PCA9546_I2C_SDA")
	)
	(segment
		(start 126.619 -52.451254)
		(end 125.857254 -53.213)
		(width 0.11938)
		(layer "B.Cu")
		(net "FPGA_PCA9546_I2C_SDA")
	)
	(segment
		(start 124.069348 -25.669494)
		(end 124.34443 -25.944576)
		(width 0.11938)
		(layer "B.Cu")
		(net "FPGA_PCA9546_I2C_SDA")
	)
	(segment
		(start 124.46 -53.213)
		(end 121.793 -55.88)
		(width 0.11938)
		(layer "B.Cu")
		(net "FPGA_PCA9546_I2C_SDA")
	)
	(segment
		(start 119.253 -56.134)
		(end 116.84 -56.134)
		(width 0.11938)
		(layer "B.Cu")
		(net "FPGA_PCA9546_I2C_SDA")
	)
	(segment
		(start 124.484892 -24.916638)
		(end 124.484892 -25.085294)
		(width 0.11938)
		(layer "B.Cu")
		(net "FPGA_PCA9546_I2C_SDA")
	)
	(segment
		(start 116.84 -56.134)
		(end 116.205 -56.769)
		(width 0.11938)
		(layer "B.Cu")
		(net "FPGA_PCA9546_I2C_SDA")
	)
	(segment
		(start 121.031 -22.479)
		(end 122.047254 -22.479)
		(width 0.11938)
		(layer "B.Cu")
		(net "FPGA_PCA9546_I2C_SDA")
	)
	(segment
		(start 125.097286 -25.529032)
		(end 125.372368 -25.804114)
		(width 0.11938)
		(layer "B.Cu")
		(net "FPGA_PCA9546_I2C_SDA")
	)
	(segment
		(start 122.047254 -22.479)
		(end 124.484892 -24.916638)
		(width 0.11938)
		(layer "B.Cu")
		(net "FPGA_PCA9546_I2C_SDA")
	)
	(segment
		(start 119.507 -55.88)
		(end 119.253 -56.134)
		(width 0.11938)
		(layer "B.Cu")
		(net "FPGA_PCA9546_I2C_SDA")
	)
	(segment
		(start 124.484892 -25.085294)
		(end 124.069348 -25.500838)
		(width 0.11938)
		(layer "B.Cu")
		(net "FPGA_PCA9546_I2C_SDA")
	)
	(segment
		(start 126.492 -29.150818)
		(end 128.710182 -31.369)
		(width 0.11938)
		(layer "B.Cu")
		(net "FPGA_PCA9546_I2C_SDA")
	)
	(segment
		(start 128.710182 -37.504878)
		(end 128.71069 -37.505386)
		(width 0.11938)
		(layer "B.Cu")
		(net "FPGA_PCA9546_I2C_SDA")
	)
	(segment
		(start 128.71069 -44.509436)
		(end 129.54 -45.338746)
		(width 0.11938)
		(layer "B.Cu")
		(net "FPGA_PCA9546_I2C_SDA")
	)
	(segment
		(start 129.54 -45.338746)
		(end 129.54 -49.022)
		(width 0.11938)
		(layer "B.Cu")
		(net "FPGA_PCA9546_I2C_SDA")
	)
	(segment
		(start 125.372368 -25.97277)
		(end 124.956824 -26.388314)
		(width 0.11938)
		(layer "B.Cu")
		(net "FPGA_PCA9546_I2C_SDA")
	)
	(segment
		(start 125.400562 -26.832052)
		(end 125.816106 -26.416508)
		(width 0.11938)
		(layer "B.Cu")
		(net "FPGA_PCA9546_I2C_SDA")
	)
	(segment
		(start 128.710182 -31.369)
		(end 128.710182 -37.504878)
		(width 0.11938)
		(layer "B.Cu")
		(net "FPGA_PCA9546_I2C_SDA")
	)
	(segment
		(start 125.372368 -25.804114)
		(end 125.372368 -25.97277)
		(width 0.11938)
		(layer "B.Cu")
		(net "FPGA_PCA9546_I2C_SDA")
	)
	(segment
		(start 121.793 -55.88)
		(end 119.507 -55.88)
		(width 0.11938)
		(layer "B.Cu")
		(net "FPGA_PCA9546_I2C_SDA")
	)
	(segment
		(start 126.619 -51.943)
		(end 126.619 -52.451254)
		(width 0.11938)
		(layer "B.Cu")
		(net "FPGA_PCA9546_I2C_SDA")
	)
	(segment
		(start 125.984762 -26.416508)
		(end 126.492 -26.923746)
		(width 0.11938)
		(layer "B.Cu")
		(net "FPGA_PCA9546_I2C_SDA")
	)
	(segment
		(start 125.816106 -26.416508)
		(end 125.984762 -26.416508)
		(width 0.11938)
		(layer "B.Cu")
		(net "FPGA_PCA9546_I2C_SDA")
	)
	(segment
		(start 124.956824 -26.55697)
		(end 125.231906 -26.832052)
		(width 0.11938)
		(layer "B.Cu")
		(net "FPGA_PCA9546_I2C_SDA")
	)
	(segment
		(start 124.92863 -25.529032)
		(end 125.097286 -25.529032)
		(width 0.11938)
		(layer "B.Cu")
		(net "FPGA_PCA9546_I2C_SDA")
	)
	(segment
		(start 124.513086 -25.944576)
		(end 124.92863 -25.529032)
		(width 0.11938)
		(layer "B.Cu")
		(net "FPGA_PCA9546_I2C_SDA")
	)
	(segment
		(start 124.956824 -26.388314)
		(end 124.956824 -26.55697)
		(width 0.11938)
		(layer "B.Cu")
		(net "FPGA_PCA9546_I2C_SDA")
	)
	(segment
		(start 125.231906 -26.832052)
		(end 125.400562 -26.832052)
		(width 0.11938)
		(layer "B.Cu")
		(net "FPGA_PCA9546_I2C_SDA")
	)
	(segment
		(start 129.54 -49.022)
		(end 126.619 -51.943)
		(width 0.11938)
		(layer "B.Cu")
		(net "FPGA_PCA9546_I2C_SDA")
	)
	(segment
		(start 119.507 -20.955)
		(end 121.031 -22.479)
		(width 0.11938)
		(layer "B.Cu")
		(net "FPGA_PCA9546_I2C_SDA")
	)
	(segment
		(start 114.86642 -49.84242)
		(end 114.34699 -49.32299)
		(width 0.127)
		(layer "In7.Cu")
		(net "FPGA_PCA9546_I2C_SDA")
	)
	(segment
		(start 116.205 -56.769)
		(end 115.89004 -56.45404)
		(width 0.127)
		(layer "In7.Cu")
		(net "FPGA_PCA9546_I2C_SDA")
	)
	(segment
		(start 115.89004 -56.45404)
		(end 115.89004 -50.10404)
		(width 0.127)
		(layer "In7.Cu")
		(net "FPGA_PCA9546_I2C_SDA")
	)
	(segment
		(start 115.62842 -49.84242)
		(end 114.86642 -49.84242)
		(width 0.127)
		(layer "In7.Cu")
		(net "FPGA_PCA9546_I2C_SDA")
	)
	(segment
		(start 115.89004 -50.10404)
		(end 115.62842 -49.84242)
		(width 0.127)
		(layer "In7.Cu")
		(net "FPGA_PCA9546_I2C_SDA")
	)
	(segment
		(start 121.158 -20.447)
		(end 120.65 -19.939)
		(width 0.11938)
		(layer "F.Cu")
		(net "FPGA_PCA9546_I2C_SCL")
	)
	(segment
		(start 110.847124 -49.823116)
		(end 111.346996 -50.322988)
		(width 0.11938)
		(layer "F.Cu")
		(net "FPGA_PCA9546_I2C_SCL")
	)
	(segment
		(start 120.65 -19.939)
		(end 120.2944 -19.939)
		(width 0.11938)
		(layer "F.Cu")
		(net "FPGA_PCA9546_I2C_SCL")
	)
	(segment
		(start 122.809 -20.447)
		(end 121.158 -20.447)
		(width 0.11938)
		(layer "F.Cu")
		(net "FPGA_PCA9546_I2C_SCL")
	)
	(segment
		(start 124.0917 -20.75688)
		(end 123.11888 -20.75688)
		(width 0.11938)
		(layer "F.Cu")
		(net "FPGA_PCA9546_I2C_SCL")
	)
	(segment
		(start 120.777 -20.955)
		(end 120.523 -20.955)
		(width 0.11938)
		(layer "F.Cu")
		(net "FPGA_PCA9546_I2C_SCL")
	)
	(segment
		(start 120.2944 -20.7264)
		(end 120.2944 -19.939)
		(width 0.11938)
		(layer "F.Cu")
		(net "FPGA_PCA9546_I2C_SCL")
	)
	(segment
		(start 120.523 -20.955)
		(end 120.2944 -20.7264)
		(width 0.11938)
		(layer "F.Cu")
		(net "FPGA_PCA9546_I2C_SCL")
	)
	(segment
		(start 123.11888 -20.75688)
		(end 122.809 -20.447)
		(width 0.11938)
		(layer "F.Cu")
		(net "FPGA_PCA9546_I2C_SCL")
	)
	(via
		(at 111.346996 -50.322988)
		(size 0.4572)
		(drill 0.2032)
		(layers "F.Cu" "B.Cu")
		(net "FPGA_PCA9546_I2C_SCL")
	)
	(via
		(at 116.205 -57.785)
		(size 0.508)
		(drill 0.254)
		(layers "F.Cu" "B.Cu")
		(net "FPGA_PCA9546_I2C_SCL")
	)
	(via
		(at 120.777 -20.955)
		(size 0.508)
		(drill 0.254)
		(layers "F.Cu" "B.Cu")
		(net "FPGA_PCA9546_I2C_SCL")
	)
	(segment
		(start 120.777 -20.955)
		(end 121.86158 -22.03958)
		(width 0.11938)
		(layer "B.Cu")
		(net "FPGA_PCA9546_I2C_SCL")
	)
	(segment
		(start 129.921 -45.085)
		(end 129.921 -45.098208)
		(width 0.11938)
		(layer "B.Cu")
		(net "FPGA_PCA9546_I2C_SCL")
	)
	(segment
		(start 116.332 -57.785)
		(end 116.205 -57.785)
		(width 0.11938)
		(layer "B.Cu")
		(net "FPGA_PCA9546_I2C_SCL")
	)
	(segment
		(start 127.127 -52.578)
		(end 125.857 -53.848)
		(width 0.11938)
		(layer "B.Cu")
		(net "FPGA_PCA9546_I2C_SCL")
	)
	(segment
		(start 122.174 -56.388)
		(end 119.634 -56.388)
		(width 0.11938)
		(layer "B.Cu")
		(net "FPGA_PCA9546_I2C_SCL")
	)
	(segment
		(start 119.634 -56.388)
		(end 118.872 -57.15)
		(width 0.11938)
		(layer "B.Cu")
		(net "FPGA_PCA9546_I2C_SCL")
	)
	(segment
		(start 122.229372 -22.03958)
		(end 127.120396 -26.930604)
		(width 0.11938)
		(layer "B.Cu")
		(net "FPGA_PCA9546_I2C_SCL")
	)
	(segment
		(start 117.583204 -57.59069)
		(end 116.52631 -57.59069)
		(width 0.11938)
		(layer "B.Cu")
		(net "FPGA_PCA9546_I2C_SCL")
	)
	(segment
		(start 124.714 -53.848)
		(end 122.174 -56.388)
		(width 0.11938)
		(layer "B.Cu")
		(net "FPGA_PCA9546_I2C_SCL")
	)
	(segment
		(start 127.127 -52.056538)
		(end 127.127 -52.578)
		(width 0.11938)
		(layer "B.Cu")
		(net "FPGA_PCA9546_I2C_SCL")
	)
	(segment
		(start 129.159 -31.170372)
		(end 129.159 -44.323)
		(width 0.11938)
		(layer "B.Cu")
		(net "FPGA_PCA9546_I2C_SCL")
	)
	(segment
		(start 118.872 -57.15)
		(end 118.023894 -57.15)
		(width 0.11938)
		(layer "B.Cu")
		(net "FPGA_PCA9546_I2C_SCL")
	)
	(segment
		(start 125.857 -53.848)
		(end 124.714 -53.848)
		(width 0.11938)
		(layer "B.Cu")
		(net "FPGA_PCA9546_I2C_SCL")
	)
	(segment
		(start 118.023894 -57.15)
		(end 117.583204 -57.59069)
		(width 0.11938)
		(layer "B.Cu")
		(net "FPGA_PCA9546_I2C_SCL")
	)
	(segment
		(start 127.120396 -29.131768)
		(end 129.159 -31.170372)
		(width 0.11938)
		(layer "B.Cu")
		(net "FPGA_PCA9546_I2C_SCL")
	)
	(segment
		(start 127.120396 -26.930604)
		(end 127.120396 -29.131768)
		(width 0.11938)
		(layer "B.Cu")
		(net "FPGA_PCA9546_I2C_SCL")
	)
	(segment
		(start 121.86158 -22.03958)
		(end 122.229372 -22.03958)
		(width 0.11938)
		(layer "B.Cu")
		(net "FPGA_PCA9546_I2C_SCL")
	)
	(segment
		(start 116.52631 -57.59069)
		(end 116.332 -57.785)
		(width 0.11938)
		(layer "B.Cu")
		(net "FPGA_PCA9546_I2C_SCL")
	)
	(segment
		(start 129.97942 -45.156628)
		(end 129.97942 -49.204118)
		(width 0.11938)
		(layer "B.Cu")
		(net "FPGA_PCA9546_I2C_SCL")
	)
	(segment
		(start 129.921 -45.098208)
		(end 129.97942 -45.156628)
		(width 0.11938)
		(layer "B.Cu")
		(net "FPGA_PCA9546_I2C_SCL")
	)
	(segment
		(start 129.159 -44.323)
		(end 129.921 -45.085)
		(width 0.11938)
		(layer "B.Cu")
		(net "FPGA_PCA9546_I2C_SCL")
	)
	(segment
		(start 129.97942 -49.204118)
		(end 127.127 -52.056538)
		(width 0.11938)
		(layer "B.Cu")
		(net "FPGA_PCA9546_I2C_SCL")
	)
	(segment
		(start 115.443 -57.15)
		(end 115.443 -56.642)
		(width 0.127)
		(layer "In7.Cu")
		(net "FPGA_PCA9546_I2C_SCL")
	)
	(segment
		(start 114.808 -50.927)
		(end 114.681 -50.8)
		(width 0.127)
		(layer "In7.Cu")
		(net "FPGA_PCA9546_I2C_SCL")
	)
	(segment
		(start 114.681 -50.8)
		(end 111.824008 -50.8)
		(width 0.127)
		(layer "In7.Cu")
		(net "FPGA_PCA9546_I2C_SCL")
	)
	(segment
		(start 116.078 -57.785)
		(end 115.443 -57.15)
		(width 0.127)
		(layer "In7.Cu")
		(net "FPGA_PCA9546_I2C_SCL")
	)
	(segment
		(start 111.824008 -50.8)
		(end 111.346996 -50.322988)
		(width 0.127)
		(layer "In7.Cu")
		(net "FPGA_PCA9546_I2C_SCL")
	)
	(segment
		(start 116.205 -57.785)
		(end 116.078 -57.785)
		(width 0.127)
		(layer "In7.Cu")
		(net "FPGA_PCA9546_I2C_SCL")
	)
	(segment
		(start 114.808 -56.007)
		(end 114.808 -50.927)
		(width 0.127)
		(layer "In7.Cu")
		(net "FPGA_PCA9546_I2C_SCL")
	)
	(segment
		(start 115.443 -56.642)
		(end 114.808 -56.007)
		(width 0.127)
		(layer "In7.Cu")
		(net "FPGA_PCA9546_I2C_SCL")
	)
	(segment
		(start 118.847108 -45.823124)
		(end 119.34698 -46.322996)
		(width 0.11938)
		(layer "F.Cu")
		(net "FPGA_OUT_SN_EEPROM_WP")
	)
	(via
		(at 119.34698 -46.322996)
		(size 0.4572)
		(drill 0.2032)
		(layers "F.Cu" "B.Cu")
		(net "FPGA_OUT_SN_EEPROM_WP")
	)
	(via
		(at 32.004 -18.288)
		(size 0.508)
		(drill 0.254)
		(layers "F.Cu" "B.Cu")
		(net "FPGA_OUT_SN_EEPROM_WP")
	)
	(segment
		(start 31.71444 -17.99844)
		(end 32.004 -18.288)
		(width 0.11938)
		(layer "B.Cu")
		(net "FPGA_OUT_SN_EEPROM_WP")
	)
	(segment
		(start 30.87878 -17.99844)
		(end 31.71444 -17.99844)
		(width 0.11938)
		(layer "B.Cu")
		(net "FPGA_OUT_SN_EEPROM_WP")
	)
	(segment
		(start 81.90484 -16.4465)
		(end 85.361018 -16.4465)
		(width 0.127)
		(layer "In2.Cu")
		(net "FPGA_OUT_SN_EEPROM_WP")
	)
	(segment
		(start 46.736 -19.05)
		(end 49.276 -16.51)
		(width 0.127)
		(layer "In2.Cu")
		(net "FPGA_OUT_SN_EEPROM_WP")
	)
	(segment
		(start 57.785254 -14.859)
		(end 62.738254 -14.859)
		(width 0.127)
		(layer "In2.Cu")
		(net "FPGA_OUT_SN_EEPROM_WP")
	)
	(segment
		(start 127.07874 -47.353982)
		(end 126.640082 -47.79264)
		(width 0.127)
		(layer "In2.Cu")
		(net "FPGA_OUT_SN_EEPROM_WP")
	)
	(segment
		(start 32.66186 -18.288)
		(end 35.50158 -21.12772)
		(width 0.127)
		(layer "In2.Cu")
		(net "FPGA_OUT_SN_EEPROM_WP")
	)
	(segment
		(start 49.276 -16.51)
		(end 52.578254 -16.51)
		(width 0.127)
		(layer "In2.Cu")
		(net "FPGA_OUT_SN_EEPROM_WP")
	)
	(segment
		(start 120.14962 -46.81728)
		(end 119.655336 -46.322996)
		(width 0.127)
		(layer "In2.Cu")
		(net "FPGA_OUT_SN_EEPROM_WP")
	)
	(segment
		(start 57.132474 -15.51178)
		(end 57.785254 -14.859)
		(width 0.127)
		(layer "In2.Cu")
		(net "FPGA_OUT_SN_EEPROM_WP")
	)
	(segment
		(start 52.578254 -16.51)
		(end 53.576474 -15.51178)
		(width 0.127)
		(layer "In2.Cu")
		(net "FPGA_OUT_SN_EEPROM_WP")
	)
	(segment
		(start 62.738254 -14.859)
		(end 64.262254 -16.383)
		(width 0.127)
		(layer "In2.Cu")
		(net "FPGA_OUT_SN_EEPROM_WP")
	)
	(segment
		(start 74.30516 -16.4084)
		(end 81.86674 -16.4084)
		(width 0.127)
		(layer "In2.Cu")
		(net "FPGA_OUT_SN_EEPROM_WP")
	)
	(segment
		(start 64.262254 -16.383)
		(end 74.27976 -16.383)
		(width 0.127)
		(layer "In2.Cu")
		(net "FPGA_OUT_SN_EEPROM_WP")
	)
	(segment
		(start 121.31294 -46.81728)
		(end 120.14962 -46.81728)
		(width 0.127)
		(layer "In2.Cu")
		(net "FPGA_OUT_SN_EEPROM_WP")
	)
	(segment
		(start 131.318 -24.383746)
		(end 131.318 -24.427434)
		(width 0.127)
		(layer "In2.Cu")
		(net "FPGA_OUT_SN_EEPROM_WP")
	)
	(segment
		(start 126.640082 -47.79264)
		(end 122.2883 -47.79264)
		(width 0.127)
		(layer "In2.Cu")
		(net "FPGA_OUT_SN_EEPROM_WP")
	)
	(segment
		(start 92.785438 -16.0655)
		(end 94.538038 -14.3129)
		(width 0.127)
		(layer "In2.Cu")
		(net "FPGA_OUT_SN_EEPROM_WP")
	)
	(segment
		(start 74.27976 -16.383)
		(end 74.30516 -16.4084)
		(width 0.127)
		(layer "In2.Cu")
		(net "FPGA_OUT_SN_EEPROM_WP")
	)
	(segment
		(start 46.131988 -21.12772)
		(end 46.736 -20.523708)
		(width 0.127)
		(layer "In2.Cu")
		(net "FPGA_OUT_SN_EEPROM_WP")
	)
	(segment
		(start 32.004 -18.288)
		(end 32.66186 -18.288)
		(width 0.127)
		(layer "In2.Cu")
		(net "FPGA_OUT_SN_EEPROM_WP")
	)
	(segment
		(start 131.318 -31.493206)
		(end 131.318 -41.188386)
		(width 0.127)
		(layer "In2.Cu")
		(net "FPGA_OUT_SN_EEPROM_WP")
	)
	(segment
		(start 46.736 -20.523708)
		(end 46.736 -19.05)
		(width 0.127)
		(layer "In2.Cu")
		(net "FPGA_OUT_SN_EEPROM_WP")
	)
	(segment
		(start 53.576474 -15.51178)
		(end 57.132474 -15.51178)
		(width 0.127)
		(layer "In2.Cu")
		(net "FPGA_OUT_SN_EEPROM_WP")
	)
	(segment
		(start 86.723982 -15.5575)
		(end 87.231982 -16.0655)
		(width 0.127)
		(layer "In2.Cu")
		(net "FPGA_OUT_SN_EEPROM_WP")
	)
	(segment
		(start 86.250018 -15.5575)
		(end 86.723982 -15.5575)
		(width 0.127)
		(layer "In2.Cu")
		(net "FPGA_OUT_SN_EEPROM_WP")
	)
	(segment
		(start 35.50158 -21.12772)
		(end 46.131988 -21.12772)
		(width 0.127)
		(layer "In2.Cu")
		(net "FPGA_OUT_SN_EEPROM_WP")
	)
	(segment
		(start 85.361018 -16.4465)
		(end 86.250018 -15.5575)
		(width 0.127)
		(layer "In2.Cu")
		(net "FPGA_OUT_SN_EEPROM_WP")
	)
	(segment
		(start 94.538038 -14.3129)
		(end 122.640598 -14.3129)
		(width 0.127)
		(layer "In2.Cu")
		(net "FPGA_OUT_SN_EEPROM_WP")
	)
	(segment
		(start 87.231982 -16.0655)
		(end 92.785438 -16.0655)
		(width 0.127)
		(layer "In2.Cu")
		(net "FPGA_OUT_SN_EEPROM_WP")
	)
	(segment
		(start 130.556 -22.228302)
		(end 130.556 -23.621746)
		(width 0.127)
		(layer "In2.Cu")
		(net "FPGA_OUT_SN_EEPROM_WP")
	)
	(segment
		(start 119.655336 -46.322996)
		(end 119.34698 -46.322996)
		(width 0.127)
		(layer "In2.Cu")
		(net "FPGA_OUT_SN_EEPROM_WP")
	)
	(segment
		(start 122.2883 -47.79264)
		(end 121.31294 -46.81728)
		(width 0.127)
		(layer "In2.Cu")
		(net "FPGA_OUT_SN_EEPROM_WP")
	)
	(segment
		(start 130.556 -23.621746)
		(end 131.318 -24.383746)
		(width 0.127)
		(layer "In2.Cu")
		(net "FPGA_OUT_SN_EEPROM_WP")
	)
	(segment
		(start 131.953 -25.062434)
		(end 131.953 -30.858206)
		(width 0.127)
		(layer "In2.Cu")
		(net "FPGA_OUT_SN_EEPROM_WP")
	)
	(segment
		(start 131.318 -41.188386)
		(end 127.07874 -45.427646)
		(width 0.127)
		(layer "In2.Cu")
		(net "FPGA_OUT_SN_EEPROM_WP")
	)
	(segment
		(start 122.640598 -14.3129)
		(end 130.556 -22.228302)
		(width 0.127)
		(layer "In2.Cu")
		(net "FPGA_OUT_SN_EEPROM_WP")
	)
	(segment
		(start 81.86674 -16.4084)
		(end 81.90484 -16.4465)
		(width 0.127)
		(layer "In2.Cu")
		(net "FPGA_OUT_SN_EEPROM_WP")
	)
	(segment
		(start 131.318 -24.427434)
		(end 131.953 -25.062434)
		(width 0.127)
		(layer "In2.Cu")
		(net "FPGA_OUT_SN_EEPROM_WP")
	)
	(segment
		(start 127.07874 -45.427646)
		(end 127.07874 -47.353982)
		(width 0.127)
		(layer "In2.Cu")
		(net "FPGA_OUT_SN_EEPROM_WP")
	)
	(segment
		(start 131.953 -30.858206)
		(end 131.318 -31.493206)
		(width 0.127)
		(layer "In2.Cu")
		(net "FPGA_OUT_SN_EEPROM_WP")
	)
	(segment
		(start 119.847106 -45.823124)
		(end 120.346978 -46.322996)
		(width 0.11938)
		(layer "F.Cu")
		(net "FPGA_OUT_SEC_EEPROM_WP")
	)
	(via
		(at 120.346978 -46.322996)
		(size 0.4572)
		(drill 0.2032)
		(layers "F.Cu" "B.Cu")
		(net "FPGA_OUT_SEC_EEPROM_WP")
	)
	(via
		(at 21.3868 -19.05)
		(size 0.508)
		(drill 0.254)
		(layers "F.Cu" "B.Cu")
		(net "FPGA_OUT_SEC_EEPROM_WP")
	)
	(segment
		(start 21.3106 -19.1262)
		(end 20.2946 -19.1262)
		(width 0.11938)
		(layer "B.Cu")
		(net "FPGA_OUT_SEC_EEPROM_WP")
	)
	(segment
		(start 21.3868 -19.05)
		(end 21.3106 -19.1262)
		(width 0.11938)
		(layer "B.Cu")
		(net "FPGA_OUT_SEC_EEPROM_WP")
	)
	(segment
		(start 124.968 -44.533058)
		(end 125.813058 -43.688)
		(width 0.127)
		(layer "In2.Cu")
		(net "FPGA_OUT_SEC_EEPROM_WP")
	)
	(segment
		(start 48.00092 -19.519646)
		(end 48.00092 -20.69592)
		(width 0.127)
		(layer "In2.Cu")
		(net "FPGA_OUT_SEC_EEPROM_WP")
	)
	(segment
		(start 22.479 -20.828)
		(end 22.479 -20.1422)
		(width 0.127)
		(layer "In2.Cu")
		(net "FPGA_OUT_SEC_EEPROM_WP")
	)
	(segment
		(start 64.77 -18.415)
		(end 62.23 -15.875)
		(width 0.127)
		(layer "In2.Cu")
		(net "FPGA_OUT_SEC_EEPROM_WP")
	)
	(segment
		(start 122.511566 -15.621)
		(end 106.16819 -15.621)
		(width 0.127)
		(layer "In2.Cu")
		(net "FPGA_OUT_SEC_EEPROM_WP")
	)
	(segment
		(start 121.9962 -46.736)
		(end 122.428 -46.736)
		(width 0.127)
		(layer "In2.Cu")
		(net "FPGA_OUT_SEC_EEPROM_WP")
	)
	(segment
		(start 129.6035 -41.465754)
		(end 129.6035 -36.128452)
		(width 0.127)
		(layer "In2.Cu")
		(net "FPGA_OUT_SEC_EEPROM_WP")
	)
	(segment
		(start 123.464066 -46.5455)
		(end 124.968 -45.041566)
		(width 0.127)
		(layer "In2.Cu")
		(net "FPGA_OUT_SEC_EEPROM_WP")
	)
	(segment
		(start 66.929 -17.907)
		(end 66.421 -18.415)
		(width 0.127)
		(layer "In2.Cu")
		(net "FPGA_OUT_SEC_EEPROM_WP")
	)
	(segment
		(start 120.346978 -46.322996)
		(end 121.583196 -46.322996)
		(width 0.127)
		(layer "In2.Cu")
		(net "FPGA_OUT_SEC_EEPROM_WP")
	)
	(segment
		(start 127.381254 -43.688)
		(end 129.6035 -41.465754)
		(width 0.127)
		(layer "In2.Cu")
		(net "FPGA_OUT_SEC_EEPROM_WP")
	)
	(segment
		(start 22.479 -20.1422)
		(end 21.3868 -19.05)
		(width 0.127)
		(layer "In2.Cu")
		(net "FPGA_OUT_SEC_EEPROM_WP")
	)
	(segment
		(start 82.325972 -17.4625)
		(end 81.910936 -17.877536)
		(width 0.127)
		(layer "In2.Cu")
		(net "FPGA_OUT_SEC_EEPROM_WP")
	)
	(segment
		(start 122.428 -46.736)
		(end 122.6185 -46.5455)
		(width 0.127)
		(layer "In2.Cu")
		(net "FPGA_OUT_SEC_EEPROM_WP")
	)
	(segment
		(start 57.657746 -16.637)
		(end 54.157626 -16.637)
		(width 0.127)
		(layer "In2.Cu")
		(net "FPGA_OUT_SEC_EEPROM_WP")
	)
	(segment
		(start 129.286 -22.395434)
		(end 122.511566 -15.621)
		(width 0.127)
		(layer "In2.Cu")
		(net "FPGA_OUT_SEC_EEPROM_WP")
	)
	(segment
		(start 58.419746 -15.875)
		(end 57.657746 -16.637)
		(width 0.127)
		(layer "In2.Cu")
		(net "FPGA_OUT_SEC_EEPROM_WP")
	)
	(segment
		(start 129.6035 -36.128452)
		(end 130.175 -35.556952)
		(width 0.127)
		(layer "In2.Cu")
		(net "FPGA_OUT_SEC_EEPROM_WP")
	)
	(segment
		(start 106.16819 -15.621)
		(end 105.87609 -15.3289)
		(width 0.127)
		(layer "In2.Cu")
		(net "FPGA_OUT_SEC_EEPROM_WP")
	)
	(segment
		(start 77.956664 -17.877536)
		(end 77.2668 -18.5674)
		(width 0.127)
		(layer "In2.Cu")
		(net "FPGA_OUT_SEC_EEPROM_WP")
	)
	(segment
		(start 125.813058 -43.688)
		(end 127.381254 -43.688)
		(width 0.127)
		(layer "In2.Cu")
		(net "FPGA_OUT_SEC_EEPROM_WP")
	)
	(segment
		(start 49.156366 -18.3642)
		(end 48.00092 -19.519646)
		(width 0.127)
		(layer "In2.Cu")
		(net "FPGA_OUT_SEC_EEPROM_WP")
	)
	(segment
		(start 92.82557 -17.4625)
		(end 82.325972 -17.4625)
		(width 0.127)
		(layer "In2.Cu")
		(net "FPGA_OUT_SEC_EEPROM_WP")
	)
	(segment
		(start 124.968 -45.041566)
		(end 124.968 -44.533058)
		(width 0.127)
		(layer "In2.Cu")
		(net "FPGA_OUT_SEC_EEPROM_WP")
	)
	(segment
		(start 38.34384 -30.353)
		(end 32.004 -30.353)
		(width 0.127)
		(layer "In2.Cu")
		(net "FPGA_OUT_SEC_EEPROM_WP")
	)
	(segment
		(start 130.809746 -25.4)
		(end 129.286 -23.876254)
		(width 0.127)
		(layer "In2.Cu")
		(net "FPGA_OUT_SEC_EEPROM_WP")
	)
	(segment
		(start 81.910936 -17.877536)
		(end 77.956664 -17.877536)
		(width 0.127)
		(layer "In2.Cu")
		(net "FPGA_OUT_SEC_EEPROM_WP")
	)
	(segment
		(start 94.95917 -15.3289)
		(end 92.82557 -17.4625)
		(width 0.127)
		(layer "In2.Cu")
		(net "FPGA_OUT_SEC_EEPROM_WP")
	)
	(segment
		(start 62.23 -15.875)
		(end 58.419746 -15.875)
		(width 0.127)
		(layer "In2.Cu")
		(net "FPGA_OUT_SEC_EEPROM_WP")
	)
	(segment
		(start 54.157626 -16.637)
		(end 52.430426 -18.3642)
		(width 0.127)
		(layer "In2.Cu")
		(net "FPGA_OUT_SEC_EEPROM_WP")
	)
	(segment
		(start 129.286 -23.876254)
		(end 129.286 -22.395434)
		(width 0.127)
		(layer "In2.Cu")
		(net "FPGA_OUT_SEC_EEPROM_WP")
	)
	(segment
		(start 48.00092 -20.69592)
		(end 38.34384 -30.353)
		(width 0.127)
		(layer "In2.Cu")
		(net "FPGA_OUT_SEC_EEPROM_WP")
	)
	(segment
		(start 77.2668 -18.5674)
		(end 74.4474 -18.5674)
		(width 0.127)
		(layer "In2.Cu")
		(net "FPGA_OUT_SEC_EEPROM_WP")
	)
	(segment
		(start 130.809746 -30.39872)
		(end 130.809746 -25.4)
		(width 0.127)
		(layer "In2.Cu")
		(net "FPGA_OUT_SEC_EEPROM_WP")
	)
	(segment
		(start 74.4474 -18.5674)
		(end 73.787 -17.907)
		(width 0.127)
		(layer "In2.Cu")
		(net "FPGA_OUT_SEC_EEPROM_WP")
	)
	(segment
		(start 32.004 -30.353)
		(end 22.479 -20.828)
		(width 0.127)
		(layer "In2.Cu")
		(net "FPGA_OUT_SEC_EEPROM_WP")
	)
	(segment
		(start 130.175 -31.033466)
		(end 130.809746 -30.39872)
		(width 0.127)
		(layer "In2.Cu")
		(net "FPGA_OUT_SEC_EEPROM_WP")
	)
	(segment
		(start 66.421 -18.415)
		(end 64.77 -18.415)
		(width 0.127)
		(layer "In2.Cu")
		(net "FPGA_OUT_SEC_EEPROM_WP")
	)
	(segment
		(start 52.430426 -18.3642)
		(end 49.156366 -18.3642)
		(width 0.127)
		(layer "In2.Cu")
		(net "FPGA_OUT_SEC_EEPROM_WP")
	)
	(segment
		(start 73.787 -17.907)
		(end 66.929 -17.907)
		(width 0.127)
		(layer "In2.Cu")
		(net "FPGA_OUT_SEC_EEPROM_WP")
	)
	(segment
		(start 121.583196 -46.322996)
		(end 121.9962 -46.736)
		(width 0.127)
		(layer "In2.Cu")
		(net "FPGA_OUT_SEC_EEPROM_WP")
	)
	(segment
		(start 122.6185 -46.5455)
		(end 123.464066 -46.5455)
		(width 0.127)
		(layer "In2.Cu")
		(net "FPGA_OUT_SEC_EEPROM_WP")
	)
	(segment
		(start 105.87609 -15.3289)
		(end 94.95917 -15.3289)
		(width 0.127)
		(layer "In2.Cu")
		(net "FPGA_OUT_SEC_EEPROM_WP")
	)
	(segment
		(start 130.175 -35.556952)
		(end 130.175 -31.033466)
		(width 0.127)
		(layer "In2.Cu")
		(net "FPGA_OUT_SEC_EEPROM_WP")
	)
	(segment
		(start 104.902 -30.48)
		(end 103.505 -31.877)
		(width 0.11938)
		(layer "F.Cu")
		(net "FPGA_OUT_MUX3_SEL")
	)
	(segment
		(start 117.475 -31.75)
		(end 111.633254 -31.75)
		(width 0.11938)
		(layer "F.Cu")
		(net "FPGA_OUT_MUX3_SEL")
	)
	(segment
		(start 103.505 -31.877)
		(end 98.298 -31.877)
		(width 0.11938)
		(layer "F.Cu")
		(net "FPGA_OUT_MUX3_SEL")
	)
	(segment
		(start 94.906846 -46.519846)
		(end 94.906846 -47.17669)
		(width 0.11938)
		(layer "F.Cu")
		(net "FPGA_OUT_MUX3_SEL")
	)
	(segment
		(start 94.361 -44.704)
		(end 94.361 -45.974)
		(width 0.11938)
		(layer "F.Cu")
		(net "FPGA_OUT_MUX3_SEL")
	)
	(segment
		(start 110.363254 -30.48)
		(end 104.902 -30.48)
		(width 0.11938)
		(layer "F.Cu")
		(net "FPGA_OUT_MUX3_SEL")
	)
	(segment
		(start 104.847136 -47.82312)
		(end 104.347264 -48.322992)
		(width 0.11938)
		(layer "F.Cu")
		(net "FPGA_OUT_MUX3_SEL")
	)
	(segment
		(start 119.2276 -24.511)
		(end 117.602 -26.1366)
		(width 0.11938)
		(layer "F.Cu")
		(net "FPGA_OUT_MUX3_SEL")
	)
	(segment
		(start 118.618 -30.607)
		(end 117.475 -31.75)
		(width 0.11938)
		(layer "F.Cu")
		(net "FPGA_OUT_MUX3_SEL")
	)
	(segment
		(start 117.602 -28.448)
		(end 118.618 -29.464)
		(width 0.11938)
		(layer "F.Cu")
		(net "FPGA_OUT_MUX3_SEL")
	)
	(segment
		(start 118.618 -29.464)
		(end 118.618 -30.607)
		(width 0.11938)
		(layer "F.Cu")
		(net "FPGA_OUT_MUX3_SEL")
	)
	(segment
		(start 111.633254 -31.75)
		(end 110.363254 -30.48)
		(width 0.11938)
		(layer "F.Cu")
		(net "FPGA_OUT_MUX3_SEL")
	)
	(segment
		(start 97.155 -37.211)
		(end 97.155 -41.91)
		(width 0.11938)
		(layer "F.Cu")
		(net "FPGA_OUT_MUX3_SEL")
	)
	(segment
		(start 97.155 -41.91)
		(end 94.361 -44.704)
		(width 0.11938)
		(layer "F.Cu")
		(net "FPGA_OUT_MUX3_SEL")
	)
	(segment
		(start 117.602 -26.1366)
		(end 117.602 -28.448)
		(width 0.11938)
		(layer "F.Cu")
		(net "FPGA_OUT_MUX3_SEL")
	)
	(segment
		(start 97.663 -32.512)
		(end 97.663 -36.703)
		(width 0.11938)
		(layer "F.Cu")
		(net "FPGA_OUT_MUX3_SEL")
	)
	(segment
		(start 98.298 -31.877)
		(end 97.663 -32.512)
		(width 0.11938)
		(layer "F.Cu")
		(net "FPGA_OUT_MUX3_SEL")
	)
	(segment
		(start 94.361 -45.974)
		(end 94.906846 -46.519846)
		(width 0.11938)
		(layer "F.Cu")
		(net "FPGA_OUT_MUX3_SEL")
	)
	(segment
		(start 97.663 -36.703)
		(end 97.155 -37.211)
		(width 0.11938)
		(layer "F.Cu")
		(net "FPGA_OUT_MUX3_SEL")
	)
	(via
		(at 94.906846 -47.17669)
		(size 0.508)
		(drill 0.254)
		(layers "F.Cu" "B.Cu")
		(net "FPGA_OUT_MUX3_SEL")
	)
	(via
		(at 104.347264 -48.322992)
		(size 0.4572)
		(drill 0.2032)
		(layers "F.Cu" "B.Cu")
		(net "FPGA_OUT_MUX3_SEL")
	)
	(segment
		(start 94.906846 -47.17669)
		(end 95.885 -46.198536)
		(width 0.127)
		(layer "In2.Cu")
		(net "FPGA_OUT_MUX3_SEL")
	)
	(segment
		(start 95.885 -44.704)
		(end 96.139 -44.45)
		(width 0.127)
		(layer "In2.Cu")
		(net "FPGA_OUT_MUX3_SEL")
	)
	(segment
		(start 103.886 -47.861728)
		(end 104.347264 -48.322992)
		(width 0.127)
		(layer "In2.Cu")
		(net "FPGA_OUT_MUX3_SEL")
	)
	(segment
		(start 99.314 -44.45)
		(end 99.949 -45.085)
		(width 0.127)
		(layer "In2.Cu")
		(net "FPGA_OUT_MUX3_SEL")
	)
	(segment
		(start 95.885 -46.198536)
		(end 95.885 -44.704)
		(width 0.127)
		(layer "In2.Cu")
		(net "FPGA_OUT_MUX3_SEL")
	)
	(segment
		(start 100.203 -45.847)
		(end 103.505 -45.847)
		(width 0.127)
		(layer "In2.Cu")
		(net "FPGA_OUT_MUX3_SEL")
	)
	(segment
		(start 103.505 -45.847)
		(end 103.886 -46.228)
		(width 0.127)
		(layer "In2.Cu")
		(net "FPGA_OUT_MUX3_SEL")
	)
	(segment
		(start 103.886 -46.228)
		(end 103.886 -47.861728)
		(width 0.127)
		(layer "In2.Cu")
		(net "FPGA_OUT_MUX3_SEL")
	)
	(segment
		(start 96.139 -44.45)
		(end 99.314 -44.45)
		(width 0.127)
		(layer "In2.Cu")
		(net "FPGA_OUT_MUX3_SEL")
	)
	(segment
		(start 99.949 -45.593)
		(end 100.203 -45.847)
		(width 0.127)
		(layer "In2.Cu")
		(net "FPGA_OUT_MUX3_SEL")
	)
	(segment
		(start 99.949 -45.085)
		(end 99.949 -45.593)
		(width 0.127)
		(layer "In2.Cu")
		(net "FPGA_OUT_MUX3_SEL")
	)
	(segment
		(start 104.013 -76.327)
		(end 104.648 -76.962)
		(width 0.11938)
		(layer "F.Cu")
		(net "FPGA_OUT_MUX2_SEL")
	)
	(segment
		(start 104.847136 -45.823124)
		(end 104.347264 -46.322996)
		(width 0.11938)
		(layer "F.Cu")
		(net "FPGA_OUT_MUX2_SEL")
	)
	(segment
		(start 110.109 -76.962)
		(end 110.363 -76.708)
		(width 0.11938)
		(layer "F.Cu")
		(net "FPGA_OUT_MUX2_SEL")
	)
	(segment
		(start 100.9142 -83.5914)
		(end 99.695 -83.5914)
		(width 0.11938)
		(layer "F.Cu")
		(net "FPGA_OUT_MUX2_SEL")
	)
	(segment
		(start 103.505 -76.327)
		(end 104.013 -76.327)
		(width 0.11938)
		(layer "F.Cu")
		(net "FPGA_OUT_MUX2_SEL")
	)
	(segment
		(start 104.648 -76.962)
		(end 110.109 -76.962)
		(width 0.11938)
		(layer "F.Cu")
		(net "FPGA_OUT_MUX2_SEL")
	)
	(via
		(at 110.363 -76.708)
		(size 0.508)
		(drill 0.254)
		(layers "F.Cu" "B.Cu")
		(net "FPGA_OUT_MUX2_SEL")
	)
	(via
		(at 104.347264 -46.322996)
		(size 0.4572)
		(drill 0.2032)
		(layers "F.Cu" "B.Cu")
		(net "FPGA_OUT_MUX2_SEL")
	)
	(via
		(at 99.695 -83.5914)
		(size 0.508)
		(drill 0.254)
		(layers "F.Cu" "B.Cu")
		(net "FPGA_OUT_MUX2_SEL")
	)
	(via
		(at 103.505 -76.327)
		(size 0.508)
		(drill 0.254)
		(layers "F.Cu" "B.Cu")
		(net "FPGA_OUT_MUX2_SEL")
	)
	(segment
		(start 108.161582 -73.8251)
		(end 107.6071 -73.8251)
		(width 0.127)
		(layer "In2.Cu")
		(net "FPGA_OUT_MUX2_SEL")
	)
	(segment
		(start 108.4961 -74.159618)
		(end 108.161582 -73.8251)
		(width 0.127)
		(layer "In2.Cu")
		(net "FPGA_OUT_MUX2_SEL")
	)
	(segment
		(start 108.4961 -74.8411)
		(end 108.4961 -74.159618)
		(width 0.127)
		(layer "In2.Cu")
		(net "FPGA_OUT_MUX2_SEL")
	)
	(segment
		(start 96.5835 -58.3565)
		(end 100.054156 -54.885844)
		(width 0.127)
		(layer "In2.Cu")
		(net "FPGA_OUT_MUX2_SEL")
	)
	(segment
		(start 96.5835 -59.34456)
		(end 96.5835 -58.3565)
		(width 0.127)
		(layer "In2.Cu")
		(net "FPGA_OUT_MUX2_SEL")
	)
	(segment
		(start 97.028 -60.579)
		(end 97.028 -59.78906)
		(width 0.127)
		(layer "In2.Cu")
		(net "FPGA_OUT_MUX2_SEL")
	)
	(segment
		(start 102.8065 -77.0255)
		(end 103.505 -76.327)
		(width 0.127)
		(layer "In2.Cu")
		(net "FPGA_OUT_MUX2_SEL")
	)
	(segment
		(start 99.695 -83.5914)
		(end 99.949 -83.5914)
		(width 0.127)
		(layer "In2.Cu")
		(net "FPGA_OUT_MUX2_SEL")
	)
	(segment
		(start 110.363 -76.708)
		(end 108.4961 -74.8411)
		(width 0.127)
		(layer "In2.Cu")
		(net "FPGA_OUT_MUX2_SEL")
	)
	(segment
		(start 102.8065 -80.7339)
		(end 102.8065 -77.0255)
		(width 0.127)
		(layer "In2.Cu")
		(net "FPGA_OUT_MUX2_SEL")
	)
	(segment
		(start 101.854 -50.056542)
		(end 102.126542 -49.784)
		(width 0.127)
		(layer "In2.Cu")
		(net "FPGA_OUT_MUX2_SEL")
	)
	(segment
		(start 97.028 -59.78906)
		(end 96.5835 -59.34456)
		(width 0.127)
		(layer "In2.Cu")
		(net "FPGA_OUT_MUX2_SEL")
	)
	(segment
		(start 96.984312 -64.77)
		(end 95.4659 -63.251588)
		(width 0.127)
		(layer "In2.Cu")
		(net "FPGA_OUT_MUX2_SEL")
	)
	(segment
		(start 95.4659 -62.1411)
		(end 97.028 -60.579)
		(width 0.127)
		(layer "In2.Cu")
		(net "FPGA_OUT_MUX2_SEL")
	)
	(segment
		(start 101.578156 -54.885844)
		(end 101.854 -54.61)
		(width 0.127)
		(layer "In2.Cu")
		(net "FPGA_OUT_MUX2_SEL")
	)
	(segment
		(start 95.4659 -63.251588)
		(end 95.4659 -62.1411)
		(width 0.127)
		(layer "In2.Cu")
		(net "FPGA_OUT_MUX2_SEL")
	)
	(segment
		(start 104.902 -46.877732)
		(end 104.347264 -46.322996)
		(width 0.127)
		(layer "In2.Cu")
		(net "FPGA_OUT_MUX2_SEL")
	)
	(segment
		(start 106.172 -72.39)
		(end 106.172 -68.453)
		(width 0.127)
		(layer "In2.Cu")
		(net "FPGA_OUT_MUX2_SEL")
	)
	(segment
		(start 102.126542 -49.784)
		(end 104.521 -49.784)
		(width 0.127)
		(layer "In2.Cu")
		(net "FPGA_OUT_MUX2_SEL")
	)
	(segment
		(start 106.172 -68.453)
		(end 102.489 -64.77)
		(width 0.127)
		(layer "In2.Cu")
		(net "FPGA_OUT_MUX2_SEL")
	)
	(segment
		(start 107.6071 -73.8251)
		(end 106.172 -72.39)
		(width 0.127)
		(layer "In2.Cu")
		(net "FPGA_OUT_MUX2_SEL")
	)
	(segment
		(start 102.489 -64.77)
		(end 96.984312 -64.77)
		(width 0.127)
		(layer "In2.Cu")
		(net "FPGA_OUT_MUX2_SEL")
	)
	(segment
		(start 100.054156 -54.885844)
		(end 101.578156 -54.885844)
		(width 0.127)
		(layer "In2.Cu")
		(net "FPGA_OUT_MUX2_SEL")
	)
	(segment
		(start 104.521 -49.784)
		(end 104.902 -49.403)
		(width 0.127)
		(layer "In2.Cu")
		(net "FPGA_OUT_MUX2_SEL")
	)
	(segment
		(start 101.854 -54.61)
		(end 101.854 -50.056542)
		(width 0.127)
		(layer "In2.Cu")
		(net "FPGA_OUT_MUX2_SEL")
	)
	(segment
		(start 104.902 -49.403)
		(end 104.902 -46.877732)
		(width 0.127)
		(layer "In2.Cu")
		(net "FPGA_OUT_MUX2_SEL")
	)
	(segment
		(start 99.949 -83.5914)
		(end 102.8065 -80.7339)
		(width 0.127)
		(layer "In2.Cu")
		(net "FPGA_OUT_MUX2_SEL")
	)
	(segment
		(start 104.902 -76.327)
		(end 105.156 -76.073)
		(width 0.11938)
		(layer "F.Cu")
		(net "FPGA_OUT_MUX1_SEL")
	)
	(segment
		(start 105.156 -76.073)
		(end 110.871 -76.073)
		(width 0.11938)
		(layer "F.Cu")
		(net "FPGA_OUT_MUX1_SEL")
	)
	(segment
		(start 105.847134 -45.823124)
		(end 105.347262 -46.322996)
		(width 0.11938)
		(layer "F.Cu")
		(net "FPGA_OUT_MUX1_SEL")
	)
	(segment
		(start 110.871 -76.073)
		(end 111.506 -76.708)
		(width 0.11938)
		(layer "F.Cu")
		(net "FPGA_OUT_MUX1_SEL")
	)
	(segment
		(start 97.5106 -96.774)
		(end 96.393 -96.774)
		(width 0.11938)
		(layer "F.Cu")
		(net "FPGA_OUT_MUX1_SEL")
	)
	(via
		(at 96.393 -96.774)
		(size 0.508)
		(drill 0.254)
		(layers "F.Cu" "B.Cu")
		(net "FPGA_OUT_MUX1_SEL")
	)
	(via
		(at 111.506 -76.708)
		(size 0.508)
		(drill 0.254)
		(layers "F.Cu" "B.Cu")
		(net "FPGA_OUT_MUX1_SEL")
	)
	(via
		(at 104.902 -76.327)
		(size 0.508)
		(drill 0.254)
		(layers "F.Cu" "B.Cu")
		(net "FPGA_OUT_MUX1_SEL")
	)
	(via
		(at 105.347262 -46.322996)
		(size 0.4572)
		(drill 0.2032)
		(layers "F.Cu" "B.Cu")
		(net "FPGA_OUT_MUX1_SEL")
	)
	(segment
		(start 109.0041 -73.949052)
		(end 108.372148 -73.3171)
		(width 0.127)
		(layer "In2.Cu")
		(net "FPGA_OUT_MUX1_SEL")
	)
	(segment
		(start 95.9739 -62.395354)
		(end 98.3615 -60.007754)
		(width 0.127)
		(layer "In2.Cu")
		(net "FPGA_OUT_MUX1_SEL")
	)
	(segment
		(start 106.041952 -93.726)
		(end 102.64394 -93.726)
		(width 0.127)
		(layer "In2.Cu")
		(net "FPGA_OUT_MUX1_SEL")
	)
	(segment
		(start 107.33786 -83.59902)
		(end 107.33786 -85.49386)
		(width 0.127)
		(layer "In2.Cu")
		(net "FPGA_OUT_MUX1_SEL")
	)
	(segment
		(start 106.359452 -94.0435)
		(end 106.041952 -93.726)
		(width 0.127)
		(layer "In2.Cu")
		(net "FPGA_OUT_MUX1_SEL")
	)
	(segment
		(start 105.918 -46.893734)
		(end 105.347262 -46.322996)
		(width 0.127)
		(layer "In2.Cu")
		(net "FPGA_OUT_MUX1_SEL")
	)
	(segment
		(start 102.87 -54.102)
		(end 102.87 -52.197)
		(width 0.127)
		(layer "In2.Cu")
		(net "FPGA_OUT_MUX1_SEL")
	)
	(segment
		(start 102.87 -52.197)
		(end 103.251 -51.816)
		(width 0.127)
		(layer "In2.Cu")
		(net "FPGA_OUT_MUX1_SEL")
	)
	(segment
		(start 105.16616 -76.59116)
		(end 105.16616 -81.42732)
		(width 0.127)
		(layer "In2.Cu")
		(net "FPGA_OUT_MUX1_SEL")
	)
	(segment
		(start 104.902 -76.327)
		(end 105.16616 -76.59116)
		(width 0.127)
		(layer "In2.Cu")
		(net "FPGA_OUT_MUX1_SEL")
	)
	(segment
		(start 99.187 -56.515)
		(end 100.457 -55.245)
		(width 0.127)
		(layer "In2.Cu")
		(net "FPGA_OUT_MUX1_SEL")
	)
	(segment
		(start 100.457 -55.245)
		(end 101.727 -55.245)
		(width 0.127)
		(layer "In2.Cu")
		(net "FPGA_OUT_MUX1_SEL")
	)
	(segment
		(start 111.506 -76.708)
		(end 109.0041 -74.2061)
		(width 0.127)
		(layer "In2.Cu")
		(net "FPGA_OUT_MUX1_SEL")
	)
	(segment
		(start 107.33786 -85.49386)
		(end 109.474 -87.63)
		(width 0.127)
		(layer "In2.Cu")
		(net "FPGA_OUT_MUX1_SEL")
	)
	(segment
		(start 97.311718 -64.262)
		(end 95.9739 -62.924182)
		(width 0.127)
		(layer "In2.Cu")
		(net "FPGA_OUT_MUX1_SEL")
	)
	(segment
		(start 99.187 -57.93994)
		(end 99.187 -56.515)
		(width 0.127)
		(layer "In2.Cu")
		(net "FPGA_OUT_MUX1_SEL")
	)
	(segment
		(start 106.807 -68.326)
		(end 102.743 -64.262)
		(width 0.127)
		(layer "In2.Cu")
		(net "FPGA_OUT_MUX1_SEL")
	)
	(segment
		(start 102.64394 -93.726)
		(end 99.59594 -96.774)
		(width 0.127)
		(layer "In2.Cu")
		(net "FPGA_OUT_MUX1_SEL")
	)
	(segment
		(start 105.664 -51.816)
		(end 105.918 -51.562)
		(width 0.127)
		(layer "In2.Cu")
		(net "FPGA_OUT_MUX1_SEL")
	)
	(segment
		(start 95.9739 -62.924182)
		(end 95.9739 -62.395354)
		(width 0.127)
		(layer "In2.Cu")
		(net "FPGA_OUT_MUX1_SEL")
	)
	(segment
		(start 105.918 -51.562)
		(end 105.918 -46.893734)
		(width 0.127)
		(layer "In2.Cu")
		(net "FPGA_OUT_MUX1_SEL")
	)
	(segment
		(start 98.3615 -60.007754)
		(end 98.3615 -58.76544)
		(width 0.127)
		(layer "In2.Cu")
		(net "FPGA_OUT_MUX1_SEL")
	)
	(segment
		(start 101.727 -55.245)
		(end 102.87 -54.102)
		(width 0.127)
		(layer "In2.Cu")
		(net "FPGA_OUT_MUX1_SEL")
	)
	(segment
		(start 106.807 -72.262746)
		(end 106.807 -68.326)
		(width 0.127)
		(layer "In2.Cu")
		(net "FPGA_OUT_MUX1_SEL")
	)
	(segment
		(start 99.59594 -96.774)
		(end 96.393 -96.774)
		(width 0.127)
		(layer "In2.Cu")
		(net "FPGA_OUT_MUX1_SEL")
	)
	(segment
		(start 109.474 -89.154)
		(end 109.347 -89.281)
		(width 0.127)
		(layer "In2.Cu")
		(net "FPGA_OUT_MUX1_SEL")
	)
	(segment
		(start 109.474 -87.63)
		(end 109.474 -89.154)
		(width 0.127)
		(layer "In2.Cu")
		(net "FPGA_OUT_MUX1_SEL")
	)
	(segment
		(start 109.347 -92.031566)
		(end 107.335066 -94.0435)
		(width 0.127)
		(layer "In2.Cu")
		(net "FPGA_OUT_MUX1_SEL")
	)
	(segment
		(start 108.372148 -73.3171)
		(end 107.861354 -73.3171)
		(width 0.127)
		(layer "In2.Cu")
		(net "FPGA_OUT_MUX1_SEL")
	)
	(segment
		(start 98.3615 -58.76544)
		(end 99.187 -57.93994)
		(width 0.127)
		(layer "In2.Cu")
		(net "FPGA_OUT_MUX1_SEL")
	)
	(segment
		(start 109.347 -89.281)
		(end 109.347 -92.031566)
		(width 0.127)
		(layer "In2.Cu")
		(net "FPGA_OUT_MUX1_SEL")
	)
	(segment
		(start 102.743 -64.262)
		(end 97.311718 -64.262)
		(width 0.127)
		(layer "In2.Cu")
		(net "FPGA_OUT_MUX1_SEL")
	)
	(segment
		(start 103.251 -51.816)
		(end 105.664 -51.816)
		(width 0.127)
		(layer "In2.Cu")
		(net "FPGA_OUT_MUX1_SEL")
	)
	(segment
		(start 107.335066 -94.0435)
		(end 106.359452 -94.0435)
		(width 0.127)
		(layer "In2.Cu")
		(net "FPGA_OUT_MUX1_SEL")
	)
	(segment
		(start 107.861354 -73.3171)
		(end 106.807 -72.262746)
		(width 0.127)
		(layer "In2.Cu")
		(net "FPGA_OUT_MUX1_SEL")
	)
	(segment
		(start 105.16616 -81.42732)
		(end 107.33786 -83.59902)
		(width 0.127)
		(layer "In2.Cu")
		(net "FPGA_OUT_MUX1_SEL")
	)
	(segment
		(start 109.0041 -74.2061)
		(end 109.0041 -73.949052)
		(width 0.127)
		(layer "In2.Cu")
		(net "FPGA_OUT_MUX1_SEL")
	)
	(segment
		(start 111.506 -84.709)
		(end 111.506 -84.963)
		(width 0.11938)
		(layer "F.Cu")
		(net "FPGA_IO_FT_USBDET_RST_N")
	)
	(segment
		(start 110.236 -86.233)
		(end 110.236 -87.7316)
		(width 0.11938)
		(layer "F.Cu")
		(net "FPGA_IO_FT_USBDET_RST_N")
	)
	(segment
		(start 118.847108 -47.82312)
		(end 119.34698 -48.322992)
		(width 0.11938)
		(layer "F.Cu")
		(net "FPGA_IO_FT_USBDET_RST_N")
	)
	(segment
		(start 111.76 -84.455)
		(end 111.506 -84.709)
		(width 0.11938)
		(layer "F.Cu")
		(net "FPGA_IO_FT_USBDET_RST_N")
	)
	(segment
		(start 111.506 -84.963)
		(end 110.236 -86.233)
		(width 0.11938)
		(layer "F.Cu")
		(net "FPGA_IO_FT_USBDET_RST_N")
	)
	(via
		(at 119.34698 -48.322992)
		(size 0.4572)
		(drill 0.2032)
		(layers "F.Cu" "B.Cu")
		(net "FPGA_IO_FT_USBDET_RST_N")
	)
	(via
		(at 117.221 -78.994)
		(size 0.508)
		(drill 0.254)
		(layers "F.Cu" "B.Cu")
		(net "FPGA_IO_FT_USBDET_RST_N")
	)
	(via
		(at 111.76 -84.455)
		(size 0.508)
		(drill 0.254)
		(layers "F.Cu" "B.Cu")
		(net "FPGA_IO_FT_USBDET_RST_N")
	)
	(segment
		(start 117.221 -79.629)
		(end 117.221 -78.994)
		(width 0.11938)
		(layer "B.Cu")
		(net "FPGA_IO_FT_USBDET_RST_N")
	)
	(segment
		(start 111.76 -84.455)
		(end 112.395 -84.455)
		(width 0.11938)
		(layer "B.Cu")
		(net "FPGA_IO_FT_USBDET_RST_N")
	)
	(segment
		(start 112.395 -84.455)
		(end 117.221 -79.629)
		(width 0.11938)
		(layer "B.Cu")
		(net "FPGA_IO_FT_USBDET_RST_N")
	)
	(segment
		(start 117.856 -59.817)
		(end 117.856 -57.912)
		(width 0.127)
		(layer "In2.Cu")
		(net "FPGA_IO_FT_USBDET_RST_N")
	)
	(segment
		(start 119.8245 -48.800512)
		(end 119.34698 -48.322992)
		(width 0.127)
		(layer "In2.Cu")
		(net "FPGA_IO_FT_USBDET_RST_N")
	)
	(segment
		(start 121.031 -51.689)
		(end 119.8245 -50.4825)
		(width 0.127)
		(layer "In2.Cu")
		(net "FPGA_IO_FT_USBDET_RST_N")
	)
	(segment
		(start 120.523 -56.007)
		(end 121.031 -55.499)
		(width 0.127)
		(layer "In2.Cu")
		(net "FPGA_IO_FT_USBDET_RST_N")
	)
	(segment
		(start 119.761 -56.007)
		(end 120.523 -56.007)
		(width 0.127)
		(layer "In2.Cu")
		(net "FPGA_IO_FT_USBDET_RST_N")
	)
	(segment
		(start 116.7765 -63.736982)
		(end 116.7765 -60.8965)
		(width 0.127)
		(layer "In2.Cu")
		(net "FPGA_IO_FT_USBDET_RST_N")
	)
	(segment
		(start 116.967 -75.692)
		(end 116.078 -75.692)
		(width 0.127)
		(layer "In2.Cu")
		(net "FPGA_IO_FT_USBDET_RST_N")
	)
	(segment
		(start 117.856 -57.912)
		(end 119.761 -56.007)
		(width 0.127)
		(layer "In2.Cu")
		(net "FPGA_IO_FT_USBDET_RST_N")
	)
	(segment
		(start 115.443 -75.057)
		(end 115.443 -65.070482)
		(width 0.127)
		(layer "In2.Cu")
		(net "FPGA_IO_FT_USBDET_RST_N")
	)
	(segment
		(start 116.7765 -60.8965)
		(end 117.856 -59.817)
		(width 0.127)
		(layer "In2.Cu")
		(net "FPGA_IO_FT_USBDET_RST_N")
	)
	(segment
		(start 117.983 -78.232)
		(end 117.983 -76.708)
		(width 0.127)
		(layer "In2.Cu")
		(net "FPGA_IO_FT_USBDET_RST_N")
	)
	(segment
		(start 121.031 -55.499)
		(end 121.031 -51.689)
		(width 0.127)
		(layer "In2.Cu")
		(net "FPGA_IO_FT_USBDET_RST_N")
	)
	(segment
		(start 119.8245 -50.4825)
		(end 119.8245 -48.800512)
		(width 0.127)
		(layer "In2.Cu")
		(net "FPGA_IO_FT_USBDET_RST_N")
	)
	(segment
		(start 117.221 -78.994)
		(end 117.983 -78.232)
		(width 0.127)
		(layer "In2.Cu")
		(net "FPGA_IO_FT_USBDET_RST_N")
	)
	(segment
		(start 117.983 -76.708)
		(end 116.967 -75.692)
		(width 0.127)
		(layer "In2.Cu")
		(net "FPGA_IO_FT_USBDET_RST_N")
	)
	(segment
		(start 115.443 -65.070482)
		(end 116.7765 -63.736982)
		(width 0.127)
		(layer "In2.Cu")
		(net "FPGA_IO_FT_USBDET_RST_N")
	)
	(segment
		(start 116.078 -75.692)
		(end 115.443 -75.057)
		(width 0.127)
		(layer "In2.Cu")
		(net "FPGA_IO_FT_USBDET_RST_N")
	)
	(segment
		(start 110.30331 -56.53151)
		(end 109.3216 -55.5498)
		(width 0.11938)
		(layer "F.Cu")
		(net "FPGA_IO_7")
	)
	(segment
		(start 105.41 -63.754)
		(end 105.41 -62.6872)
		(width 0.11938)
		(layer "F.Cu")
		(net "FPGA_IO_7")
	)
	(segment
		(start 110.30331 -60.23229)
		(end 110.30331 -56.53151)
		(width 0.11938)
		(layer "F.Cu")
		(net "FPGA_IO_7")
	)
	(segment
		(start 105.97769 -62.11951)
		(end 108.41609 -62.11951)
		(width 0.11938)
		(layer "F.Cu")
		(net "FPGA_IO_7")
	)
	(segment
		(start 109.3216 -55.5498)
		(end 109.3216 -54.29758)
		(width 0.11938)
		(layer "F.Cu")
		(net "FPGA_IO_7")
	)
	(segment
		(start 105.41 -62.6872)
		(end 105.97769 -62.11951)
		(width 0.11938)
		(layer "F.Cu")
		(net "FPGA_IO_7")
	)
	(segment
		(start 109.3216 -54.29758)
		(end 108.847128 -53.823108)
		(width 0.11938)
		(layer "F.Cu")
		(net "FPGA_IO_7")
	)
	(segment
		(start 108.41609 -62.11951)
		(end 110.30331 -60.23229)
		(width 0.11938)
		(layer "F.Cu")
		(net "FPGA_IO_7")
	)
	(via
		(at 157.988 -35.941)
		(size 0.508)
		(drill 0.254)
		(layers "F.Cu" "B.Cu")
		(net "FPGA_IO_7")
	)
	(via
		(at 105.41 -62.6872)
		(size 0.508)
		(drill 0.254)
		(layers "F.Cu" "B.Cu")
		(net "FPGA_IO_7")
	)
	(via
		(at 117.221 -68.175886)
		(size 0.508)
		(drill 0.254)
		(layers "F.Cu" "B.Cu")
		(net "FPGA_IO_7")
	)
	(segment
		(start 117.221 -68.175886)
		(end 115.820952 -68.175886)
		(width 0.11938)
		(layer "B.Cu")
		(net "FPGA_IO_7")
	)
	(segment
		(start 157.5054 -36.4236)
		(end 157.988 -35.941)
		(width 0.11938)
		(layer "B.Cu")
		(net "FPGA_IO_7")
	)
	(segment
		(start 105.41 -63.754)
		(end 105.41 -62.6872)
		(width 0.11938)
		(layer "B.Cu")
		(net "FPGA_IO_7")
	)
	(segment
		(start 105.968546 -62.6872)
		(end 105.41 -62.6872)
		(width 0.11938)
		(layer "B.Cu")
		(net "FPGA_IO_7")
	)
	(segment
		(start 107.696 -62.671706)
		(end 107.143804 -62.11951)
		(width 0.11938)
		(layer "B.Cu")
		(net "FPGA_IO_7")
	)
	(segment
		(start 106.536236 -62.11951)
		(end 105.968546 -62.6872)
		(width 0.11938)
		(layer "B.Cu")
		(net "FPGA_IO_7")
	)
	(segment
		(start 115.820952 -68.175886)
		(end 113.840006 -66.19494)
		(width 0.11938)
		(layer "B.Cu")
		(net "FPGA_IO_7")
	)
	(segment
		(start 107.143804 -62.11951)
		(end 106.536236 -62.11951)
		(width 0.11938)
		(layer "B.Cu")
		(net "FPGA_IO_7")
	)
	(segment
		(start 107.696 -64.725042)
		(end 107.696 -62.671706)
		(width 0.11938)
		(layer "B.Cu")
		(net "FPGA_IO_7")
	)
	(segment
		(start 156.718 -36.4236)
		(end 157.5054 -36.4236)
		(width 0.11938)
		(layer "B.Cu")
		(net "FPGA_IO_7")
	)
	(segment
		(start 109.165898 -66.19494)
		(end 107.696 -64.725042)
		(width 0.11938)
		(layer "B.Cu")
		(net "FPGA_IO_7")
	)
	(segment
		(start 113.840006 -66.19494)
		(end 109.165898 -66.19494)
		(width 0.11938)
		(layer "B.Cu")
		(net "FPGA_IO_7")
	)
	(segment
		(start 127.254254 -51.816)
		(end 128.183132 -51.816)
		(width 0.127)
		(layer "In2.Cu")
		(net "FPGA_IO_7")
	)
	(segment
		(start 122.682 -58.078878)
		(end 122.9995 -57.761378)
		(width 0.127)
		(layer "In2.Cu")
		(net "FPGA_IO_7")
	)
	(segment
		(start 134.239 -41.860216)
		(end 134.239 -40.259254)
		(width 0.127)
		(layer "In2.Cu")
		(net "FPGA_IO_7")
	)
	(segment
		(start 128.183132 -51.816)
		(end 130.556 -49.443132)
		(width 0.127)
		(layer "In2.Cu")
		(net "FPGA_IO_7")
	)
	(segment
		(start 118.514114 -68.175886)
		(end 118.6815 -68.0085)
		(width 0.127)
		(layer "In2.Cu")
		(net "FPGA_IO_7")
	)
	(segment
		(start 134.239 -40.259254)
		(end 135.318754 -39.1795)
		(width 0.127)
		(layer "In2.Cu")
		(net "FPGA_IO_7")
	)
	(segment
		(start 122.682 -65.58788)
		(end 122.682 -58.078878)
		(width 0.127)
		(layer "In2.Cu")
		(net "FPGA_IO_7")
	)
	(segment
		(start 124.670312 -53.467)
		(end 125.603254 -53.467)
		(width 0.127)
		(layer "In2.Cu")
		(net "FPGA_IO_7")
	)
	(segment
		(start 118.6815 -68.0085)
		(end 120.26138 -68.0085)
		(width 0.127)
		(layer "In2.Cu")
		(net "FPGA_IO_7")
	)
	(segment
		(start 117.221 -68.175886)
		(end 118.514114 -68.175886)
		(width 0.127)
		(layer "In2.Cu")
		(net "FPGA_IO_7")
	)
	(segment
		(start 136.025382 -39.1795)
		(end 137.358882 -37.846)
		(width 0.127)
		(layer "In2.Cu")
		(net "FPGA_IO_7")
	)
	(segment
		(start 122.9995 -55.137812)
		(end 124.670312 -53.467)
		(width 0.127)
		(layer "In2.Cu")
		(net "FPGA_IO_7")
	)
	(segment
		(start 137.358882 -37.846)
		(end 156.083 -37.846)
		(width 0.127)
		(layer "In2.Cu")
		(net "FPGA_IO_7")
	)
	(segment
		(start 120.26138 -68.0085)
		(end 122.682 -65.58788)
		(width 0.127)
		(layer "In2.Cu")
		(net "FPGA_IO_7")
	)
	(segment
		(start 156.083 -37.846)
		(end 157.988 -35.941)
		(width 0.127)
		(layer "In2.Cu")
		(net "FPGA_IO_7")
	)
	(segment
		(start 122.9995 -57.761378)
		(end 122.9995 -55.137812)
		(width 0.127)
		(layer "In2.Cu")
		(net "FPGA_IO_7")
	)
	(segment
		(start 125.603254 -53.467)
		(end 127.254254 -51.816)
		(width 0.127)
		(layer "In2.Cu")
		(net "FPGA_IO_7")
	)
	(segment
		(start 130.556 -45.543216)
		(end 134.239 -41.860216)
		(width 0.127)
		(layer "In2.Cu")
		(net "FPGA_IO_7")
	)
	(segment
		(start 135.318754 -39.1795)
		(end 136.025382 -39.1795)
		(width 0.127)
		(layer "In2.Cu")
		(net "FPGA_IO_7")
	)
	(segment
		(start 130.556 -49.443132)
		(end 130.556 -45.543216)
		(width 0.127)
		(layer "In2.Cu")
		(net "FPGA_IO_7")
	)
	(segment
		(start 117.729 -66.929)
		(end 117.729 -65.278)
		(width 0.11938)
		(layer "F.Cu")
		(net "FPGA_IO_6")
	)
	(segment
		(start 118.999 -68.58)
		(end 118.364 -67.945)
		(width 0.11938)
		(layer "F.Cu")
		(net "FPGA_IO_6")
	)
	(segment
		(start 118.364 -67.564)
		(end 117.729 -66.929)
		(width 0.11938)
		(layer "F.Cu")
		(net "FPGA_IO_6")
	)
	(segment
		(start 110.363 -64.516)
		(end 109.601 -63.754)
		(width 0.11938)
		(layer "F.Cu")
		(net "FPGA_IO_6")
	)
	(segment
		(start 109.601 -63.754)
		(end 106.9086 -63.754)
		(width 0.11938)
		(layer "F.Cu")
		(net "FPGA_IO_6")
	)
	(segment
		(start 118.364 -67.945)
		(end 118.364 -67.564)
		(width 0.11938)
		(layer "F.Cu")
		(net "FPGA_IO_6")
	)
	(segment
		(start 116.967 -64.516)
		(end 110.363 -64.516)
		(width 0.11938)
		(layer "F.Cu")
		(net "FPGA_IO_6")
	)
	(segment
		(start 117.729 -65.278)
		(end 116.967 -64.516)
		(width 0.11938)
		(layer "F.Cu")
		(net "FPGA_IO_6")
	)
	(segment
		(start 106.9086 -63.754)
		(end 106.9086 -62.6872)
		(width 0.11938)
		(layer "F.Cu")
		(net "FPGA_IO_6")
	)
	(segment
		(start 109.847126 -53.823108)
		(end 110.346998 -54.32298)
		(width 0.11938)
		(layer "F.Cu")
		(net "FPGA_IO_6")
	)
	(via
		(at 106.9086 -62.6872)
		(size 0.508)
		(drill 0.254)
		(layers "F.Cu" "B.Cu")
		(net "FPGA_IO_6")
	)
	(via
		(at 157.988 -38.5064)
		(size 0.508)
		(drill 0.254)
		(layers "F.Cu" "B.Cu")
		(net "FPGA_IO_6")
	)
	(via
		(at 118.999 -68.58)
		(size 0.508)
		(drill 0.254)
		(layers "F.Cu" "B.Cu")
		(net "FPGA_IO_6")
	)
	(via
		(at 110.346998 -54.32298)
		(size 0.4572)
		(drill 0.2032)
		(layers "F.Cu" "B.Cu")
		(net "FPGA_IO_6")
	)
	(segment
		(start 106.9086 -63.754)
		(end 106.9086 -62.6872)
		(width 0.11938)
		(layer "B.Cu")
		(net "FPGA_IO_6")
	)
	(segment
		(start 157.5308 -38.9636)
		(end 157.988 -38.5064)
		(width 0.11938)
		(layer "B.Cu")
		(net "FPGA_IO_6")
	)
	(segment
		(start 156.718 -38.9636)
		(end 157.5308 -38.9636)
		(width 0.11938)
		(layer "B.Cu")
		(net "FPGA_IO_6")
	)
	(segment
		(start 148.59 -39.116)
		(end 150.622 -39.116)
		(width 0.127)
		(layer "In2.Cu")
		(net "FPGA_IO_6")
	)
	(segment
		(start 119.042434 -68.623434)
		(end 120.185434 -68.623434)
		(width 0.127)
		(layer "In2.Cu")
		(net "FPGA_IO_6")
	)
	(segment
		(start 127.412242 -52.197)
		(end 128.34112 -52.197)
		(width 0.127)
		(layer "In2.Cu")
		(net "FPGA_IO_6")
	)
	(segment
		(start 111.125 -61.214)
		(end 108.3818 -61.214)
		(width 0.127)
		(layer "In2.Cu")
		(net "FPGA_IO_6")
	)
	(segment
		(start 123.3805 -55.3085)
		(end 124.841 -53.848)
		(width 0.127)
		(layer "In2.Cu")
		(net "FPGA_IO_6")
	)
	(segment
		(start 124.841 -53.848)
		(end 125.761242 -53.848)
		(width 0.127)
		(layer "In2.Cu")
		(net "FPGA_IO_6")
	)
	(segment
		(start 134.62 -40.417242)
		(end 135.476742 -39.5605)
		(width 0.127)
		(layer "In2.Cu")
		(net "FPGA_IO_6")
	)
	(segment
		(start 128.34112 -52.197)
		(end 130.937 -49.60112)
		(width 0.127)
		(layer "In2.Cu")
		(net "FPGA_IO_6")
	)
	(segment
		(start 109.7788 -57.2008)
		(end 111.506 -58.928)
		(width 0.127)
		(layer "In2.Cu")
		(net "FPGA_IO_6")
	)
	(segment
		(start 108.3818 -61.214)
		(end 106.9086 -62.6872)
		(width 0.127)
		(layer "In2.Cu")
		(net "FPGA_IO_6")
	)
	(segment
		(start 136.18337 -39.5605)
		(end 137.51687 -38.227)
		(width 0.127)
		(layer "In2.Cu")
		(net "FPGA_IO_6")
	)
	(segment
		(start 111.506 -60.833)
		(end 111.125 -61.214)
		(width 0.127)
		(layer "In2.Cu")
		(net "FPGA_IO_6")
	)
	(segment
		(start 151.2316 -38.5064)
		(end 157.988 -38.5064)
		(width 0.127)
		(layer "In2.Cu")
		(net "FPGA_IO_6")
	)
	(segment
		(start 130.937 -45.701204)
		(end 134.62 -42.018204)
		(width 0.127)
		(layer "In2.Cu")
		(net "FPGA_IO_6")
	)
	(segment
		(start 111.506 -58.928)
		(end 111.506 -60.833)
		(width 0.127)
		(layer "In2.Cu")
		(net "FPGA_IO_6")
	)
	(segment
		(start 135.476742 -39.5605)
		(end 136.18337 -39.5605)
		(width 0.127)
		(layer "In2.Cu")
		(net "FPGA_IO_6")
	)
	(segment
		(start 150.622 -39.116)
		(end 151.2316 -38.5064)
		(width 0.127)
		(layer "In2.Cu")
		(net "FPGA_IO_6")
	)
	(segment
		(start 109.7788 -54.891178)
		(end 109.7788 -57.2008)
		(width 0.127)
		(layer "In2.Cu")
		(net "FPGA_IO_6")
	)
	(segment
		(start 147.701 -38.227)
		(end 148.59 -39.116)
		(width 0.127)
		(layer "In2.Cu")
		(net "FPGA_IO_6")
	)
	(segment
		(start 123.063 -58.236866)
		(end 123.3805 -57.919366)
		(width 0.127)
		(layer "In2.Cu")
		(net "FPGA_IO_6")
	)
	(segment
		(start 123.063 -65.745868)
		(end 123.063 -58.236866)
		(width 0.127)
		(layer "In2.Cu")
		(net "FPGA_IO_6")
	)
	(segment
		(start 125.761242 -53.848)
		(end 127.412242 -52.197)
		(width 0.127)
		(layer "In2.Cu")
		(net "FPGA_IO_6")
	)
	(segment
		(start 137.51687 -38.227)
		(end 147.701 -38.227)
		(width 0.127)
		(layer "In2.Cu")
		(net "FPGA_IO_6")
	)
	(segment
		(start 110.346998 -54.32298)
		(end 109.7788 -54.891178)
		(width 0.127)
		(layer "In2.Cu")
		(net "FPGA_IO_6")
	)
	(segment
		(start 120.185434 -68.623434)
		(end 123.063 -65.745868)
		(width 0.127)
		(layer "In2.Cu")
		(net "FPGA_IO_6")
	)
	(segment
		(start 123.3805 -57.919366)
		(end 123.3805 -55.3085)
		(width 0.127)
		(layer "In2.Cu")
		(net "FPGA_IO_6")
	)
	(segment
		(start 118.999 -68.58)
		(end 119.042434 -68.623434)
		(width 0.127)
		(layer "In2.Cu")
		(net "FPGA_IO_6")
	)
	(segment
		(start 130.937 -49.60112)
		(end 130.937 -45.701204)
		(width 0.127)
		(layer "In2.Cu")
		(net "FPGA_IO_6")
	)
	(segment
		(start 134.62 -42.018204)
		(end 134.62 -40.417242)
		(width 0.127)
		(layer "In2.Cu")
		(net "FPGA_IO_6")
	)
	(segment
		(start 107.84713 -55.37454)
		(end 107.84713 -54.823106)
		(width 0.11938)
		(layer "F.Cu")
		(net "FPGA_IO_5")
	)
	(segment
		(start 104.90327 -61.74613)
		(end 108.26115 -61.74613)
		(width 0.11938)
		(layer "F.Cu")
		(net "FPGA_IO_5")
	)
	(segment
		(start 103.9622 -63.754)
		(end 103.9622 -62.6872)
		(width 0.11938)
		(layer "F.Cu")
		(net "FPGA_IO_5")
	)
	(segment
		(start 109.92993 -57.45734)
		(end 107.84713 -55.37454)
		(width 0.11938)
		(layer "F.Cu")
		(net "FPGA_IO_5")
	)
	(segment
		(start 109.92993 -60.07735)
		(end 109.92993 -57.45734)
		(width 0.11938)
		(layer "F.Cu")
		(net "FPGA_IO_5")
	)
	(segment
		(start 103.9622 -62.6872)
		(end 104.90327 -61.74613)
		(width 0.11938)
		(layer "F.Cu")
		(net "FPGA_IO_5")
	)
	(segment
		(start 108.26115 -61.74613)
		(end 109.92993 -60.07735)
		(width 0.11938)
		(layer "F.Cu")
		(net "FPGA_IO_5")
	)
	(via
		(at 103.9622 -62.6872)
		(size 0.508)
		(drill 0.254)
		(layers "F.Cu" "B.Cu")
		(net "FPGA_IO_5")
	)
	(via
		(at 157.988 -41.148)
		(size 0.508)
		(drill 0.254)
		(layers "F.Cu" "B.Cu")
		(net "FPGA_IO_5")
	)
	(via
		(at 126.365 -57.404)
		(size 0.508)
		(drill 0.254)
		(layers "F.Cu" "B.Cu")
		(net "FPGA_IO_5")
	)
	(segment
		(start 109.320584 -65.82156)
		(end 108.077 -64.577976)
		(width 0.11938)
		(layer "B.Cu")
		(net "FPGA_IO_5")
	)
	(segment
		(start 123.444 -59.690254)
		(end 123.444 -65.405)
		(width 0.11938)
		(layer "B.Cu")
		(net "FPGA_IO_5")
	)
	(segment
		(start 106.38155 -61.74613)
		(end 106.15168 -61.976)
		(width 0.11938)
		(layer "B.Cu")
		(net "FPGA_IO_5")
	)
	(segment
		(start 116.57838 -67.55638)
		(end 116.177314 -67.55638)
		(width 0.11938)
		(layer "B.Cu")
		(net "FPGA_IO_5")
	)
	(segment
		(start 120.904 -67.945)
		(end 118.491 -67.945)
		(width 0.11938)
		(layer "B.Cu")
		(net "FPGA_IO_5")
	)
	(segment
		(start 157.6324 -41.5036)
		(end 157.988 -41.148)
		(width 0.11938)
		(layer "B.Cu")
		(net "FPGA_IO_5")
	)
	(segment
		(start 116.177314 -67.55638)
		(end 114.442494 -65.82156)
		(width 0.11938)
		(layer "B.Cu")
		(net "FPGA_IO_5")
	)
	(segment
		(start 124.460254 -58.674)
		(end 123.444 -59.690254)
		(width 0.11938)
		(layer "B.Cu")
		(net "FPGA_IO_5")
	)
	(segment
		(start 126.365 -57.404)
		(end 125.095 -58.674)
		(width 0.11938)
		(layer "B.Cu")
		(net "FPGA_IO_5")
	)
	(segment
		(start 118.491 -67.945)
		(end 118.11 -67.564)
		(width 0.11938)
		(layer "B.Cu")
		(net "FPGA_IO_5")
	)
	(segment
		(start 104.4448 -62.6872)
		(end 103.9622 -62.6872)
		(width 0.11938)
		(layer "B.Cu")
		(net "FPGA_IO_5")
	)
	(segment
		(start 125.095 -58.674)
		(end 124.460254 -58.674)
		(width 0.11938)
		(layer "B.Cu")
		(net "FPGA_IO_5")
	)
	(segment
		(start 105.156 -61.976)
		(end 104.4448 -62.6872)
		(width 0.11938)
		(layer "B.Cu")
		(net "FPGA_IO_5")
	)
	(segment
		(start 123.444 -65.405)
		(end 120.904 -67.945)
		(width 0.11938)
		(layer "B.Cu")
		(net "FPGA_IO_5")
	)
	(segment
		(start 107.29849 -61.74613)
		(end 106.38155 -61.74613)
		(width 0.11938)
		(layer "B.Cu")
		(net "FPGA_IO_5")
	)
	(segment
		(start 118.11 -67.564)
		(end 116.586 -67.564)
		(width 0.11938)
		(layer "B.Cu")
		(net "FPGA_IO_5")
	)
	(segment
		(start 156.718 -41.5036)
		(end 157.6324 -41.5036)
		(width 0.11938)
		(layer "B.Cu")
		(net "FPGA_IO_5")
	)
	(segment
		(start 108.069634 -62.517274)
		(end 107.29849 -61.74613)
		(width 0.11938)
		(layer "B.Cu")
		(net "FPGA_IO_5")
	)
	(segment
		(start 106.15168 -61.976)
		(end 105.156 -61.976)
		(width 0.11938)
		(layer "B.Cu")
		(net "FPGA_IO_5")
	)
	(segment
		(start 108.077 -62.611)
		(end 108.069634 -62.603634)
		(width 0.11938)
		(layer "B.Cu")
		(net "FPGA_IO_5")
	)
	(segment
		(start 114.442494 -65.82156)
		(end 109.320584 -65.82156)
		(width 0.11938)
		(layer "B.Cu")
		(net "FPGA_IO_5")
	)
	(segment
		(start 103.9622 -63.754)
		(end 103.9622 -62.6872)
		(width 0.11938)
		(layer "B.Cu")
		(net "FPGA_IO_5")
	)
	(segment
		(start 108.077 -64.577976)
		(end 108.077 -62.611)
		(width 0.11938)
		(layer "B.Cu")
		(net "FPGA_IO_5")
	)
	(segment
		(start 108.069634 -62.603634)
		(end 108.069634 -62.517274)
		(width 0.11938)
		(layer "B.Cu")
		(net "FPGA_IO_5")
	)
	(segment
		(start 116.586 -67.564)
		(end 116.57838 -67.55638)
		(width 0.11938)
		(layer "B.Cu")
		(net "FPGA_IO_5")
	)
	(segment
		(start 131.318 -49.784254)
		(end 131.318 -46.100746)
		(width 0.127)
		(layer "In2.Cu")
		(net "FPGA_IO_5")
	)
	(segment
		(start 147.955 -39.116)
		(end 149.352 -40.513)
		(width 0.127)
		(layer "In2.Cu")
		(net "FPGA_IO_5")
	)
	(segment
		(start 126.365 -55.291482)
		(end 127 -54.656482)
		(width 0.127)
		(layer "In2.Cu")
		(net "FPGA_IO_5")
	)
	(segment
		(start 137.540746 -39.116)
		(end 147.955 -39.116)
		(width 0.127)
		(layer "In2.Cu")
		(net "FPGA_IO_5")
	)
	(segment
		(start 126.365 -57.404)
		(end 126.365 -55.291482)
		(width 0.127)
		(layer "In2.Cu")
		(net "FPGA_IO_5")
	)
	(segment
		(start 149.352 -40.513)
		(end 157.353 -40.513)
		(width 0.127)
		(layer "In2.Cu")
		(net "FPGA_IO_5")
	)
	(segment
		(start 157.353 -40.513)
		(end 157.988 -41.148)
		(width 0.127)
		(layer "In2.Cu")
		(net "FPGA_IO_5")
	)
	(segment
		(start 127 -54.656482)
		(end 127 -54.102254)
		(width 0.127)
		(layer "In2.Cu")
		(net "FPGA_IO_5")
	)
	(segment
		(start 136.2075 -40.449246)
		(end 137.540746 -39.116)
		(width 0.127)
		(layer "In2.Cu")
		(net "FPGA_IO_5")
	)
	(segment
		(start 136.2075 -41.211246)
		(end 136.2075 -40.449246)
		(width 0.127)
		(layer "In2.Cu")
		(net "FPGA_IO_5")
	)
	(segment
		(start 131.318 -46.100746)
		(end 136.2075 -41.211246)
		(width 0.127)
		(layer "In2.Cu")
		(net "FPGA_IO_5")
	)
	(segment
		(start 127 -54.102254)
		(end 131.318 -49.784254)
		(width 0.127)
		(layer "In2.Cu")
		(net "FPGA_IO_5")
	)
	(segment
		(start 108.106464 -61.37275)
		(end 109.55655 -59.922664)
		(width 0.11938)
		(layer "F.Cu")
		(net "FPGA_IO_4")
	)
	(segment
		(start 107.315 -54.355238)
		(end 107.84713 -53.823108)
		(width 0.11938)
		(layer "F.Cu")
		(net "FPGA_IO_4")
	)
	(segment
		(start 102.5398 -62.6872)
		(end 103.85425 -61.37275)
		(width 0.11938)
		(layer "F.Cu")
		(net "FPGA_IO_4")
	)
	(segment
		(start 109.55655 -59.922664)
		(end 109.55655 -57.51195)
		(width 0.11938)
		(layer "F.Cu")
		(net "FPGA_IO_4")
	)
	(segment
		(start 109.55655 -57.51195)
		(end 107.315 -55.2704)
		(width 0.11938)
		(layer "F.Cu")
		(net "FPGA_IO_4")
	)
	(segment
		(start 103.85425 -61.37275)
		(end 108.106464 -61.37275)
		(width 0.11938)
		(layer "F.Cu")
		(net "FPGA_IO_4")
	)
	(segment
		(start 102.5398 -63.754)
		(end 102.5398 -62.6872)
		(width 0.11938)
		(layer "F.Cu")
		(net "FPGA_IO_4")
	)
	(segment
		(start 107.315 -55.2704)
		(end 107.315 -54.355238)
		(width 0.11938)
		(layer "F.Cu")
		(net "FPGA_IO_4")
	)
	(via
		(at 102.5398 -62.6872)
		(size 0.508)
		(drill 0.254)
		(layers "F.Cu" "B.Cu")
		(net "FPGA_IO_4")
	)
	(via
		(at 125.095 -57.404)
		(size 0.508)
		(drill 0.254)
		(layers "F.Cu" "B.Cu")
		(net "FPGA_IO_4")
	)
	(via
		(at 157.988 -46.101)
		(size 0.508)
		(drill 0.254)
		(layers "F.Cu" "B.Cu")
		(net "FPGA_IO_4")
	)
	(segment
		(start 105.996994 -61.60262)
		(end 105.001314 -61.60262)
		(width 0.11938)
		(layer "B.Cu")
		(net "FPGA_IO_4")
	)
	(segment
		(start 108.45038 -62.202314)
		(end 107.620816 -61.37275)
		(width 0.11938)
		(layer "B.Cu")
		(net "FPGA_IO_4")
	)
	(segment
		(start 103.0478 -62.6872)
		(end 102.5398 -62.6872)
		(width 0.11938)
		(layer "B.Cu")
		(net "FPGA_IO_4")
	)
	(segment
		(start 119.420894 -66.802)
		(end 119.234204 -66.61531)
		(width 0.11938)
		(layer "B.Cu")
		(net "FPGA_IO_4")
	)
	(segment
		(start 122.936 -59.182)
		(end 122.936 -65.278)
		(width 0.11938)
		(layer "B.Cu")
		(net "FPGA_IO_4")
	)
	(segment
		(start 121.412 -66.802)
		(end 119.420894 -66.802)
		(width 0.11938)
		(layer "B.Cu")
		(net "FPGA_IO_4")
	)
	(segment
		(start 108.458 -62.357)
		(end 108.45038 -62.34938)
		(width 0.11938)
		(layer "B.Cu")
		(net "FPGA_IO_4")
	)
	(segment
		(start 116.332 -67.183)
		(end 114.59718 -65.44818)
		(width 0.11938)
		(layer "B.Cu")
		(net "FPGA_IO_4")
	)
	(segment
		(start 108.458 -64.419988)
		(end 108.458 -62.357)
		(width 0.11938)
		(layer "B.Cu")
		(net "FPGA_IO_4")
	)
	(segment
		(start 107.620816 -61.37275)
		(end 106.226864 -61.37275)
		(width 0.11938)
		(layer "B.Cu")
		(net "FPGA_IO_4")
	)
	(segment
		(start 108.45038 -62.34938)
		(end 108.45038 -62.202314)
		(width 0.11938)
		(layer "B.Cu")
		(net "FPGA_IO_4")
	)
	(segment
		(start 124.714 -57.404)
		(end 122.936 -59.182)
		(width 0.11938)
		(layer "B.Cu")
		(net "FPGA_IO_4")
	)
	(segment
		(start 109.486192 -65.44818)
		(end 108.458 -64.419988)
		(width 0.11938)
		(layer "B.Cu")
		(net "FPGA_IO_4")
	)
	(segment
		(start 102.5398 -63.754)
		(end 102.5398 -62.6872)
		(width 0.11938)
		(layer "B.Cu")
		(net "FPGA_IO_4")
	)
	(segment
		(start 117.094 -67.183)
		(end 116.332 -67.183)
		(width 0.11938)
		(layer "B.Cu")
		(net "FPGA_IO_4")
	)
	(segment
		(start 114.59718 -65.44818)
		(end 109.486192 -65.44818)
		(width 0.11938)
		(layer "B.Cu")
		(net "FPGA_IO_4")
	)
	(segment
		(start 157.8864 -45.9994)
		(end 157.988 -46.101)
		(width 0.11938)
		(layer "B.Cu")
		(net "FPGA_IO_4")
	)
	(segment
		(start 117.66169 -66.61531)
		(end 117.094 -67.183)
		(width 0.11938)
		(layer "B.Cu")
		(net "FPGA_IO_4")
	)
	(segment
		(start 106.226864 -61.37275)
		(end 105.996994 -61.60262)
		(width 0.11938)
		(layer "B.Cu")
		(net "FPGA_IO_4")
	)
	(segment
		(start 119.234204 -66.61531)
		(end 117.66169 -66.61531)
		(width 0.11938)
		(layer "B.Cu")
		(net "FPGA_IO_4")
	)
	(segment
		(start 125.095 -57.404)
		(end 124.714 -57.404)
		(width 0.11938)
		(layer "B.Cu")
		(net "FPGA_IO_4")
	)
	(segment
		(start 156.337 -45.9994)
		(end 157.8864 -45.9994)
		(width 0.11938)
		(layer "B.Cu")
		(net "FPGA_IO_4")
	)
	(segment
		(start 122.936 -65.278)
		(end 121.412 -66.802)
		(width 0.11938)
		(layer "B.Cu")
		(net "FPGA_IO_4")
	)
	(segment
		(start 103.632 -62.103)
		(end 103.0478 -62.6872)
		(width 0.11938)
		(layer "B.Cu")
		(net "FPGA_IO_4")
	)
	(segment
		(start 104.500934 -62.103)
		(end 103.632 -62.103)
		(width 0.11938)
		(layer "B.Cu")
		(net "FPGA_IO_4")
	)
	(segment
		(start 105.001314 -61.60262)
		(end 104.500934 -62.103)
		(width 0.11938)
		(layer "B.Cu")
		(net "FPGA_IO_4")
	)
	(segment
		(start 153.924 -42.037)
		(end 157.988 -46.101)
		(width 0.127)
		(layer "In2.Cu")
		(net "FPGA_IO_4")
	)
	(segment
		(start 136.5885 -40.7035)
		(end 137.668 -39.624)
		(width 0.127)
		(layer "In2.Cu")
		(net "FPGA_IO_4")
	)
	(segment
		(start 147.447 -39.624)
		(end 149.86 -42.037)
		(width 0.127)
		(layer "In2.Cu")
		(net "FPGA_IO_4")
	)
	(segment
		(start 125.857 -58.166)
		(end 127 -58.166)
		(width 0.127)
		(layer "In2.Cu")
		(net "FPGA_IO_4")
	)
	(segment
		(start 125.095 -57.404)
		(end 125.857 -58.166)
		(width 0.127)
		(layer "In2.Cu")
		(net "FPGA_IO_4")
	)
	(segment
		(start 127 -58.166)
		(end 128.016 -57.15)
		(width 0.127)
		(layer "In2.Cu")
		(net "FPGA_IO_4")
	)
	(segment
		(start 149.86 -42.037)
		(end 153.924 -42.037)
		(width 0.127)
		(layer "In2.Cu")
		(net "FPGA_IO_4")
	)
	(segment
		(start 132.588 -53.594)
		(end 132.588 -45.369734)
		(width 0.127)
		(layer "In2.Cu")
		(net "FPGA_IO_4")
	)
	(segment
		(start 128.016 -57.15)
		(end 129.032 -57.15)
		(width 0.127)
		(layer "In2.Cu")
		(net "FPGA_IO_4")
	)
	(segment
		(start 132.588 -45.369734)
		(end 136.5885 -41.369234)
		(width 0.127)
		(layer "In2.Cu")
		(net "FPGA_IO_4")
	)
	(segment
		(start 136.5885 -41.369234)
		(end 136.5885 -40.7035)
		(width 0.127)
		(layer "In2.Cu")
		(net "FPGA_IO_4")
	)
	(segment
		(start 129.032 -57.15)
		(end 132.588 -53.594)
		(width 0.127)
		(layer "In2.Cu")
		(net "FPGA_IO_4")
	)
	(segment
		(start 137.668 -39.624)
		(end 147.447 -39.624)
		(width 0.127)
		(layer "In2.Cu")
		(net "FPGA_IO_4")
	)
	(segment
		(start 104.847136 -52.82311)
		(end 104.347264 -53.322982)
		(width 0.11938)
		(layer "F.Cu")
		(net "FPGA_IO_3")
	)
	(segment
		(start 96.5454 -63.754)
		(end 96.5454 -62.6872)
		(width 0.11938)
		(layer "F.Cu")
		(net "FPGA_IO_3")
	)
	(via
		(at 104.347264 -53.322982)
		(size 0.4572)
		(drill 0.2032)
		(layers "F.Cu" "B.Cu")
		(net "FPGA_IO_3")
	)
	(via
		(at 150.368 -35.814)
		(size 0.508)
		(drill 0.254)
		(layers "F.Cu" "B.Cu")
		(net "FPGA_IO_3")
	)
	(via
		(at 96.5454 -62.6872)
		(size 0.508)
		(drill 0.254)
		(layers "F.Cu" "B.Cu")
		(net "FPGA_IO_3")
	)
	(via
		(at 129.286 -54.737)
		(size 0.508)
		(drill 0.254)
		(layers "F.Cu" "B.Cu")
		(net "FPGA_IO_3")
	)
	(segment
		(start 129.286 -55.372)
		(end 129.286 -54.737)
		(width 0.11938)
		(layer "B.Cu")
		(net "FPGA_IO_3")
	)
	(segment
		(start 125.222 -59.055)
		(end 125.603 -59.055)
		(width 0.11938)
		(layer "B.Cu")
		(net "FPGA_IO_3")
	)
	(segment
		(start 116.84 -69.342)
		(end 120.142 -69.342)
		(width 0.11938)
		(layer "B.Cu")
		(net "FPGA_IO_3")
	)
	(segment
		(start 96.5454 -62.6872)
		(end 96.063054 -62.6872)
		(width 0.11938)
		(layer "B.Cu")
		(net "FPGA_IO_3")
	)
	(segment
		(start 95.81007 -63.44793)
		(end 94.869 -64.389)
		(width 0.11938)
		(layer "B.Cu")
		(net "FPGA_IO_3")
	)
	(segment
		(start 95.81007 -62.940184)
		(end 95.81007 -63.44793)
		(width 0.11938)
		(layer "B.Cu")
		(net "FPGA_IO_3")
	)
	(segment
		(start 107.061 -67.31)
		(end 110.363 -67.31)
		(width 0.11938)
		(layer "B.Cu")
		(net "FPGA_IO_3")
	)
	(segment
		(start 151.892 -36.0426)
		(end 150.5966 -36.0426)
		(width 0.11938)
		(layer "B.Cu")
		(net "FPGA_IO_3")
	)
	(segment
		(start 106.231182 -66.480182)
		(end 107.061 -67.31)
		(width 0.11938)
		(layer "B.Cu")
		(net "FPGA_IO_3")
	)
	(segment
		(start 94.869 -65.531746)
		(end 95.817436 -66.480182)
		(width 0.11938)
		(layer "B.Cu")
		(net "FPGA_IO_3")
	)
	(segment
		(start 116.205 -68.707)
		(end 116.84 -69.342)
		(width 0.11938)
		(layer "B.Cu")
		(net "FPGA_IO_3")
	)
	(segment
		(start 150.5966 -36.0426)
		(end 150.368 -35.814)
		(width 0.11938)
		(layer "B.Cu")
		(net "FPGA_IO_3")
	)
	(segment
		(start 96.063054 -62.6872)
		(end 95.81007 -62.940184)
		(width 0.11938)
		(layer "B.Cu")
		(net "FPGA_IO_3")
	)
	(segment
		(start 123.952 -60.325)
		(end 125.222 -59.055)
		(width 0.11938)
		(layer "B.Cu")
		(net "FPGA_IO_3")
	)
	(segment
		(start 96.5454 -63.754)
		(end 96.5454 -62.6872)
		(width 0.11938)
		(layer "B.Cu")
		(net "FPGA_IO_3")
	)
	(segment
		(start 123.952 -65.532)
		(end 123.952 -60.325)
		(width 0.11938)
		(layer "B.Cu")
		(net "FPGA_IO_3")
	)
	(segment
		(start 120.142 -69.342)
		(end 123.952 -65.532)
		(width 0.11938)
		(layer "B.Cu")
		(net "FPGA_IO_3")
	)
	(segment
		(start 94.869 -64.389)
		(end 94.869 -65.531746)
		(width 0.11938)
		(layer "B.Cu")
		(net "FPGA_IO_3")
	)
	(segment
		(start 95.817436 -66.480182)
		(end 106.231182 -66.480182)
		(width 0.11938)
		(layer "B.Cu")
		(net "FPGA_IO_3")
	)
	(segment
		(start 111.76 -68.707)
		(end 116.205 -68.707)
		(width 0.11938)
		(layer "B.Cu")
		(net "FPGA_IO_3")
	)
	(segment
		(start 110.363 -67.31)
		(end 111.76 -68.707)
		(width 0.11938)
		(layer "B.Cu")
		(net "FPGA_IO_3")
	)
	(segment
		(start 125.603 -59.055)
		(end 129.286 -55.372)
		(width 0.11938)
		(layer "B.Cu")
		(net "FPGA_IO_3")
	)
	(segment
		(start 103.9368 -53.733446)
		(end 104.347264 -53.322982)
		(width 0.127)
		(layer "In2.Cu")
		(net "FPGA_IO_3")
	)
	(segment
		(start 98.376486 -60.856114)
		(end 98.448114 -60.856114)
		(width 0.127)
		(layer "In2.Cu")
		(net "FPGA_IO_3")
	)
	(segment
		(start 98.448114 -60.856114)
		(end 103.9368 -55.367428)
		(width 0.127)
		(layer "In2.Cu")
		(net "FPGA_IO_3")
	)
	(segment
		(start 103.9368 -55.367428)
		(end 103.9368 -53.733446)
		(width 0.127)
		(layer "In2.Cu")
		(net "FPGA_IO_3")
	)
	(segment
		(start 96.5454 -62.6872)
		(end 98.376486 -60.856114)
		(width 0.127)
		(layer "In2.Cu")
		(net "FPGA_IO_3")
	)
	(segment
		(start 129.032 -52.959)
		(end 129.032 -54.483)
		(width 0.127)
		(layer "In7.Cu")
		(net "FPGA_IO_3")
	)
	(segment
		(start 133.096 -38.227)
		(end 133.096 -40.005)
		(width 0.127)
		(layer "In7.Cu")
		(net "FPGA_IO_3")
	)
	(segment
		(start 137.414 -37.846)
		(end 136.652 -37.084)
		(width 0.127)
		(layer "In7.Cu")
		(net "FPGA_IO_3")
	)
	(segment
		(start 128.905 -49.784)
		(end 128.905 -52.832)
		(width 0.127)
		(layer "In7.Cu")
		(net "FPGA_IO_3")
	)
	(segment
		(start 133.096 -40.005)
		(end 129.54 -43.561)
		(width 0.127)
		(layer "In7.Cu")
		(net "FPGA_IO_3")
	)
	(segment
		(start 148.336 -37.846)
		(end 137.414 -37.846)
		(width 0.127)
		(layer "In7.Cu")
		(net "FPGA_IO_3")
	)
	(segment
		(start 129.032 -54.483)
		(end 129.286 -54.737)
		(width 0.127)
		(layer "In7.Cu")
		(net "FPGA_IO_3")
	)
	(segment
		(start 129.54 -49.149)
		(end 128.905 -49.784)
		(width 0.127)
		(layer "In7.Cu")
		(net "FPGA_IO_3")
	)
	(segment
		(start 129.54 -43.561)
		(end 129.54 -49.149)
		(width 0.127)
		(layer "In7.Cu")
		(net "FPGA_IO_3")
	)
	(segment
		(start 128.905 -52.832)
		(end 129.032 -52.959)
		(width 0.127)
		(layer "In7.Cu")
		(net "FPGA_IO_3")
	)
	(segment
		(start 134.239 -37.084)
		(end 133.096 -38.227)
		(width 0.127)
		(layer "In7.Cu")
		(net "FPGA_IO_3")
	)
	(segment
		(start 136.652 -37.084)
		(end 134.239 -37.084)
		(width 0.127)
		(layer "In7.Cu")
		(net "FPGA_IO_3")
	)
	(segment
		(start 150.368 -35.814)
		(end 148.336 -37.846)
		(width 0.127)
		(layer "In7.Cu")
		(net "FPGA_IO_3")
	)
	(segment
		(start 98.044 -63.754)
		(end 98.044 -62.6872)
		(width 0.11938)
		(layer "F.Cu")
		(net "FPGA_IO_2")
	)
	(segment
		(start 105.847134 -52.82311)
		(end 105.347262 -53.322982)
		(width 0.11938)
		(layer "F.Cu")
		(net "FPGA_IO_2")
	)
	(via
		(at 98.044 -62.6872)
		(size 0.508)
		(drill 0.254)
		(layers "F.Cu" "B.Cu")
		(net "FPGA_IO_2")
	)
	(via
		(at 150.368 -38.481)
		(size 0.508)
		(drill 0.254)
		(layers "F.Cu" "B.Cu")
		(net "FPGA_IO_2")
	)
	(via
		(at 105.347262 -53.322982)
		(size 0.4572)
		(drill 0.2032)
		(layers "F.Cu" "B.Cu")
		(net "FPGA_IO_2")
	)
	(via
		(at 130.429 -54.737)
		(size 0.508)
		(drill 0.254)
		(layers "F.Cu" "B.Cu")
		(net "FPGA_IO_2")
	)
	(segment
		(start 95.885254 -62.23)
		(end 95.885 -62.23)
		(width 0.11938)
		(layer "B.Cu")
		(net "FPGA_IO_2")
	)
	(segment
		(start 111.605314 -69.08038)
		(end 116.050314 -69.08038)
		(width 0.11938)
		(layer "B.Cu")
		(net "FPGA_IO_2")
	)
	(segment
		(start 95.885 -62.23)
		(end 95.43669 -62.67831)
		(width 0.11938)
		(layer "B.Cu")
		(net "FPGA_IO_2")
	)
	(segment
		(start 95.43669 -63.293244)
		(end 94.49562 -64.234314)
		(width 0.11938)
		(layer "B.Cu")
		(net "FPGA_IO_2")
	)
	(segment
		(start 116.685314 -69.71538)
		(end 120.296686 -69.71538)
		(width 0.11938)
		(layer "B.Cu")
		(net "FPGA_IO_2")
	)
	(segment
		(start 97.348294 -62.6872)
		(end 96.780604 -62.11951)
		(width 0.11938)
		(layer "B.Cu")
		(net "FPGA_IO_2")
	)
	(segment
		(start 125.369066 -59.436)
		(end 125.856746 -59.436)
		(width 0.11938)
		(layer "B.Cu")
		(net "FPGA_IO_2")
	)
	(segment
		(start 130.429 -54.863746)
		(end 130.429 -54.737)
		(width 0.11938)
		(layer "B.Cu")
		(net "FPGA_IO_2")
	)
	(segment
		(start 98.044 -62.6872)
		(end 97.348294 -62.6872)
		(width 0.11938)
		(layer "B.Cu")
		(net "FPGA_IO_2")
	)
	(segment
		(start 125.856746 -59.436)
		(end 130.429 -54.863746)
		(width 0.11938)
		(layer "B.Cu")
		(net "FPGA_IO_2")
	)
	(segment
		(start 106.906314 -67.68338)
		(end 110.208314 -67.68338)
		(width 0.11938)
		(layer "B.Cu")
		(net "FPGA_IO_2")
	)
	(segment
		(start 95.995744 -62.11951)
		(end 95.885254 -62.23)
		(width 0.11938)
		(layer "B.Cu")
		(net "FPGA_IO_2")
	)
	(segment
		(start 96.780604 -62.11951)
		(end 95.995744 -62.11951)
		(width 0.11938)
		(layer "B.Cu")
		(net "FPGA_IO_2")
	)
	(segment
		(start 94.49562 -65.79362)
		(end 95.555562 -66.853562)
		(width 0.11938)
		(layer "B.Cu")
		(net "FPGA_IO_2")
	)
	(segment
		(start 94.49562 -64.234314)
		(end 94.49562 -65.79362)
		(width 0.11938)
		(layer "B.Cu")
		(net "FPGA_IO_2")
	)
	(segment
		(start 116.050314 -69.08038)
		(end 116.685314 -69.71538)
		(width 0.11938)
		(layer "B.Cu")
		(net "FPGA_IO_2")
	)
	(segment
		(start 120.296686 -69.71538)
		(end 124.32538 -65.686686)
		(width 0.11938)
		(layer "B.Cu")
		(net "FPGA_IO_2")
	)
	(segment
		(start 110.208314 -67.68338)
		(end 111.605314 -69.08038)
		(width 0.11938)
		(layer "B.Cu")
		(net "FPGA_IO_2")
	)
	(segment
		(start 106.076496 -66.853562)
		(end 106.906314 -67.68338)
		(width 0.11938)
		(layer "B.Cu")
		(net "FPGA_IO_2")
	)
	(segment
		(start 95.555562 -66.853562)
		(end 106.076496 -66.853562)
		(width 0.11938)
		(layer "B.Cu")
		(net "FPGA_IO_2")
	)
	(segment
		(start 98.044 -63.754)
		(end 98.044 -62.6872)
		(width 0.11938)
		(layer "B.Cu")
		(net "FPGA_IO_2")
	)
	(segment
		(start 124.32538 -60.479686)
		(end 125.369066 -59.436)
		(width 0.11938)
		(layer "B.Cu")
		(net "FPGA_IO_2")
	)
	(segment
		(start 95.43669 -62.67831)
		(end 95.43669 -63.293244)
		(width 0.11938)
		(layer "B.Cu")
		(net "FPGA_IO_2")
	)
	(segment
		(start 151.892 -39.0906)
		(end 150.9776 -39.0906)
		(width 0.11938)
		(layer "B.Cu")
		(net "FPGA_IO_2")
	)
	(segment
		(start 124.32538 -65.686686)
		(end 124.32538 -60.479686)
		(width 0.11938)
		(layer "B.Cu")
		(net "FPGA_IO_2")
	)
	(segment
		(start 150.9776 -39.0906)
		(end 150.368 -38.481)
		(width 0.11938)
		(layer "B.Cu")
		(net "FPGA_IO_2")
	)
	(segment
		(start 105.347262 -53.322982)
		(end 104.4956 -54.174644)
		(width 0.127)
		(layer "In2.Cu")
		(net "FPGA_IO_2")
	)
	(segment
		(start 100.076 -61.595)
		(end 99.1362 -61.595)
		(width 0.127)
		(layer "In2.Cu")
		(net "FPGA_IO_2")
	)
	(segment
		(start 104.4956 -57.1754)
		(end 100.076 -61.595)
		(width 0.127)
		(layer "In2.Cu")
		(net "FPGA_IO_2")
	)
	(segment
		(start 104.4956 -54.174644)
		(end 104.4956 -57.1754)
		(width 0.127)
		(layer "In2.Cu")
		(net "FPGA_IO_2")
	)
	(segment
		(start 99.1362 -61.595)
		(end 98.044 -62.6872)
		(width 0.127)
		(layer "In2.Cu")
		(net "FPGA_IO_2")
	)
	(segment
		(start 129.54 -52.928012)
		(end 129.3114 -52.699412)
		(width 0.127)
		(layer "In7.Cu")
		(net "FPGA_IO_2")
	)
	(segment
		(start 130.429 -54.737)
		(end 129.54 -53.848)
		(width 0.127)
		(layer "In7.Cu")
		(net "FPGA_IO_2")
	)
	(segment
		(start 134.471156 -39.34841)
		(end 136.16559 -39.34841)
		(width 0.127)
		(layer "In7.Cu")
		(net "FPGA_IO_2")
	)
	(segment
		(start 129.921 -49.403)
		(end 129.921 -43.898566)
		(width 0.127)
		(layer "In7.Cu")
		(net "FPGA_IO_2")
	)
	(segment
		(start 129.3114 -52.699412)
		(end 129.3114 -50.0126)
		(width 0.127)
		(layer "In7.Cu")
		(net "FPGA_IO_2")
	)
	(segment
		(start 136.16559 -39.34841)
		(end 137.033 -38.481)
		(width 0.127)
		(layer "In7.Cu")
		(net "FPGA_IO_2")
	)
	(segment
		(start 129.921 -43.898566)
		(end 134.471156 -39.34841)
		(width 0.127)
		(layer "In7.Cu")
		(net "FPGA_IO_2")
	)
	(segment
		(start 129.54 -53.848)
		(end 129.54 -52.928012)
		(width 0.127)
		(layer "In7.Cu")
		(net "FPGA_IO_2")
	)
	(segment
		(start 137.033 -38.481)
		(end 150.368 -38.481)
		(width 0.127)
		(layer "In7.Cu")
		(net "FPGA_IO_2")
	)
	(segment
		(start 129.3114 -50.0126)
		(end 129.921 -49.403)
		(width 0.127)
		(layer "In7.Cu")
		(net "FPGA_IO_2")
	)
	(segment
		(start 101.60381 -60.62599)
		(end 107.67441 -60.62599)
		(width 0.11938)
		(layer "F.Cu")
		(net "FPGA_IO_1")
	)
	(segment
		(start 108.7628 -57.912)
		(end 105.847134 -54.996334)
		(width 0.11938)
		(layer "F.Cu")
		(net "FPGA_IO_1")
	)
	(segment
		(start 99.5426 -62.6872)
		(end 101.60381 -60.62599)
		(width 0.11938)
		(layer "F.Cu")
		(net "FPGA_IO_1")
	)
	(segment
		(start 105.847134 -54.996334)
		(end 105.847134 -54.823106)
		(width 0.11938)
		(layer "F.Cu")
		(net "FPGA_IO_1")
	)
	(segment
		(start 107.67441 -60.62599)
		(end 108.7628 -59.5376)
		(width 0.11938)
		(layer "F.Cu")
		(net "FPGA_IO_1")
	)
	(segment
		(start 108.7628 -59.5376)
		(end 108.7628 -57.912)
		(width 0.11938)
		(layer "F.Cu")
		(net "FPGA_IO_1")
	)
	(segment
		(start 99.5426 -63.754)
		(end 99.5426 -62.6872)
		(width 0.11938)
		(layer "F.Cu")
		(net "FPGA_IO_1")
	)
	(via
		(at 99.5426 -62.6872)
		(size 0.508)
		(drill 0.254)
		(layers "F.Cu" "B.Cu")
		(net "FPGA_IO_1")
	)
	(via
		(at 150.368 -41.402)
		(size 0.508)
		(drill 0.254)
		(layers "F.Cu" "B.Cu")
		(net "FPGA_IO_1")
	)
	(via
		(at 129.921 -52.451)
		(size 0.508)
		(drill 0.254)
		(layers "F.Cu" "B.Cu")
		(net "FPGA_IO_1")
	)
	(segment
		(start 100.711 -61.087)
		(end 99.5426 -62.2554)
		(width 0.11938)
		(layer "B.Cu")
		(net "FPGA_IO_1")
	)
	(segment
		(start 117.911118 -64.70142)
		(end 109.926882 -64.70142)
		(width 0.11938)
		(layer "B.Cu")
		(net "FPGA_IO_1")
	)
	(segment
		(start 150.4696 -41.5036)
		(end 150.368 -41.402)
		(width 0.11938)
		(layer "B.Cu")
		(net "FPGA_IO_1")
	)
	(segment
		(start 129.907538 -52.451)
		(end 126.293118 -56.06542)
		(width 0.11938)
		(layer "B.Cu")
		(net "FPGA_IO_1")
	)
	(segment
		(start 109.347 -61.341)
		(end 108.61929 -60.61329)
		(width 0.11938)
		(layer "B.Cu")
		(net "FPGA_IO_1")
	)
	(segment
		(start 129.921 -52.451)
		(end 129.907538 -52.451)
		(width 0.11938)
		(layer "B.Cu")
		(net "FPGA_IO_1")
	)
	(segment
		(start 121.732802 -58.166)
		(end 119.126 -58.166)
		(width 0.11938)
		(layer "B.Cu")
		(net "FPGA_IO_1")
	)
	(segment
		(start 151.892 -41.5036)
		(end 150.4696 -41.5036)
		(width 0.11938)
		(layer "B.Cu")
		(net "FPGA_IO_1")
	)
	(segment
		(start 118.42242 -58.86958)
		(end 118.42242 -64.190118)
		(width 0.11938)
		(layer "B.Cu")
		(net "FPGA_IO_1")
	)
	(segment
		(start 99.5426 -62.2554)
		(end 99.5426 -62.6872)
		(width 0.11938)
		(layer "B.Cu")
		(net "FPGA_IO_1")
	)
	(segment
		(start 109.347 -64.121538)
		(end 109.347 -61.341)
		(width 0.11938)
		(layer "B.Cu")
		(net "FPGA_IO_1")
	)
	(segment
		(start 104.460802 -61.087)
		(end 100.711 -61.087)
		(width 0.11938)
		(layer "B.Cu")
		(net "FPGA_IO_1")
	)
	(segment
		(start 104.934512 -60.61329)
		(end 104.460802 -61.087)
		(width 0.11938)
		(layer "B.Cu")
		(net "FPGA_IO_1")
	)
	(segment
		(start 126.293118 -56.06542)
		(end 123.833382 -56.06542)
		(width 0.11938)
		(layer "B.Cu")
		(net "FPGA_IO_1")
	)
	(segment
		(start 119.126 -58.166)
		(end 118.42242 -58.86958)
		(width 0.11938)
		(layer "B.Cu")
		(net "FPGA_IO_1")
	)
	(segment
		(start 108.61929 -60.61329)
		(end 104.934512 -60.61329)
		(width 0.11938)
		(layer "B.Cu")
		(net "FPGA_IO_1")
	)
	(segment
		(start 123.833382 -56.06542)
		(end 121.732802 -58.166)
		(width 0.11938)
		(layer "B.Cu")
		(net "FPGA_IO_1")
	)
	(segment
		(start 118.42242 -64.190118)
		(end 117.911118 -64.70142)
		(width 0.11938)
		(layer "B.Cu")
		(net "FPGA_IO_1")
	)
	(segment
		(start 99.5426 -63.754)
		(end 99.5426 -62.6872)
		(width 0.11938)
		(layer "B.Cu")
		(net "FPGA_IO_1")
	)
	(segment
		(start 109.926882 -64.70142)
		(end 109.347 -64.121538)
		(width 0.11938)
		(layer "B.Cu")
		(net "FPGA_IO_1")
	)
	(segment
		(start 130.302 -49.560988)
		(end 130.302 -44.236132)
		(width 0.127)
		(layer "In7.Cu")
		(net "FPGA_IO_1")
	)
	(segment
		(start 129.921 -49.941988)
		(end 130.302 -49.560988)
		(width 0.127)
		(layer "In7.Cu")
		(net "FPGA_IO_1")
	)
	(segment
		(start 129.921 -52.451)
		(end 129.921 -49.941988)
		(width 0.127)
		(layer "In7.Cu")
		(net "FPGA_IO_1")
	)
	(segment
		(start 134.533132 -40.005)
		(end 136.779 -40.005)
		(width 0.127)
		(layer "In7.Cu")
		(net "FPGA_IO_1")
	)
	(segment
		(start 136.779 -40.005)
		(end 137.668 -39.116)
		(width 0.127)
		(layer "In7.Cu")
		(net "FPGA_IO_1")
	)
	(segment
		(start 150.368 -41.021)
		(end 150.368 -41.402)
		(width 0.127)
		(layer "In7.Cu")
		(net "FPGA_IO_1")
	)
	(segment
		(start 137.668 -39.116)
		(end 148.463 -39.116)
		(width 0.127)
		(layer "In7.Cu")
		(net "FPGA_IO_1")
	)
	(segment
		(start 130.302 -44.236132)
		(end 134.533132 -40.005)
		(width 0.127)
		(layer "In7.Cu")
		(net "FPGA_IO_1")
	)
	(segment
		(start 148.463 -39.116)
		(end 150.368 -41.021)
		(width 0.127)
		(layer "In7.Cu")
		(net "FPGA_IO_1")
	)
	(segment
		(start 106.847132 -54.823106)
		(end 106.847132 -55.285132)
		(width 0.11938)
		(layer "F.Cu")
		(net "FPGA_IO_0")
	)
	(segment
		(start 109.18317 -59.767978)
		(end 107.951778 -60.99937)
		(width 0.11938)
		(layer "F.Cu")
		(net "FPGA_IO_0")
	)
	(segment
		(start 106.847132 -55.285132)
		(end 109.18317 -57.62117)
		(width 0.11938)
		(layer "F.Cu")
		(net "FPGA_IO_0")
	)
	(segment
		(start 109.18317 -57.62117)
		(end 109.18317 -59.767978)
		(width 0.11938)
		(layer "F.Cu")
		(net "FPGA_IO_0")
	)
	(segment
		(start 107.951778 -60.99937)
		(end 102.72903 -60.99937)
		(width 0.11938)
		(layer "F.Cu")
		(net "FPGA_IO_0")
	)
	(segment
		(start 101.0412 -63.754)
		(end 101.0412 -62.6872)
		(width 0.11938)
		(layer "F.Cu")
		(net "FPGA_IO_0")
	)
	(segment
		(start 102.72903 -60.99937)
		(end 101.0412 -62.6872)
		(width 0.11938)
		(layer "F.Cu")
		(net "FPGA_IO_0")
	)
	(via
		(at 101.0412 -62.6872)
		(size 0.508)
		(drill 0.254)
		(layers "F.Cu" "B.Cu")
		(net "FPGA_IO_0")
	)
	(via
		(at 130.302 -53.467)
		(size 0.508)
		(drill 0.254)
		(layers "F.Cu" "B.Cu")
		(net "FPGA_IO_0")
	)
	(via
		(at 150.368 -43.942)
		(size 0.508)
		(drill 0.254)
		(layers "F.Cu" "B.Cu")
		(net "FPGA_IO_0")
	)
	(segment
		(start 151.892 -44.1706)
		(end 150.5966 -44.1706)
		(width 0.11938)
		(layer "B.Cu")
		(net "FPGA_IO_0")
	)
	(segment
		(start 105.842308 -61.22924)
		(end 104.846628 -61.22924)
		(width 0.11938)
		(layer "B.Cu")
		(net "FPGA_IO_0")
	)
	(segment
		(start 108.37037 -60.99937)
		(end 106.072178 -60.99937)
		(width 0.11938)
		(layer "B.Cu")
		(net "FPGA_IO_0")
	)
	(segment
		(start 120.777 -58.674)
		(end 118.7958 -60.6552)
		(width 0.11938)
		(layer "B.Cu")
		(net "FPGA_IO_0")
	)
	(segment
		(start 130.302 -53.467)
		(end 129.419604 -53.467)
		(width 0.11938)
		(layer "B.Cu")
		(net "FPGA_IO_0")
	)
	(segment
		(start 108.839 -64.141604)
		(end 108.839 -62.23)
		(width 0.11938)
		(layer "B.Cu")
		(net "FPGA_IO_0")
	)
	(segment
		(start 108.839 -62.23)
		(end 108.83138 -62.22238)
		(width 0.11938)
		(layer "B.Cu")
		(net "FPGA_IO_0")
	)
	(segment
		(start 104.353868 -61.722)
		(end 101.473 -61.722)
		(width 0.11938)
		(layer "B.Cu")
		(net "FPGA_IO_0")
	)
	(segment
		(start 108.824014 -62.194948)
		(end 108.824014 -61.453014)
		(width 0.11938)
		(layer "B.Cu")
		(net "FPGA_IO_0")
	)
	(segment
		(start 109.772196 -65.0748)
		(end 108.839 -64.141604)
		(width 0.11938)
		(layer "B.Cu")
		(net "FPGA_IO_0")
	)
	(segment
		(start 108.824014 -61.453014)
		(end 108.37037 -60.99937)
		(width 0.11938)
		(layer "B.Cu")
		(net "FPGA_IO_0")
	)
	(segment
		(start 121.752868 -58.674)
		(end 120.777 -58.674)
		(width 0.11938)
		(layer "B.Cu")
		(net "FPGA_IO_0")
	)
	(segment
		(start 118.7958 -60.6552)
		(end 118.7958 -64.344804)
		(width 0.11938)
		(layer "B.Cu")
		(net "FPGA_IO_0")
	)
	(segment
		(start 150.5966 -44.1706)
		(end 150.368 -43.942)
		(width 0.11938)
		(layer "B.Cu")
		(net "FPGA_IO_0")
	)
	(segment
		(start 106.072178 -60.99937)
		(end 105.842308 -61.22924)
		(width 0.11938)
		(layer "B.Cu")
		(net "FPGA_IO_0")
	)
	(segment
		(start 118.065804 -65.0748)
		(end 109.772196 -65.0748)
		(width 0.11938)
		(layer "B.Cu")
		(net "FPGA_IO_0")
	)
	(segment
		(start 118.7958 -64.344804)
		(end 118.065804 -65.0748)
		(width 0.11938)
		(layer "B.Cu")
		(net "FPGA_IO_0")
	)
	(segment
		(start 101.473 -61.722)
		(end 101.0412 -62.1538)
		(width 0.11938)
		(layer "B.Cu")
		(net "FPGA_IO_0")
	)
	(segment
		(start 108.83138 -62.202314)
		(end 108.824014 -62.194948)
		(width 0.11938)
		(layer "B.Cu")
		(net "FPGA_IO_0")
	)
	(segment
		(start 123.988068 -56.4388)
		(end 121.752868 -58.674)
		(width 0.11938)
		(layer "B.Cu")
		(net "FPGA_IO_0")
	)
	(segment
		(start 126.447804 -56.4388)
		(end 123.988068 -56.4388)
		(width 0.11938)
		(layer "B.Cu")
		(net "FPGA_IO_0")
	)
	(segment
		(start 104.846628 -61.22924)
		(end 104.353868 -61.722)
		(width 0.11938)
		(layer "B.Cu")
		(net "FPGA_IO_0")
	)
	(segment
		(start 101.0412 -63.754)
		(end 101.0412 -62.6872)
		(width 0.11938)
		(layer "B.Cu")
		(net "FPGA_IO_0")
	)
	(segment
		(start 101.0412 -62.1538)
		(end 101.0412 -62.6872)
		(width 0.11938)
		(layer "B.Cu")
		(net "FPGA_IO_0")
	)
	(segment
		(start 129.419604 -53.467)
		(end 126.447804 -56.4388)
		(width 0.11938)
		(layer "B.Cu")
		(net "FPGA_IO_0")
	)
	(segment
		(start 108.83138 -62.22238)
		(end 108.83138 -62.202314)
		(width 0.11938)
		(layer "B.Cu")
		(net "FPGA_IO_0")
	)
	(segment
		(start 130.302 -53.467)
		(end 130.556 -53.213)
		(width 0.127)
		(layer "In7.Cu")
		(net "FPGA_IO_0")
	)
	(segment
		(start 130.3528 -50.202338)
		(end 130.683 -49.872138)
		(width 0.127)
		(layer "In7.Cu")
		(net "FPGA_IO_0")
	)
	(segment
		(start 130.556 -51.7144)
		(end 130.3528 -51.5112)
		(width 0.127)
		(layer "In7.Cu")
		(net "FPGA_IO_0")
	)
	(segment
		(start 130.683 -49.872138)
		(end 130.683 -46.863254)
		(width 0.127)
		(layer "In7.Cu")
		(net "FPGA_IO_0")
	)
	(segment
		(start 149.733 -43.18)
		(end 150.368 -43.815)
		(width 0.127)
		(layer "In7.Cu")
		(net "FPGA_IO_0")
	)
	(segment
		(start 150.368 -43.815)
		(end 150.368 -43.942)
		(width 0.127)
		(layer "In7.Cu")
		(net "FPGA_IO_0")
	)
	(segment
		(start 149.733 -41.275)
		(end 149.733 -43.18)
		(width 0.127)
		(layer "In7.Cu")
		(net "FPGA_IO_0")
	)
	(segment
		(start 130.683 -46.863254)
		(end 137.922254 -39.624)
		(width 0.127)
		(layer "In7.Cu")
		(net "FPGA_IO_0")
	)
	(segment
		(start 130.3528 -51.5112)
		(end 130.3528 -50.202338)
		(width 0.127)
		(layer "In7.Cu")
		(net "FPGA_IO_0")
	)
	(segment
		(start 130.556 -53.213)
		(end 130.556 -51.7144)
		(width 0.127)
		(layer "In7.Cu")
		(net "FPGA_IO_0")
	)
	(segment
		(start 137.922254 -39.624)
		(end 148.082 -39.624)
		(width 0.127)
		(layer "In7.Cu")
		(net "FPGA_IO_0")
	)
	(segment
		(start 148.082 -39.624)
		(end 149.733 -41.275)
		(width 0.127)
		(layer "In7.Cu")
		(net "FPGA_IO_0")
	)
	(segment
		(start 117.7544 -62.5094)
		(end 117.348 -62.5094)
		(width 0.11938)
		(layer "F.Cu")
		(net "FPGA_FLASH_DQ3")
	)
	(segment
		(start 104.14 -85.852)
		(end 103.632 -86.36)
		(width 0.11938)
		(layer "F.Cu")
		(net "FPGA_FLASH_DQ3")
	)
	(segment
		(start 118.237 -66.675)
		(end 118.237 -62.992)
		(width 0.11938)
		(layer "F.Cu")
		(net "FPGA_FLASH_DQ3")
	)
	(segment
		(start 118.999 -67.183)
		(end 118.745 -67.183)
		(width 0.11938)
		(layer "F.Cu")
		(net "FPGA_FLASH_DQ3")
	)
	(segment
		(start 118.745 -67.183)
		(end 118.237 -66.675)
		(width 0.11938)
		(layer "F.Cu")
		(net "FPGA_FLASH_DQ3")
	)
	(segment
		(start 104.84104 -86.55304)
		(end 104.14 -85.852)
		(width 0.11938)
		(layer "F.Cu")
		(net "FPGA_FLASH_DQ3")
	)
	(segment
		(start 118.237 -62.992)
		(end 117.7544 -62.5094)
		(width 0.11938)
		(layer "F.Cu")
		(net "FPGA_FLASH_DQ3")
	)
	(segment
		(start 103.632 -86.36)
		(end 103.632 -87.0966)
		(width 0.11938)
		(layer "F.Cu")
		(net "FPGA_FLASH_DQ3")
	)
	(segment
		(start 105.395014 -86.55304)
		(end 104.84104 -86.55304)
		(width 0.11938)
		(layer "F.Cu")
		(net "FPGA_FLASH_DQ3")
	)
	(via
		(at 118.999 -67.183)
		(size 0.508)
		(drill 0.254)
		(layers "F.Cu" "B.Cu")
		(net "FPGA_FLASH_DQ3")
	)
	(via
		(at 104.14 -85.852)
		(size 0.508)
		(drill 0.254)
		(layers "F.Cu" "B.Cu")
		(net "FPGA_FLASH_DQ3")
	)
	(segment
		(start 104.14 -85.852)
		(end 105.029 -84.963)
		(width 0.127)
		(layer "In7.Cu")
		(net "FPGA_FLASH_DQ3")
	)
	(segment
		(start 115.316 -78.232)
		(end 115.316 -76.581)
		(width 0.127)
		(layer "In7.Cu")
		(net "FPGA_FLASH_DQ3")
	)
	(segment
		(start 115.824 -71.724012)
		(end 118.4275 -69.120512)
		(width 0.127)
		(layer "In7.Cu")
		(net "FPGA_FLASH_DQ3")
	)
	(segment
		(start 118.4275 -69.120512)
		(end 118.4275 -68.343018)
		(width 0.127)
		(layer "In7.Cu")
		(net "FPGA_FLASH_DQ3")
	)
	(segment
		(start 108.711746 -84.963)
		(end 109.601 -84.073746)
		(width 0.127)
		(layer "In7.Cu")
		(net "FPGA_FLASH_DQ3")
	)
	(segment
		(start 118.999 -67.771518)
		(end 118.999 -67.183)
		(width 0.127)
		(layer "In7.Cu")
		(net "FPGA_FLASH_DQ3")
	)
	(segment
		(start 109.601 -84.073746)
		(end 109.601 -83.058)
		(width 0.127)
		(layer "In7.Cu")
		(net "FPGA_FLASH_DQ3")
	)
	(segment
		(start 109.601 -83.058)
		(end 112.395 -80.264)
		(width 0.127)
		(layer "In7.Cu")
		(net "FPGA_FLASH_DQ3")
	)
	(segment
		(start 115.951 -79.68488)
		(end 115.951 -78.867)
		(width 0.127)
		(layer "In7.Cu")
		(net "FPGA_FLASH_DQ3")
	)
	(segment
		(start 105.029 -84.963)
		(end 108.711746 -84.963)
		(width 0.127)
		(layer "In7.Cu")
		(net "FPGA_FLASH_DQ3")
	)
	(segment
		(start 115.316 -76.581)
		(end 115.824 -76.073)
		(width 0.127)
		(layer "In7.Cu")
		(net "FPGA_FLASH_DQ3")
	)
	(segment
		(start 115.824 -76.073)
		(end 115.824 -71.724012)
		(width 0.127)
		(layer "In7.Cu")
		(net "FPGA_FLASH_DQ3")
	)
	(segment
		(start 115.37188 -80.264)
		(end 115.951 -79.68488)
		(width 0.127)
		(layer "In7.Cu")
		(net "FPGA_FLASH_DQ3")
	)
	(segment
		(start 112.395 -80.264)
		(end 115.37188 -80.264)
		(width 0.127)
		(layer "In7.Cu")
		(net "FPGA_FLASH_DQ3")
	)
	(segment
		(start 115.951 -78.867)
		(end 115.316 -78.232)
		(width 0.127)
		(layer "In7.Cu")
		(net "FPGA_FLASH_DQ3")
	)
	(segment
		(start 118.4275 -68.343018)
		(end 118.999 -67.771518)
		(width 0.127)
		(layer "In7.Cu")
		(net "FPGA_FLASH_DQ3")
	)
	(segment
		(start 99.06 -85.979)
		(end 98.298 -86.741)
		(width 0.11938)
		(layer "F.Cu")
		(net "FPGA_FLASH_DQ2")
	)
	(segment
		(start 98.298 -86.741)
		(end 98.298 -86.9696)
		(width 0.11938)
		(layer "F.Cu")
		(net "FPGA_FLASH_DQ2")
	)
	(segment
		(start 115.062 -62.5094)
		(end 115.062 -63.5)
		(width 0.11938)
		(layer "F.Cu")
		(net "FPGA_FLASH_DQ2")
	)
	(segment
		(start 99.58324 -86.50224)
		(end 99.06 -85.979)
		(width 0.11938)
		(layer "F.Cu")
		(net "FPGA_FLASH_DQ2")
	)
	(segment
		(start 100.442014 -86.50224)
		(end 99.58324 -86.50224)
		(width 0.11938)
		(layer "F.Cu")
		(net "FPGA_FLASH_DQ2")
	)
	(via
		(at 99.06 -85.979)
		(size 0.508)
		(drill 0.254)
		(layers "F.Cu" "B.Cu")
		(net "FPGA_FLASH_DQ2")
	)
	(via
		(at 115.062 -63.5)
		(size 0.508)
		(drill 0.254)
		(layers "F.Cu" "B.Cu")
		(net "FPGA_FLASH_DQ2")
	)
	(segment
		(start 112.9538 -75.3364)
		(end 112.9538 -76.1492)
		(width 0.127)
		(layer "In7.Cu")
		(net "FPGA_FLASH_DQ2")
	)
	(segment
		(start 113.5888 -68.3006)
		(end 112.4712 -69.4182)
		(width 0.127)
		(layer "In7.Cu")
		(net "FPGA_FLASH_DQ2")
	)
	(segment
		(start 106.807 -84.328)
		(end 106.426 -83.947)
		(width 0.127)
		(layer "In7.Cu")
		(net "FPGA_FLASH_DQ2")
	)
	(segment
		(start 108.966 -81.788254)
		(end 108.966 -83.693)
		(width 0.127)
		(layer "In7.Cu")
		(net "FPGA_FLASH_DQ2")
	)
	(segment
		(start 112.9538 -76.1492)
		(end 112.141 -76.962)
		(width 0.127)
		(layer "In7.Cu")
		(net "FPGA_FLASH_DQ2")
	)
	(segment
		(start 101.163882 -83.947)
		(end 101.151182 -83.9343)
		(width 0.127)
		(layer "In7.Cu")
		(net "FPGA_FLASH_DQ2")
	)
	(segment
		(start 108.966 -83.693)
		(end 108.331 -84.328)
		(width 0.127)
		(layer "In7.Cu")
		(net "FPGA_FLASH_DQ2")
	)
	(segment
		(start 100.3427 -84.268818)
		(end 100.3427 -84.6963)
		(width 0.127)
		(layer "In7.Cu")
		(net "FPGA_FLASH_DQ2")
	)
	(segment
		(start 108.331 -84.328)
		(end 106.807 -84.328)
		(width 0.127)
		(layer "In7.Cu")
		(net "FPGA_FLASH_DQ2")
	)
	(segment
		(start 112.4712 -69.4182)
		(end 112.4712 -74.8538)
		(width 0.127)
		(layer "In7.Cu")
		(net "FPGA_FLASH_DQ2")
	)
	(segment
		(start 115.062 -63.5)
		(end 113.5888 -64.9732)
		(width 0.127)
		(layer "In7.Cu")
		(net "FPGA_FLASH_DQ2")
	)
	(segment
		(start 101.151182 -83.9343)
		(end 100.677218 -83.9343)
		(width 0.127)
		(layer "In7.Cu")
		(net "FPGA_FLASH_DQ2")
	)
	(segment
		(start 106.426 -83.947)
		(end 101.163882 -83.947)
		(width 0.127)
		(layer "In7.Cu")
		(net "FPGA_FLASH_DQ2")
	)
	(segment
		(start 112.4712 -74.8538)
		(end 112.9538 -75.3364)
		(width 0.127)
		(layer "In7.Cu")
		(net "FPGA_FLASH_DQ2")
	)
	(segment
		(start 112.141 -76.962)
		(end 112.141 -78.613254)
		(width 0.127)
		(layer "In7.Cu")
		(net "FPGA_FLASH_DQ2")
	)
	(segment
		(start 113.5888 -64.9732)
		(end 113.5888 -68.3006)
		(width 0.127)
		(layer "In7.Cu")
		(net "FPGA_FLASH_DQ2")
	)
	(segment
		(start 112.141 -78.613254)
		(end 108.966 -81.788254)
		(width 0.127)
		(layer "In7.Cu")
		(net "FPGA_FLASH_DQ2")
	)
	(segment
		(start 100.677218 -83.9343)
		(end 100.3427 -84.268818)
		(width 0.127)
		(layer "In7.Cu")
		(net "FPGA_FLASH_DQ2")
	)
	(segment
		(start 100.3427 -84.6963)
		(end 99.06 -85.979)
		(width 0.127)
		(layer "In7.Cu")
		(net "FPGA_FLASH_DQ2")
	)
	(segment
		(start 113.852706 -79.187294)
		(end 111.9759 -79.187294)
		(width 0.11938)
		(layer "F.Cu")
		(net "FPGA_FLASH_DQ1_MISO")
	)
	(segment
		(start 115.189 -60.0964)
		(end 116.0018 -60.0964)
		(width 0.11938)
		(layer "F.Cu")
		(net "FPGA_FLASH_DQ1_MISO")
	)
	(segment
		(start 113.919 -79.121)
		(end 113.852706 -79.187294)
		(width 0.11938)
		(layer "F.Cu")
		(net "FPGA_FLASH_DQ1_MISO")
	)
	(segment
		(start 116.205 -61.4426)
		(end 116.205 -60.2996)
		(width 0.11938)
		(layer "F.Cu")
		(net "FPGA_FLASH_DQ1_MISO")
	)
	(segment
		(start 116.0018 -60.0964)
		(end 116.205 -60.2996)
		(width 0.11938)
		(layer "F.Cu")
		(net "FPGA_FLASH_DQ1_MISO")
	)
	(via
		(at 116.205 -60.2996)
		(size 0.508)
		(drill 0.254)
		(layers "F.Cu" "B.Cu")
		(net "FPGA_FLASH_DQ1_MISO")
	)
	(via
		(at 113.919 -79.121)
		(size 0.508)
		(drill 0.254)
		(layers "F.Cu" "B.Cu")
		(net "FPGA_FLASH_DQ1_MISO")
	)
	(segment
		(start 114.935 -66.877946)
		(end 116.205 -66.877946)
		(width 0.127)
		(layer "In7.Cu")
		(net "FPGA_FLASH_DQ1_MISO")
	)
	(segment
		(start 114.808 -68.020946)
		(end 114.935 -68.147946)
		(width 0.127)
		(layer "In7.Cu")
		(net "FPGA_FLASH_DQ1_MISO")
	)
	(segment
		(start 116.205 -60.2996)
		(end 115.6335 -60.8711)
		(width 0.127)
		(layer "In7.Cu")
		(net "FPGA_FLASH_DQ1_MISO")
	)
	(segment
		(start 114.935 -68.147946)
		(end 116.205 -68.147946)
		(width 0.127)
		(layer "In7.Cu")
		(net "FPGA_FLASH_DQ1_MISO")
	)
	(segment
		(start 115.6335 -60.87872)
		(end 115.5065 -61.00572)
		(width 0.127)
		(layer "In7.Cu")
		(net "FPGA_FLASH_DQ1_MISO")
	)
	(segment
		(start 116.205 -67.512946)
		(end 114.935 -67.512946)
		(width 0.127)
		(layer "In7.Cu")
		(net "FPGA_FLASH_DQ1_MISO")
	)
	(segment
		(start 116.332 -68.655946)
		(end 116.205 -68.782946)
		(width 0.127)
		(layer "In7.Cu")
		(net "FPGA_FLASH_DQ1_MISO")
	)
	(segment
		(start 114.935 -65.607946)
		(end 115.316 -65.607946)
		(width 0.127)
		(layer "In7.Cu")
		(net "FPGA_FLASH_DQ1_MISO")
	)
	(segment
		(start 114.4524 -62.78372)
		(end 114.5794 -62.91072)
		(width 0.127)
		(layer "In7.Cu")
		(net "FPGA_FLASH_DQ1_MISO")
	)
	(segment
		(start 116.332 -68.274946)
		(end 116.332 -68.655946)
		(width 0.127)
		(layer "In7.Cu")
		(net "FPGA_FLASH_DQ1_MISO")
	)
	(segment
		(start 114.808 -67.639946)
		(end 114.808 -68.020946)
		(width 0.127)
		(layer "In7.Cu")
		(net "FPGA_FLASH_DQ1_MISO")
	)
	(segment
		(start 114.1857 -70.802246)
		(end 114.1857 -75.806554)
		(width 0.127)
		(layer "In7.Cu")
		(net "FPGA_FLASH_DQ1_MISO")
	)
	(segment
		(start 114.5794 -61.00572)
		(end 114.4524 -61.13272)
		(width 0.127)
		(layer "In7.Cu")
		(net "FPGA_FLASH_DQ1_MISO")
	)
	(segment
		(start 114.935 -67.512946)
		(end 114.808 -67.639946)
		(width 0.127)
		(layer "In7.Cu")
		(net "FPGA_FLASH_DQ1_MISO")
	)
	(segment
		(start 115.443 -66.115946)
		(end 115.316 -66.242946)
		(width 0.127)
		(layer "In7.Cu")
		(net "FPGA_FLASH_DQ1_MISO")
	)
	(segment
		(start 115.6335 -60.8711)
		(end 115.6335 -60.87872)
		(width 0.127)
		(layer "In7.Cu")
		(net "FPGA_FLASH_DQ1_MISO")
	)
	(segment
		(start 116.332 -67.385946)
		(end 116.205 -67.512946)
		(width 0.127)
		(layer "In7.Cu")
		(net "FPGA_FLASH_DQ1_MISO")
	)
	(segment
		(start 114.808 -65.480946)
		(end 114.935 -65.607946)
		(width 0.127)
		(layer "In7.Cu")
		(net "FPGA_FLASH_DQ1_MISO")
	)
	(segment
		(start 116.205 -68.147946)
		(end 116.332 -68.274946)
		(width 0.127)
		(layer "In7.Cu")
		(net "FPGA_FLASH_DQ1_MISO")
	)
	(segment
		(start 116.332 -67.004946)
		(end 116.332 -67.385946)
		(width 0.127)
		(layer "In7.Cu")
		(net "FPGA_FLASH_DQ1_MISO")
	)
	(segment
		(start 116.205 -66.877946)
		(end 116.332 -67.004946)
		(width 0.127)
		(layer "In7.Cu")
		(net "FPGA_FLASH_DQ1_MISO")
	)
	(segment
		(start 114.808 -66.369946)
		(end 114.808 -66.750946)
		(width 0.127)
		(layer "In7.Cu")
		(net "FPGA_FLASH_DQ1_MISO")
	)
	(segment
		(start 115.7478 -69.417946)
		(end 115.8748 -69.544946)
		(width 0.127)
		(layer "In7.Cu")
		(net "FPGA_FLASH_DQ1_MISO")
	)
	(segment
		(start 114.4524 -61.51372)
		(end 114.5794 -61.64072)
		(width 0.127)
		(layer "In7.Cu")
		(net "FPGA_FLASH_DQ1_MISO")
	)
	(segment
		(start 114.4524 -61.13272)
		(end 114.4524 -61.51372)
		(width 0.127)
		(layer "In7.Cu")
		(net "FPGA_FLASH_DQ1_MISO")
	)
	(segment
		(start 115.6335 -64.135)
		(end 114.808 -64.9605)
		(width 0.127)
		(layer "In7.Cu")
		(net "FPGA_FLASH_DQ1_MISO")
	)
	(segment
		(start 114.5794 -61.64072)
		(end 115.5065 -61.64072)
		(width 0.127)
		(layer "In7.Cu")
		(net "FPGA_FLASH_DQ1_MISO")
	)
	(segment
		(start 114.808 -64.9605)
		(end 114.808 -65.480946)
		(width 0.127)
		(layer "In7.Cu")
		(net "FPGA_FLASH_DQ1_MISO")
	)
	(segment
		(start 114.5794 -62.27572)
		(end 114.4524 -62.40272)
		(width 0.127)
		(layer "In7.Cu")
		(net "FPGA_FLASH_DQ1_MISO")
	)
	(segment
		(start 115.316 -65.607946)
		(end 115.443 -65.734946)
		(width 0.127)
		(layer "In7.Cu")
		(net "FPGA_FLASH_DQ1_MISO")
	)
	(segment
		(start 115.8748 -69.925946)
		(end 115.7478 -70.052946)
		(width 0.127)
		(layer "In7.Cu")
		(net "FPGA_FLASH_DQ1_MISO")
	)
	(segment
		(start 115.6335 -61.76772)
		(end 115.6335 -62.14872)
		(width 0.127)
		(layer "In7.Cu")
		(net "FPGA_FLASH_DQ1_MISO")
	)
	(segment
		(start 114.935 -66.242946)
		(end 114.808 -66.369946)
		(width 0.127)
		(layer "In7.Cu")
		(net "FPGA_FLASH_DQ1_MISO")
	)
	(segment
		(start 114.5794 -62.91072)
		(end 115.5065 -62.91072)
		(width 0.127)
		(layer "In7.Cu")
		(net "FPGA_FLASH_DQ1_MISO")
	)
	(segment
		(start 116.205 -68.782946)
		(end 114.935 -68.782946)
		(width 0.127)
		(layer "In7.Cu")
		(net "FPGA_FLASH_DQ1_MISO")
	)
	(segment
		(start 115.5065 -62.27572)
		(end 114.5794 -62.27572)
		(width 0.127)
		(layer "In7.Cu")
		(net "FPGA_FLASH_DQ1_MISO")
	)
	(segment
		(start 115.5065 -61.64072)
		(end 115.6335 -61.76772)
		(width 0.127)
		(layer "In7.Cu")
		(net "FPGA_FLASH_DQ1_MISO")
	)
	(segment
		(start 114.808 -66.750946)
		(end 114.935 -66.877946)
		(width 0.127)
		(layer "In7.Cu")
		(net "FPGA_FLASH_DQ1_MISO")
	)
	(segment
		(start 115.8748 -69.544946)
		(end 115.8748 -69.925946)
		(width 0.127)
		(layer "In7.Cu")
		(net "FPGA_FLASH_DQ1_MISO")
	)
	(segment
		(start 114.935 -69.417946)
		(end 115.7478 -69.417946)
		(width 0.127)
		(layer "In7.Cu")
		(net "FPGA_FLASH_DQ1_MISO")
	)
	(segment
		(start 115.5065 -62.91072)
		(end 115.6335 -63.03772)
		(width 0.127)
		(layer "In7.Cu")
		(net "FPGA_FLASH_DQ1_MISO")
	)
	(segment
		(start 115.6335 -62.14872)
		(end 115.5065 -62.27572)
		(width 0.127)
		(layer "In7.Cu")
		(net "FPGA_FLASH_DQ1_MISO")
	)
	(segment
		(start 115.7478 -70.052946)
		(end 114.935 -70.052946)
		(width 0.127)
		(layer "In7.Cu")
		(net "FPGA_FLASH_DQ1_MISO")
	)
	(segment
		(start 114.935 -68.782946)
		(end 114.808 -68.909946)
		(width 0.127)
		(layer "In7.Cu")
		(net "FPGA_FLASH_DQ1_MISO")
	)
	(segment
		(start 114.808 -68.909946)
		(end 114.808 -69.290946)
		(width 0.127)
		(layer "In7.Cu")
		(net "FPGA_FLASH_DQ1_MISO")
	)
	(segment
		(start 114.808 -69.290946)
		(end 114.935 -69.417946)
		(width 0.127)
		(layer "In7.Cu")
		(net "FPGA_FLASH_DQ1_MISO")
	)
	(segment
		(start 115.5065 -61.00572)
		(end 114.5794 -61.00572)
		(width 0.127)
		(layer "In7.Cu")
		(net "FPGA_FLASH_DQ1_MISO")
	)
	(segment
		(start 114.935 -70.052946)
		(end 114.1857 -70.802246)
		(width 0.127)
		(layer "In7.Cu")
		(net "FPGA_FLASH_DQ1_MISO")
	)
	(segment
		(start 115.6335 -63.03772)
		(end 115.6335 -64.135)
		(width 0.127)
		(layer "In7.Cu")
		(net "FPGA_FLASH_DQ1_MISO")
	)
	(segment
		(start 115.443 -65.734946)
		(end 115.443 -66.115946)
		(width 0.127)
		(layer "In7.Cu")
		(net "FPGA_FLASH_DQ1_MISO")
	)
	(segment
		(start 115.316 -66.242946)
		(end 114.935 -66.242946)
		(width 0.127)
		(layer "In7.Cu")
		(net "FPGA_FLASH_DQ1_MISO")
	)
	(segment
		(start 114.1857 -75.806554)
		(end 113.284 -76.708254)
		(width 0.127)
		(layer "In7.Cu")
		(net "FPGA_FLASH_DQ1_MISO")
	)
	(segment
		(start 114.4524 -62.40272)
		(end 114.4524 -62.78372)
		(width 0.127)
		(layer "In7.Cu")
		(net "FPGA_FLASH_DQ1_MISO")
	)
	(segment
		(start 113.284 -78.486)
		(end 113.919 -79.121)
		(width 0.127)
		(layer "In7.Cu")
		(net "FPGA_FLASH_DQ1_MISO")
	)
	(segment
		(start 113.284 -76.708254)
		(end 113.284 -78.486)
		(width 0.127)
		(layer "In7.Cu")
		(net "FPGA_FLASH_DQ1_MISO")
	)
	(segment
		(start 107.99318 -79.83728)
		(end 105.9053 -79.83728)
		(width 0.11938)
		(layer "F.Cu")
		(net "FPGA_FLASH_DQ0_MOSI")
	)
	(segment
		(start 109.078268 -78.75905)
		(end 109.07141 -78.75905)
		(width 0.11938)
		(layer "F.Cu")
		(net "FPGA_FLASH_DQ0_MOSI")
	)
	(segment
		(start 113.919 -62.5094)
		(end 113.919 -63.5)
		(width 0.11938)
		(layer "F.Cu")
		(net "FPGA_FLASH_DQ0_MOSI")
	)
	(segment
		(start 109.07141 -78.75905)
		(end 107.99318 -79.83728)
		(width 0.11938)
		(layer "F.Cu")
		(net "FPGA_FLASH_DQ0_MOSI")
	)
	(via
		(at 113.919 -63.5)
		(size 0.508)
		(drill 0.254)
		(layers "F.Cu" "B.Cu")
		(net "FPGA_FLASH_DQ0_MOSI")
	)
	(via
		(at 109.078268 -78.75905)
		(size 0.508)
		(drill 0.254)
		(layers "F.Cu" "B.Cu")
		(net "FPGA_FLASH_DQ0_MOSI")
	)
	(segment
		(start 107.8738 -75.692508)
		(end 108.951268 -75.692508)
		(width 0.127)
		(layer "In7.Cu")
		(net "FPGA_FLASH_DQ0_MOSI")
	)
	(segment
		(start 108.951268 -76.327508)
		(end 107.8738 -76.327508)
		(width 0.127)
		(layer "In7.Cu")
		(net "FPGA_FLASH_DQ0_MOSI")
	)
	(segment
		(start 107.8738 -77.597508)
		(end 107.7468 -77.724508)
		(width 0.127)
		(layer "In7.Cu")
		(net "FPGA_FLASH_DQ0_MOSI")
	)
	(segment
		(start 112.2045 -66.661792)
		(end 112.2045 -68.1609)
		(width 0.127)
		(layer "In7.Cu")
		(net "FPGA_FLASH_DQ0_MOSI")
	)
	(segment
		(start 113.919 -63.5)
		(end 113.284 -64.135)
		(width 0.127)
		(layer "In7.Cu")
		(net "FPGA_FLASH_DQ0_MOSI")
	)
	(segment
		(start 109.8042 -69.6214)
		(end 109.8042 -71.374254)
		(width 0.127)
		(layer "In7.Cu")
		(net "FPGA_FLASH_DQ0_MOSI")
	)
	(segment
		(start 111.0234 -65.137792)
		(end 111.1504 -65.264792)
		(width 0.127)
		(layer "In7.Cu")
		(net "FPGA_FLASH_DQ0_MOSI")
	)
	(segment
		(start 112.2045 -68.1609)
		(end 111.7092 -68.6562)
		(width 0.127)
		(layer "In7.Cu")
		(net "FPGA_FLASH_DQ0_MOSI")
	)
	(segment
		(start 112.0775 -66.534792)
		(end 112.2045 -66.661792)
		(width 0.127)
		(layer "In7.Cu")
		(net "FPGA_FLASH_DQ0_MOSI")
	)
	(segment
		(start 111.1504 -64.629792)
		(end 111.0234 -64.756792)
		(width 0.127)
		(layer "In7.Cu")
		(net "FPGA_FLASH_DQ0_MOSI")
	)
	(segment
		(start 107.8738 -78.232508)
		(end 108.951268 -78.232508)
		(width 0.127)
		(layer "In7.Cu")
		(net "FPGA_FLASH_DQ0_MOSI")
	)
	(segment
		(start 112.2045 -64.262)
		(end 112.2045 -64.502792)
		(width 0.127)
		(layer "In7.Cu")
		(net "FPGA_FLASH_DQ0_MOSI")
	)
	(segment
		(start 108.951268 -75.057508)
		(end 107.8738 -75.057508)
		(width 0.127)
		(layer "In7.Cu")
		(net "FPGA_FLASH_DQ0_MOSI")
	)
	(segment
		(start 109.078268 -76.200508)
		(end 108.951268 -76.327508)
		(width 0.127)
		(layer "In7.Cu")
		(net "FPGA_FLASH_DQ0_MOSI")
	)
	(segment
		(start 107.7468 -76.835508)
		(end 107.8738 -76.962508)
		(width 0.127)
		(layer "In7.Cu")
		(net "FPGA_FLASH_DQ0_MOSI")
	)
	(segment
		(start 107.7468 -75.184508)
		(end 107.7468 -75.565508)
		(width 0.127)
		(layer "In7.Cu")
		(net "FPGA_FLASH_DQ0_MOSI")
	)
	(segment
		(start 109.078268 -72.100186)
		(end 109.078268 -74.930508)
		(width 0.127)
		(layer "In7.Cu")
		(net "FPGA_FLASH_DQ0_MOSI")
	)
	(segment
		(start 109.078268 -78.359508)
		(end 109.078268 -78.75905)
		(width 0.127)
		(layer "In7.Cu")
		(net "FPGA_FLASH_DQ0_MOSI")
	)
	(segment
		(start 107.8738 -76.327508)
		(end 107.7468 -76.454508)
		(width 0.127)
		(layer "In7.Cu")
		(net "FPGA_FLASH_DQ0_MOSI")
	)
	(segment
		(start 107.8738 -75.057508)
		(end 107.7468 -75.184508)
		(width 0.127)
		(layer "In7.Cu")
		(net "FPGA_FLASH_DQ0_MOSI")
	)
	(segment
		(start 108.951268 -76.962508)
		(end 109.078268 -77.089508)
		(width 0.127)
		(layer "In7.Cu")
		(net "FPGA_FLASH_DQ0_MOSI")
	)
	(segment
		(start 112.0775 -64.629792)
		(end 111.1504 -64.629792)
		(width 0.127)
		(layer "In7.Cu")
		(net "FPGA_FLASH_DQ0_MOSI")
	)
	(segment
		(start 109.078268 -77.470508)
		(end 108.951268 -77.597508)
		(width 0.127)
		(layer "In7.Cu")
		(net "FPGA_FLASH_DQ0_MOSI")
	)
	(segment
		(start 111.1504 -65.264792)
		(end 112.0775 -65.264792)
		(width 0.127)
		(layer "In7.Cu")
		(net "FPGA_FLASH_DQ0_MOSI")
	)
	(segment
		(start 109.078268 -77.089508)
		(end 109.078268 -77.470508)
		(width 0.127)
		(layer "In7.Cu")
		(net "FPGA_FLASH_DQ0_MOSI")
	)
	(segment
		(start 112.2045 -65.391792)
		(end 112.2045 -65.772792)
		(width 0.127)
		(layer "In7.Cu")
		(net "FPGA_FLASH_DQ0_MOSI")
	)
	(segment
		(start 112.3315 -64.135)
		(end 112.2045 -64.262)
		(width 0.127)
		(layer "In7.Cu")
		(net "FPGA_FLASH_DQ0_MOSI")
	)
	(segment
		(start 112.0775 -65.264792)
		(end 112.2045 -65.391792)
		(width 0.127)
		(layer "In7.Cu")
		(net "FPGA_FLASH_DQ0_MOSI")
	)
	(segment
		(start 111.0234 -66.026792)
		(end 111.0234 -66.407792)
		(width 0.127)
		(layer "In7.Cu")
		(net "FPGA_FLASH_DQ0_MOSI")
	)
	(segment
		(start 112.2045 -64.502792)
		(end 112.0775 -64.629792)
		(width 0.127)
		(layer "In7.Cu")
		(net "FPGA_FLASH_DQ0_MOSI")
	)
	(segment
		(start 107.7468 -77.724508)
		(end 107.7468 -78.105508)
		(width 0.127)
		(layer "In7.Cu")
		(net "FPGA_FLASH_DQ0_MOSI")
	)
	(segment
		(start 107.8738 -76.962508)
		(end 108.951268 -76.962508)
		(width 0.127)
		(layer "In7.Cu")
		(net "FPGA_FLASH_DQ0_MOSI")
	)
	(segment
		(start 111.0234 -66.407792)
		(end 111.1504 -66.534792)
		(width 0.127)
		(layer "In7.Cu")
		(net "FPGA_FLASH_DQ0_MOSI")
	)
	(segment
		(start 112.0775 -65.899792)
		(end 111.1504 -65.899792)
		(width 0.127)
		(layer "In7.Cu")
		(net "FPGA_FLASH_DQ0_MOSI")
	)
	(segment
		(start 108.951268 -77.597508)
		(end 107.8738 -77.597508)
		(width 0.127)
		(layer "In7.Cu")
		(net "FPGA_FLASH_DQ0_MOSI")
	)
	(segment
		(start 107.7468 -75.565508)
		(end 107.8738 -75.692508)
		(width 0.127)
		(layer "In7.Cu")
		(net "FPGA_FLASH_DQ0_MOSI")
	)
	(segment
		(start 111.1504 -65.899792)
		(end 111.0234 -66.026792)
		(width 0.127)
		(layer "In7.Cu")
		(net "FPGA_FLASH_DQ0_MOSI")
	)
	(segment
		(start 113.284 -64.135)
		(end 112.3315 -64.135)
		(width 0.127)
		(layer "In7.Cu")
		(net "FPGA_FLASH_DQ0_MOSI")
	)
	(segment
		(start 111.0234 -64.756792)
		(end 111.0234 -65.137792)
		(width 0.127)
		(layer "In7.Cu")
		(net "FPGA_FLASH_DQ0_MOSI")
	)
	(segment
		(start 108.951268 -78.232508)
		(end 109.078268 -78.359508)
		(width 0.127)
		(layer "In7.Cu")
		(net "FPGA_FLASH_DQ0_MOSI")
	)
	(segment
		(start 107.7468 -76.454508)
		(end 107.7468 -76.835508)
		(width 0.127)
		(layer "In7.Cu")
		(net "FPGA_FLASH_DQ0_MOSI")
	)
	(segment
		(start 108.951268 -75.692508)
		(end 109.078268 -75.819508)
		(width 0.127)
		(layer "In7.Cu")
		(net "FPGA_FLASH_DQ0_MOSI")
	)
	(segment
		(start 111.1504 -66.534792)
		(end 112.0775 -66.534792)
		(width 0.127)
		(layer "In7.Cu")
		(net "FPGA_FLASH_DQ0_MOSI")
	)
	(segment
		(start 109.8042 -71.374254)
		(end 109.078268 -72.100186)
		(width 0.127)
		(layer "In7.Cu")
		(net "FPGA_FLASH_DQ0_MOSI")
	)
	(segment
		(start 107.7468 -78.105508)
		(end 107.8738 -78.232508)
		(width 0.127)
		(layer "In7.Cu")
		(net "FPGA_FLASH_DQ0_MOSI")
	)
	(segment
		(start 112.2045 -65.772792)
		(end 112.0775 -65.899792)
		(width 0.127)
		(layer "In7.Cu")
		(net "FPGA_FLASH_DQ0_MOSI")
	)
	(segment
		(start 109.078268 -74.930508)
		(end 108.951268 -75.057508)
		(width 0.127)
		(layer "In7.Cu")
		(net "FPGA_FLASH_DQ0_MOSI")
	)
	(segment
		(start 111.7092 -68.6562)
		(end 110.7694 -68.6562)
		(width 0.127)
		(layer "In7.Cu")
		(net "FPGA_FLASH_DQ0_MOSI")
	)
	(segment
		(start 109.078268 -75.819508)
		(end 109.078268 -76.200508)
		(width 0.127)
		(layer "In7.Cu")
		(net "FPGA_FLASH_DQ0_MOSI")
	)
	(segment
		(start 110.7694 -68.6562)
		(end 109.8042 -69.6214)
		(width 0.127)
		(layer "In7.Cu")
		(net "FPGA_FLASH_DQ0_MOSI")
	)
	(segment
		(start 113.553494 -81.137506)
		(end 111.9759 -81.137506)
		(width 0.11938)
		(layer "F.Cu")
		(net "FPGA_FLASH_CS_N")
	)
	(segment
		(start 118.11 -59.4614)
		(end 117.1956 -59.4614)
		(width 0.11938)
		(layer "F.Cu")
		(net "FPGA_FLASH_CS_N")
	)
	(segment
		(start 115.316 -79.375)
		(end 113.553494 -81.137506)
		(width 0.11938)
		(layer "F.Cu")
		(net "FPGA_FLASH_CS_N")
	)
	(segment
		(start 117.1956 -59.4614)
		(end 117.094 -59.563)
		(width 0.11938)
		(layer "F.Cu")
		(net "FPGA_FLASH_CS_N")
	)
	(via
		(at 117.094 -59.563)
		(size 0.508)
		(drill 0.254)
		(layers "F.Cu" "B.Cu")
		(net "FPGA_FLASH_CS_N")
	)
	(via
		(at 115.316 -79.375)
		(size 0.508)
		(drill 0.254)
		(layers "F.Cu" "B.Cu")
		(net "FPGA_FLASH_CS_N")
	)
	(segment
		(start 118.1608 -65.211198)
		(end 117.5258 -65.211198)
		(width 0.127)
		(layer "In7.Cu")
		(net "FPGA_FLASH_CS_N")
	)
	(segment
		(start 117.5258 -66.481198)
		(end 117.3988 -66.608198)
		(width 0.127)
		(layer "In7.Cu")
		(net "FPGA_FLASH_CS_N")
	)
	(segment
		(start 114.8842 -74.79284)
		(end 115.0112 -74.91984)
		(width 0.127)
		(layer "In7.Cu")
		(net "FPGA_FLASH_CS_N")
	)
	(segment
		(start 116.7765 -63.826898)
		(end 117.5258 -64.576198)
		(width 0.127)
		(layer "In7.Cu")
		(net "FPGA_FLASH_CS_N")
	)
	(segment
		(start 117.5258 -64.576198)
		(end 118.1608 -64.576198)
		(width 0.127)
		(layer "In7.Cu")
		(net "FPGA_FLASH_CS_N")
	)
	(segment
		(start 115.189 -79.375)
		(end 115.316 -79.375)
		(width 0.127)
		(layer "In7.Cu")
		(net "FPGA_FLASH_CS_N")
	)
	(segment
		(start 118.2878 -66.354198)
		(end 118.1608 -66.481198)
		(width 0.127)
		(layer "In7.Cu")
		(net "FPGA_FLASH_CS_N")
	)
	(segment
		(start 118.2878 -65.084198)
		(end 118.1608 -65.211198)
		(width 0.127)
		(layer "In7.Cu")
		(net "FPGA_FLASH_CS_N")
	)
	(segment
		(start 117.094 -60.96)
		(end 116.7765 -61.2775)
		(width 0.127)
		(layer "In7.Cu")
		(net "FPGA_FLASH_CS_N")
	)
	(segment
		(start 117.3988 -65.719198)
		(end 117.5258 -65.846198)
		(width 0.127)
		(layer "In7.Cu")
		(net "FPGA_FLASH_CS_N")
	)
	(segment
		(start 115.0112 -73.64984)
		(end 115.189 -73.64984)
		(width 0.127)
		(layer "In7.Cu")
		(net "FPGA_FLASH_CS_N")
	)
	(segment
		(start 117.856 -67.488054)
		(end 117.856 -68.834)
		(width 0.127)
		(layer "In7.Cu")
		(net "FPGA_FLASH_CS_N")
	)
	(segment
		(start 115.316 -74.15784)
		(end 115.189 -74.28484)
		(width 0.127)
		(layer "In7.Cu")
		(net "FPGA_FLASH_CS_N")
	)
	(segment
		(start 116.7765 -61.2775)
		(end 116.7765 -63.826898)
		(width 0.127)
		(layer "In7.Cu")
		(net "FPGA_FLASH_CS_N")
	)
	(segment
		(start 117.3988 -66.608198)
		(end 117.3988 -67.030854)
		(width 0.127)
		(layer "In7.Cu")
		(net "FPGA_FLASH_CS_N")
	)
	(segment
		(start 115.189 -73.64984)
		(end 115.316 -73.77684)
		(width 0.127)
		(layer "In7.Cu")
		(net "FPGA_FLASH_CS_N")
	)
	(segment
		(start 115.316 -75.438)
		(end 113.792 -76.962)
		(width 0.127)
		(layer "In7.Cu")
		(net "FPGA_FLASH_CS_N")
	)
	(segment
		(start 117.3988 -65.338198)
		(end 117.3988 -65.719198)
		(width 0.127)
		(layer "In7.Cu")
		(net "FPGA_FLASH_CS_N")
	)
	(segment
		(start 115.316 -71.374)
		(end 115.316 -72.88784)
		(width 0.127)
		(layer "In7.Cu")
		(net "FPGA_FLASH_CS_N")
	)
	(segment
		(start 118.1608 -64.576198)
		(end 118.2878 -64.703198)
		(width 0.127)
		(layer "In7.Cu")
		(net "FPGA_FLASH_CS_N")
	)
	(segment
		(start 114.8842 -73.52284)
		(end 115.0112 -73.64984)
		(width 0.127)
		(layer "In7.Cu")
		(net "FPGA_FLASH_CS_N")
	)
	(segment
		(start 113.792 -77.978)
		(end 115.189 -79.375)
		(width 0.127)
		(layer "In7.Cu")
		(net "FPGA_FLASH_CS_N")
	)
	(segment
		(start 114.8842 -73.14184)
		(end 114.8842 -73.52284)
		(width 0.127)
		(layer "In7.Cu")
		(net "FPGA_FLASH_CS_N")
	)
	(segment
		(start 117.5258 -65.846198)
		(end 118.1608 -65.846198)
		(width 0.127)
		(layer "In7.Cu")
		(net "FPGA_FLASH_CS_N")
	)
	(segment
		(start 118.2878 -65.973198)
		(end 118.2878 -66.354198)
		(width 0.127)
		(layer "In7.Cu")
		(net "FPGA_FLASH_CS_N")
	)
	(segment
		(start 117.3988 -67.030854)
		(end 117.856 -67.488054)
		(width 0.127)
		(layer "In7.Cu")
		(net "FPGA_FLASH_CS_N")
	)
	(segment
		(start 118.2878 -64.703198)
		(end 118.2878 -65.084198)
		(width 0.127)
		(layer "In7.Cu")
		(net "FPGA_FLASH_CS_N")
	)
	(segment
		(start 113.792 -76.962)
		(end 113.792 -77.978)
		(width 0.127)
		(layer "In7.Cu")
		(net "FPGA_FLASH_CS_N")
	)
	(segment
		(start 115.316 -73.77684)
		(end 115.316 -74.15784)
		(width 0.127)
		(layer "In7.Cu")
		(net "FPGA_FLASH_CS_N")
	)
	(segment
		(start 115.316 -72.88784)
		(end 115.189 -73.01484)
		(width 0.127)
		(layer "In7.Cu")
		(net "FPGA_FLASH_CS_N")
	)
	(segment
		(start 115.0112 -74.28484)
		(end 114.8842 -74.41184)
		(width 0.127)
		(layer "In7.Cu")
		(net "FPGA_FLASH_CS_N")
	)
	(segment
		(start 117.5258 -65.211198)
		(end 117.3988 -65.338198)
		(width 0.127)
		(layer "In7.Cu")
		(net "FPGA_FLASH_CS_N")
	)
	(segment
		(start 115.0112 -73.01484)
		(end 114.8842 -73.14184)
		(width 0.127)
		(layer "In7.Cu")
		(net "FPGA_FLASH_CS_N")
	)
	(segment
		(start 117.856 -68.834)
		(end 115.316 -71.374)
		(width 0.127)
		(layer "In7.Cu")
		(net "FPGA_FLASH_CS_N")
	)
	(segment
		(start 115.189 -74.91984)
		(end 115.316 -75.04684)
		(width 0.127)
		(layer "In7.Cu")
		(net "FPGA_FLASH_CS_N")
	)
	(segment
		(start 118.1608 -66.481198)
		(end 117.5258 -66.481198)
		(width 0.127)
		(layer "In7.Cu")
		(net "FPGA_FLASH_CS_N")
	)
	(segment
		(start 115.0112 -74.91984)
		(end 115.189 -74.91984)
		(width 0.127)
		(layer "In7.Cu")
		(net "FPGA_FLASH_CS_N")
	)
	(segment
		(start 115.189 -74.28484)
		(end 115.0112 -74.28484)
		(width 0.127)
		(layer "In7.Cu")
		(net "FPGA_FLASH_CS_N")
	)
	(segment
		(start 117.094 -59.563)
		(end 117.094 -60.96)
		(width 0.127)
		(layer "In7.Cu")
		(net "FPGA_FLASH_CS_N")
	)
	(segment
		(start 118.1608 -65.846198)
		(end 118.2878 -65.973198)
		(width 0.127)
		(layer "In7.Cu")
		(net "FPGA_FLASH_CS_N")
	)
	(segment
		(start 115.189 -73.01484)
		(end 115.0112 -73.01484)
		(width 0.127)
		(layer "In7.Cu")
		(net "FPGA_FLASH_CS_N")
	)
	(segment
		(start 114.8842 -74.41184)
		(end 114.8842 -74.79284)
		(width 0.127)
		(layer "In7.Cu")
		(net "FPGA_FLASH_CS_N")
	)
	(segment
		(start 115.316 -75.04684)
		(end 115.316 -75.438)
		(width 0.127)
		(layer "In7.Cu")
		(net "FPGA_FLASH_CS_N")
	)
	(segment
		(start 103.759 -81.787492)
		(end 105.9053 -81.787492)
		(width 0.11938)
		(layer "F.Cu")
		(net "FPGA_FLASH_CLK")
	)
	(via
		(at 103.759 -81.787492)
		(size 0.508)
		(drill 0.254)
		(layers "F.Cu" "B.Cu")
		(net "FPGA_FLASH_CLK")
	)
	(via
		(at 110.49 -63.627)
		(size 0.508)
		(drill 0.254)
		(layers "F.Cu" "B.Cu")
		(net "FPGA_FLASH_CLK")
	)
	(segment
		(start 110.49 -63.627)
		(end 110.49 -62.5094)
		(width 0.11938)
		(layer "B.Cu")
		(net "FPGA_FLASH_CLK")
	)
	(segment
		(start 103.759 -81.787492)
		(end 106.807 -78.739492)
		(width 0.127)
		(layer "In7.Cu")
		(net "FPGA_FLASH_CLK")
	)
	(segment
		(start 106.807 -70.485)
		(end 110.49 -66.802)
		(width 0.127)
		(layer "In7.Cu")
		(net "FPGA_FLASH_CLK")
	)
	(segment
		(start 106.807 -78.739492)
		(end 106.807 -70.485)
		(width 0.127)
		(layer "In7.Cu")
		(net "FPGA_FLASH_CLK")
	)
	(segment
		(start 110.49 -66.802)
		(end 110.49 -63.627)
		(width 0.127)
		(layer "In7.Cu")
		(net "FPGA_FLASH_CLK")
	)
	(segment
		(start 119.847106 -49.823116)
		(end 120.610884 -49.823116)
		(width 0.11938)
		(layer "F.Cu")
		(net "FPGA_EEPROM_I2C_SDA")
	)
	(segment
		(start 136.906 -20.701)
		(end 136.271 -20.066)
		(width 0.11938)
		(layer "F.Cu")
		(net "FPGA_EEPROM_I2C_SDA")
	)
	(segment
		(start 120.610884 -49.823116)
		(end 122.174 -48.26)
		(width 0.11938)
		(layer "F.Cu")
		(net "FPGA_EEPROM_I2C_SDA")
	)
	(segment
		(start 136.271 -20.066)
		(end 133.604 -20.066)
		(width 0.11938)
		(layer "F.Cu")
		(net "FPGA_EEPROM_I2C_SDA")
	)
	(segment
		(start 127.127254 -48.26)
		(end 128.016 -47.371254)
		(width 0.11938)
		(layer "F.Cu")
		(net "FPGA_EEPROM_I2C_SDA")
	)
	(segment
		(start 131.317746 -19.939)
		(end 131.149852 -20.106894)
		(width 0.11938)
		(layer "F.Cu")
		(net "FPGA_EEPROM_I2C_SDA")
	)
	(segment
		(start 136.525 -22.352)
		(end 136.906 -21.971)
		(width 0.11938)
		(layer "F.Cu")
		(net "FPGA_EEPROM_I2C_SDA")
	)
	(segment
		(start 133.604 -20.066)
		(end 133.3246 -19.7866)
		(width 0.11938)
		(layer "F.Cu")
		(net "FPGA_EEPROM_I2C_SDA")
	)
	(segment
		(start 129.286 -31.32836)
		(end 132.507228 -28.107132)
		(width 0.11938)
		(layer "F.Cu")
		(net "FPGA_EEPROM_I2C_SDA")
	)
	(segment
		(start 132.34162 -19.939)
		(end 131.317746 -19.939)
		(width 0.11938)
		(layer "F.Cu")
		(net "FPGA_EEPROM_I2C_SDA")
	)
	(segment
		(start 128.016 -47.371254)
		(end 128.016 -44.069)
		(width 0.11938)
		(layer "F.Cu")
		(net "FPGA_EEPROM_I2C_SDA")
	)
	(segment
		(start 131.149852 -20.106894)
		(end 130.1623 -20.106894)
		(width 0.11938)
		(layer "F.Cu")
		(net "FPGA_EEPROM_I2C_SDA")
	)
	(segment
		(start 122.174 -48.26)
		(end 127.127254 -48.26)
		(width 0.11938)
		(layer "F.Cu")
		(net "FPGA_EEPROM_I2C_SDA")
	)
	(segment
		(start 135.301228 -28.107132)
		(end 136.525 -26.88336)
		(width 0.11938)
		(layer "F.Cu")
		(net "FPGA_EEPROM_I2C_SDA")
	)
	(segment
		(start 129.286 -42.799)
		(end 129.286 -31.32836)
		(width 0.11938)
		(layer "F.Cu")
		(net "FPGA_EEPROM_I2C_SDA")
	)
	(segment
		(start 136.525 -26.88336)
		(end 136.525 -22.352)
		(width 0.11938)
		(layer "F.Cu")
		(net "FPGA_EEPROM_I2C_SDA")
	)
	(segment
		(start 133.3246 -19.304)
		(end 132.866384 -19.304)
		(width 0.11938)
		(layer "F.Cu")
		(net "FPGA_EEPROM_I2C_SDA")
	)
	(segment
		(start 132.866384 -19.304)
		(end 132.588 -19.582384)
		(width 0.11938)
		(layer "F.Cu")
		(net "FPGA_EEPROM_I2C_SDA")
	)
	(segment
		(start 133.3246 -19.7866)
		(end 133.3246 -19.304)
		(width 0.11938)
		(layer "F.Cu")
		(net "FPGA_EEPROM_I2C_SDA")
	)
	(segment
		(start 132.507228 -28.107132)
		(end 135.301228 -28.107132)
		(width 0.11938)
		(layer "F.Cu")
		(net "FPGA_EEPROM_I2C_SDA")
	)
	(segment
		(start 128.016 -44.069)
		(end 129.286 -42.799)
		(width 0.11938)
		(layer "F.Cu")
		(net "FPGA_EEPROM_I2C_SDA")
	)
	(segment
		(start 132.588 -19.69262)
		(end 132.34162 -19.939)
		(width 0.11938)
		(layer "F.Cu")
		(net "FPGA_EEPROM_I2C_SDA")
	)
	(segment
		(start 136.906 -21.971)
		(end 136.906 -20.701)
		(width 0.11938)
		(layer "F.Cu")
		(net "FPGA_EEPROM_I2C_SDA")
	)
	(segment
		(start 132.588 -19.582384)
		(end 132.588 -19.69262)
		(width 0.11938)
		(layer "F.Cu")
		(net "FPGA_EEPROM_I2C_SDA")
	)
	(via
		(at 136.271 -20.066)
		(size 0.508)
		(drill 0.254)
		(layers "F.Cu" "B.Cu")
		(net "FPGA_EEPROM_I2C_SDA")
	)
	(segment
		(start 120.84685 -48.823118)
		(end 121.917968 -47.752)
		(width 0.11938)
		(layer "F.Cu")
		(net "FPGA_EEPROM_I2C_SCL")
	)
	(segment
		(start 128.778 -31.114746)
		(end 132.295646 -27.5971)
		(width 0.11938)
		(layer "F.Cu")
		(net "FPGA_EEPROM_I2C_SCL")
	)
	(segment
		(start 133.91261 -26.77922)
		(end 134.03199 -26.65984)
		(width 0.11938)
		(layer "F.Cu")
		(net "FPGA_EEPROM_I2C_SCL")
	)
	(segment
		(start 136.017 -22.225)
		(end 136.271 -21.971)
		(width 0.11938)
		(layer "F.Cu")
		(net "FPGA_EEPROM_I2C_SCL")
	)
	(segment
		(start 133.3246 -20.828)
		(end 133.3246 -21.082)
		(width 0.11938)
		(layer "F.Cu")
		(net "FPGA_EEPROM_I2C_SCL")
	)
	(segment
		(start 134.03199 -26.65984)
		(end 134.42061 -26.65984)
		(width 0.11938)
		(layer "F.Cu")
		(net "FPGA_EEPROM_I2C_SCL")
	)
	(segment
		(start 128.778 -42.672)
		(end 128.778 -31.114746)
		(width 0.11938)
		(layer "F.Cu")
		(net "FPGA_EEPROM_I2C_SCL")
	)
	(segment
		(start 121.917968 -47.752)
		(end 126.746 -47.752)
		(width 0.11938)
		(layer "F.Cu")
		(net "FPGA_EEPROM_I2C_SCL")
	)
	(segment
		(start 132.715 -20.828)
		(end 132.207 -21.336)
		(width 0.11938)
		(layer "F.Cu")
		(net "FPGA_EEPROM_I2C_SCL")
	)
	(segment
		(start 119.847106 -48.823118)
		(end 120.84685 -48.823118)
		(width 0.11938)
		(layer "F.Cu")
		(net "FPGA_EEPROM_I2C_SCL")
	)
	(segment
		(start 132.207 -21.336)
		(end 131.953 -21.336)
		(width 0.11938)
		(layer "F.Cu")
		(net "FPGA_EEPROM_I2C_SCL")
	)
	(segment
		(start 131.953 -21.336)
		(end 131.231894 -22.057106)
		(width 0.11938)
		(layer "F.Cu")
		(net "FPGA_EEPROM_I2C_SCL")
	)
	(segment
		(start 134.42061 -26.65984)
		(end 134.53999 -26.77922)
		(width 0.11938)
		(layer "F.Cu")
		(net "FPGA_EEPROM_I2C_SCL")
	)
	(segment
		(start 127.508 -46.99)
		(end 127.508 -43.942)
		(width 0.11938)
		(layer "F.Cu")
		(net "FPGA_EEPROM_I2C_SCL")
	)
	(segment
		(start 133.91261 -27.47772)
		(end 133.91261 -26.77922)
		(width 0.11938)
		(layer "F.Cu")
		(net "FPGA_EEPROM_I2C_SCL")
	)
	(segment
		(start 127.508 -43.942)
		(end 128.778 -42.672)
		(width 0.11938)
		(layer "F.Cu")
		(net "FPGA_EEPROM_I2C_SCL")
	)
	(segment
		(start 135.0899 -27.5971)
		(end 136.017 -26.67)
		(width 0.11938)
		(layer "F.Cu")
		(net "FPGA_EEPROM_I2C_SCL")
	)
	(segment
		(start 132.77723 -26.65984)
		(end 133.16585 -26.65984)
		(width 0.11938)
		(layer "F.Cu")
		(net "FPGA_EEPROM_I2C_SCL")
	)
	(segment
		(start 133.28523 -26.77922)
		(end 133.28523 -27.47772)
		(width 0.11938)
		(layer "F.Cu")
		(net "FPGA_EEPROM_I2C_SCL")
	)
	(segment
		(start 126.746 -47.752)
		(end 127.508 -46.99)
		(width 0.11938)
		(layer "F.Cu")
		(net "FPGA_EEPROM_I2C_SCL")
	)
	(segment
		(start 131.231894 -22.057106)
		(end 130.1623 -22.057106)
		(width 0.11938)
		(layer "F.Cu")
		(net "FPGA_EEPROM_I2C_SCL")
	)
	(segment
		(start 132.295646 -27.5971)
		(end 132.53847 -27.5971)
		(width 0.11938)
		(layer "F.Cu")
		(net "FPGA_EEPROM_I2C_SCL")
	)
	(segment
		(start 136.271 -21.971)
		(end 136.271 -21.463)
		(width 0.11938)
		(layer "F.Cu")
		(net "FPGA_EEPROM_I2C_SCL")
	)
	(segment
		(start 132.65785 -27.47772)
		(end 132.65785 -26.77922)
		(width 0.11938)
		(layer "F.Cu")
		(net "FPGA_EEPROM_I2C_SCL")
	)
	(segment
		(start 133.7056 -21.463)
		(end 136.271 -21.463)
		(width 0.11938)
		(layer "F.Cu")
		(net "FPGA_EEPROM_I2C_SCL")
	)
	(segment
		(start 133.3246 -20.828)
		(end 132.715 -20.828)
		(width 0.11938)
		(layer "F.Cu")
		(net "FPGA_EEPROM_I2C_SCL")
	)
	(segment
		(start 134.65937 -27.5971)
		(end 135.0899 -27.5971)
		(width 0.11938)
		(layer "F.Cu")
		(net "FPGA_EEPROM_I2C_SCL")
	)
	(segment
		(start 132.65785 -26.77922)
		(end 132.77723 -26.65984)
		(width 0.11938)
		(layer "F.Cu")
		(net "FPGA_EEPROM_I2C_SCL")
	)
	(segment
		(start 136.017 -26.67)
		(end 136.017 -22.225)
		(width 0.11938)
		(layer "F.Cu")
		(net "FPGA_EEPROM_I2C_SCL")
	)
	(segment
		(start 133.79323 -27.5971)
		(end 133.91261 -27.47772)
		(width 0.11938)
		(layer "F.Cu")
		(net "FPGA_EEPROM_I2C_SCL")
	)
	(segment
		(start 132.53847 -27.5971)
		(end 132.65785 -27.47772)
		(width 0.11938)
		(layer "F.Cu")
		(net "FPGA_EEPROM_I2C_SCL")
	)
	(segment
		(start 133.3246 -21.082)
		(end 133.7056 -21.463)
		(width 0.11938)
		(layer "F.Cu")
		(net "FPGA_EEPROM_I2C_SCL")
	)
	(segment
		(start 134.53999 -26.77922)
		(end 134.53999 -27.47772)
		(width 0.11938)
		(layer "F.Cu")
		(net "FPGA_EEPROM_I2C_SCL")
	)
	(segment
		(start 133.28523 -27.47772)
		(end 133.40461 -27.5971)
		(width 0.11938)
		(layer "F.Cu")
		(net "FPGA_EEPROM_I2C_SCL")
	)
	(segment
		(start 133.16585 -26.65984)
		(end 133.28523 -26.77922)
		(width 0.11938)
		(layer "F.Cu")
		(net "FPGA_EEPROM_I2C_SCL")
	)
	(segment
		(start 134.53999 -27.47772)
		(end 134.65937 -27.5971)
		(width 0.11938)
		(layer "F.Cu")
		(net "FPGA_EEPROM_I2C_SCL")
	)
	(segment
		(start 133.40461 -27.5971)
		(end 133.79323 -27.5971)
		(width 0.11938)
		(layer "F.Cu")
		(net "FPGA_EEPROM_I2C_SCL")
	)
	(via
		(at 136.271 -21.463)
		(size 0.508)
		(drill 0.254)
		(layers "F.Cu" "B.Cu")
		(net "FPGA_EEPROM_I2C_SCL")
	)
	(segment
		(start 105.395014 -88.45296)
		(end 103.92156 -88.45296)
		(width 0.11938)
		(layer "F.Cu")
		(net "FLASH_DQ3")
	)
	(segment
		(start 103.632 -89.41308)
		(end 103.27894 -89.76614)
		(width 0.11938)
		(layer "F.Cu")
		(net "FLASH_DQ3")
	)
	(segment
		(start 103.632 -88.1634)
		(end 103.632 -89.41308)
		(width 0.11938)
		(layer "F.Cu")
		(net "FLASH_DQ3")
	)
	(segment
		(start 103.92156 -88.45296)
		(end 103.632 -88.1634)
		(width 0.11938)
		(layer "F.Cu")
		(net "FLASH_DQ3")
	)
	(via
		(at 103.27894 -89.76614)
		(size 0.508)
		(drill 0.254)
		(layers "F.Cu" "B.Cu")
		(net "FLASH_DQ3")
	)
	(segment
		(start 92.2782 -86.7664)
		(end 92.2782 -82.8802)
		(width 0.11938)
		(layer "B.Cu")
		(net "FLASH_DQ3")
	)
	(segment
		(start 103.27894 -89.76614)
		(end 102.489 -90.55608)
		(width 0.11938)
		(layer "B.Cu")
		(net "FLASH_DQ3")
	)
	(segment
		(start 91.567 -82.169)
		(end 89.0524 -82.169)
		(width 0.11938)
		(layer "B.Cu")
		(net "FLASH_DQ3")
	)
	(segment
		(start 100.4824 -90.55608)
		(end 99.52101 -89.59469)
		(width 0.11938)
		(layer "B.Cu")
		(net "FLASH_DQ3")
	)
	(segment
		(start 102.489 -90.55608)
		(end 100.4824 -90.55608)
		(width 0.11938)
		(layer "B.Cu")
		(net "FLASH_DQ3")
	)
	(segment
		(start 92.2782 -82.8802)
		(end 91.567 -82.169)
		(width 0.11938)
		(layer "B.Cu")
		(net "FLASH_DQ3")
	)
	(segment
		(start 95.10649 -89.59469)
		(end 92.2782 -86.7664)
		(width 0.11938)
		(layer "B.Cu")
		(net "FLASH_DQ3")
	)
	(segment
		(start 99.52101 -89.59469)
		(end 95.10649 -89.59469)
		(width 0.11938)
		(layer "B.Cu")
		(net "FLASH_DQ3")
	)
	(segment
		(start 98.66376 -88.40216)
		(end 98.298 -88.0364)
		(width 0.11938)
		(layer "F.Cu")
		(net "FLASH_DQ2")
	)
	(segment
		(start 100.442014 -88.40216)
		(end 98.66376 -88.40216)
		(width 0.11938)
		(layer "F.Cu")
		(net "FLASH_DQ2")
	)
	(segment
		(start 98.298 -88.0364)
		(end 97.282 -88.0364)
		(width 0.11938)
		(layer "F.Cu")
		(net "FLASH_DQ2")
	)
	(via
		(at 97.282 -88.0364)
		(size 0.4572)
		(drill 0.2032)
		(layers "F.Cu" "B.Cu")
		(net "FLASH_DQ2")
	)
	(segment
		(start 95.0976 -86.741)
		(end 95.0976 -87.2236)
		(width 0.11938)
		(layer "B.Cu")
		(net "FLASH_DQ2")
	)
	(segment
		(start 97.0026 -87.757)
		(end 97.282 -88.0364)
		(width 0.11938)
		(layer "B.Cu")
		(net "FLASH_DQ2")
	)
	(segment
		(start 95.0976 -87.2236)
		(end 95.631 -87.757)
		(width 0.11938)
		(layer "B.Cu")
		(net "FLASH_DQ2")
	)
	(segment
		(start 95.631 -87.757)
		(end 97.0026 -87.757)
		(width 0.11938)
		(layer "B.Cu")
		(net "FLASH_DQ2")
	)
	(segment
		(start 111.9759 -77.887322)
		(end 110.526322 -77.887322)
		(width 0.11938)
		(layer "F.Cu")
		(net "FLASH_DQ1_MISO")
	)
	(via
		(at 110.526322 -77.887322)
		(size 0.508)
		(drill 0.254)
		(layers "F.Cu" "B.Cu")
		(net "FLASH_DQ1_MISO")
	)
	(via
		(at 93.98 -84.455)
		(size 0.508)
		(drill 0.254)
		(layers "F.Cu" "B.Cu")
		(net "FLASH_DQ1_MISO")
	)
	(segment
		(start 94.234 -81.28)
		(end 93.66631 -81.84769)
		(width 0.11938)
		(layer "B.Cu")
		(net "FLASH_DQ1_MISO")
	)
	(segment
		(start 101.78669 -79.82331)
		(end 101.346 -80.264)
		(width 0.11938)
		(layer "B.Cu")
		(net "FLASH_DQ1_MISO")
	)
	(segment
		(start 93.66631 -84.14131)
		(end 93.98 -84.455)
		(width 0.11938)
		(layer "B.Cu")
		(net "FLASH_DQ1_MISO")
	)
	(segment
		(start 97.917 -81.28)
		(end 94.234 -81.28)
		(width 0.11938)
		(layer "B.Cu")
		(net "FLASH_DQ1_MISO")
	)
	(segment
		(start 110.526322 -77.887322)
		(end 106.034078 -77.887322)
		(width 0.11938)
		(layer "B.Cu")
		(net "FLASH_DQ1_MISO")
	)
	(segment
		(start 98.933 -80.264)
		(end 97.917 -81.28)
		(width 0.11938)
		(layer "B.Cu")
		(net "FLASH_DQ1_MISO")
	)
	(segment
		(start 106.034078 -77.887322)
		(end 104.09809 -79.82331)
		(width 0.11938)
		(layer "B.Cu")
		(net "FLASH_DQ1_MISO")
	)
	(segment
		(start 101.346 -80.264)
		(end 98.933 -80.264)
		(width 0.11938)
		(layer "B.Cu")
		(net "FLASH_DQ1_MISO")
	)
	(segment
		(start 104.09809 -79.82331)
		(end 101.78669 -79.82331)
		(width 0.11938)
		(layer "B.Cu")
		(net "FLASH_DQ1_MISO")
	)
	(segment
		(start 93.66631 -81.84769)
		(end 93.66631 -84.14131)
		(width 0.11938)
		(layer "B.Cu")
		(net "FLASH_DQ1_MISO")
	)
	(segment
		(start 95.0976 -84.455)
		(end 93.98 -84.455)
		(width 0.11938)
		(layer "B.Cu")
		(net "FLASH_DQ1_MISO")
	)
	(segment
		(start 90.9955 -82.3087)
		(end 93.1672 -80.137)
		(width 0.11938)
		(layer "F.Cu")
		(net "FLASH_DQ0_MOSI")
	)
	(segment
		(start 104.14 -78.232)
		(end 104.445308 -78.537308)
		(width 0.11938)
		(layer "F.Cu")
		(net "FLASH_DQ0_MOSI")
	)
	(segment
		(start 101.727 -80.137)
		(end 103.632 -78.232)
		(width 0.11938)
		(layer "F.Cu")
		(net "FLASH_DQ0_MOSI")
	)
	(segment
		(start 104.445308 -78.537308)
		(end 105.9053 -78.537308)
		(width 0.11938)
		(layer "F.Cu")
		(net "FLASH_DQ0_MOSI")
	)
	(segment
		(start 93.1672 -80.137)
		(end 101.727 -80.137)
		(width 0.11938)
		(layer "F.Cu")
		(net "FLASH_DQ0_MOSI")
	)
	(segment
		(start 103.632 -78.232)
		(end 104.14 -78.232)
		(width 0.11938)
		(layer "F.Cu")
		(net "FLASH_DQ0_MOSI")
	)
	(segment
		(start 90.9955 -86.3727)
		(end 90.9955 -82.3087)
		(width 0.11938)
		(layer "F.Cu")
		(net "FLASH_DQ0_MOSI")
	)
	(via
		(at 90.9955 -86.3727)
		(size 0.4572)
		(drill 0.2032)
		(layers "F.Cu" "B.Cu")
		(net "FLASH_DQ0_MOSI")
	)
	(segment
		(start 90.6272 -86.741)
		(end 89.0524 -86.741)
		(width 0.11938)
		(layer "B.Cu")
		(net "FLASH_DQ0_MOSI")
	)
	(segment
		(start 90.9955 -86.3727)
		(end 90.6272 -86.741)
		(width 0.11938)
		(layer "B.Cu")
		(net "FLASH_DQ0_MOSI")
	)
	(segment
		(start 111.9759 -79.83728)
		(end 109.982 -79.83728)
		(width 0.11938)
		(layer "F.Cu")
		(net "FLASH_CS_N")
	)
	(segment
		(start 95.7326 -82.169)
		(end 97.282 -82.169)
		(width 0.11938)
		(layer "F.Cu")
		(net "FLASH_CS_N")
	)
	(via
		(at 109.982 -79.83728)
		(size 0.508)
		(drill 0.254)
		(layers "F.Cu" "B.Cu")
		(net "FLASH_CS_N")
	)
	(via
		(at 97.282 -82.169)
		(size 0.508)
		(drill 0.254)
		(layers "F.Cu" "B.Cu")
		(net "FLASH_CS_N")
	)
	(segment
		(start 106.59237 -79.31658)
		(end 106.71175 -79.1972)
		(width 0.11938)
		(layer "B.Cu")
		(net "FLASH_CS_N")
	)
	(segment
		(start 107.96651 -79.1972)
		(end 108.35513 -79.1972)
		(width 0.11938)
		(layer "B.Cu")
		(net "FLASH_CS_N")
	)
	(segment
		(start 105.96499 -79.31658)
		(end 105.96499 -80.846422)
		(width 0.11938)
		(layer "B.Cu")
		(net "FLASH_CS_N")
	)
	(segment
		(start 106.59237 -80.846422)
		(end 106.59237 -79.31658)
		(width 0.11938)
		(layer "B.Cu")
		(net "FLASH_CS_N")
	)
	(segment
		(start 107.33913 -80.965802)
		(end 107.72775 -80.965802)
		(width 0.11938)
		(layer "B.Cu")
		(net "FLASH_CS_N")
	)
	(segment
		(start 107.72775 -80.965802)
		(end 107.84713 -80.846422)
		(width 0.11938)
		(layer "B.Cu")
		(net "FLASH_CS_N")
	)
	(segment
		(start 105.33761 -80.846422)
		(end 105.33761 -79.31658)
		(width 0.11938)
		(layer "B.Cu")
		(net "FLASH_CS_N")
	)
	(segment
		(start 107.10037 -79.1972)
		(end 107.21975 -79.31658)
		(width 0.11938)
		(layer "B.Cu")
		(net "FLASH_CS_N")
	)
	(segment
		(start 96.1644 -82.169)
		(end 97.282 -82.169)
		(width 0.11938)
		(layer "B.Cu")
		(net "FLASH_CS_N")
	)
	(segment
		(start 108.35513 -79.1972)
		(end 108.47451 -79.31658)
		(width 0.11938)
		(layer "B.Cu")
		(net "FLASH_CS_N")
	)
	(segment
		(start 106.71175 -79.1972)
		(end 107.10037 -79.1972)
		(width 0.11938)
		(layer "B.Cu")
		(net "FLASH_CS_N")
	)
	(segment
		(start 106.47299 -80.965802)
		(end 106.59237 -80.846422)
		(width 0.11938)
		(layer "B.Cu")
		(net "FLASH_CS_N")
	)
	(segment
		(start 108.47451 -79.31658)
		(end 108.47451 -80.846422)
		(width 0.11938)
		(layer "B.Cu")
		(net "FLASH_CS_N")
	)
	(segment
		(start 106.08437 -80.965802)
		(end 106.47299 -80.965802)
		(width 0.11938)
		(layer "B.Cu")
		(net "FLASH_CS_N")
	)
	(segment
		(start 105.21823 -80.965802)
		(end 105.33761 -80.846422)
		(width 0.11938)
		(layer "B.Cu")
		(net "FLASH_CS_N")
	)
	(segment
		(start 99.568 -80.772)
		(end 101.727 -80.772)
		(width 0.11938)
		(layer "B.Cu")
		(net "FLASH_CS_N")
	)
	(segment
		(start 105.96499 -80.846422)
		(end 106.08437 -80.965802)
		(width 0.11938)
		(layer "B.Cu")
		(net "FLASH_CS_N")
	)
	(segment
		(start 107.84713 -79.31658)
		(end 107.96651 -79.1972)
		(width 0.11938)
		(layer "B.Cu")
		(net "FLASH_CS_N")
	)
	(segment
		(start 101.920802 -80.965802)
		(end 105.21823 -80.965802)
		(width 0.11938)
		(layer "B.Cu")
		(net "FLASH_CS_N")
	)
	(segment
		(start 107.21975 -80.846422)
		(end 107.33913 -80.965802)
		(width 0.11938)
		(layer "B.Cu")
		(net "FLASH_CS_N")
	)
	(segment
		(start 107.84713 -80.846422)
		(end 107.84713 -79.31658)
		(width 0.11938)
		(layer "B.Cu")
		(net "FLASH_CS_N")
	)
	(segment
		(start 105.33761 -79.31658)
		(end 105.45699 -79.1972)
		(width 0.11938)
		(layer "B.Cu")
		(net "FLASH_CS_N")
	)
	(segment
		(start 105.84561 -79.1972)
		(end 105.96499 -79.31658)
		(width 0.11938)
		(layer "B.Cu")
		(net "FLASH_CS_N")
	)
	(segment
		(start 97.282 -82.169)
		(end 98.171 -82.169)
		(width 0.11938)
		(layer "B.Cu")
		(net "FLASH_CS_N")
	)
	(segment
		(start 107.21975 -79.31658)
		(end 107.21975 -80.846422)
		(width 0.11938)
		(layer "B.Cu")
		(net "FLASH_CS_N")
	)
	(segment
		(start 108.47451 -80.846422)
		(end 108.59389 -80.965802)
		(width 0.11938)
		(layer "B.Cu")
		(net "FLASH_CS_N")
	)
	(segment
		(start 108.59389 -80.965802)
		(end 108.853478 -80.965802)
		(width 0.11938)
		(layer "B.Cu")
		(net "FLASH_CS_N")
	)
	(segment
		(start 101.727 -80.772)
		(end 101.920802 -80.965802)
		(width 0.11938)
		(layer "B.Cu")
		(net "FLASH_CS_N")
	)
	(segment
		(start 105.45699 -79.1972)
		(end 105.84561 -79.1972)
		(width 0.11938)
		(layer "B.Cu")
		(net "FLASH_CS_N")
	)
	(segment
		(start 108.853478 -80.965802)
		(end 109.982 -79.83728)
		(width 0.11938)
		(layer "B.Cu")
		(net "FLASH_CS_N")
	)
	(segment
		(start 98.171 -82.169)
		(end 99.568 -80.772)
		(width 0.11938)
		(layer "B.Cu")
		(net "FLASH_CS_N")
	)
	(segment
		(start 104.75976 -80.391)
		(end 104.85628 -80.48752)
		(width 0.11938)
		(layer "F.Cu")
		(net "FLASH_CLK")
	)
	(segment
		(start 103.759 -80.391)
		(end 104.75976 -80.391)
		(width 0.11938)
		(layer "F.Cu")
		(net "FLASH_CLK")
	)
	(segment
		(start 88.4174 -84.709)
		(end 86.741 -84.709)
		(width 0.11938)
		(layer "F.Cu")
		(net "FLASH_CLK")
	)
	(segment
		(start 104.85628 -80.48752)
		(end 105.9053 -80.48752)
		(width 0.11938)
		(layer "F.Cu")
		(net "FLASH_CLK")
	)
	(via
		(at 103.759 -80.391)
		(size 0.508)
		(drill 0.254)
		(layers "F.Cu" "B.Cu")
		(net "FLASH_CLK")
	)
	(via
		(at 86.741 -84.709)
		(size 0.4572)
		(drill 0.2032)
		(layers "F.Cu" "B.Cu")
		(net "FLASH_CLK")
	)
	(segment
		(start 86.995 -84.455)
		(end 87.9856 -84.455)
		(width 0.11938)
		(layer "B.Cu")
		(net "FLASH_CLK")
	)
	(segment
		(start 86.741 -84.709)
		(end 86.995 -84.455)
		(width 0.11938)
		(layer "B.Cu")
		(net "FLASH_CLK")
	)
	(segment
		(start 88.54694 -83.8581)
		(end 88.67394 -83.9851)
		(width 0.127)
		(layer "In2.Cu")
		(net "FLASH_CLK")
	)
	(segment
		(start 88.80094 -86.0298)
		(end 89.18194 -86.0298)
		(width 0.127)
		(layer "In2.Cu")
		(net "FLASH_CLK")
	)
	(segment
		(start 89.30894 -83.9851)
		(end 89.43594 -83.8581)
		(width 0.127)
		(layer "In2.Cu")
		(net "FLASH_CLK")
	)
	(segment
		(start 89.43594 -83.8581)
		(end 96.928686 -83.8581)
		(width 0.127)
		(layer "In2.Cu")
		(net "FLASH_CLK")
	)
	(segment
		(start 89.18194 -86.0298)
		(end 89.30894 -85.9028)
		(width 0.127)
		(layer "In2.Cu")
		(net "FLASH_CLK")
	)
	(segment
		(start 88.67394 -85.9028)
		(end 88.80094 -86.0298)
		(width 0.127)
		(layer "In2.Cu")
		(net "FLASH_CLK")
	)
	(segment
		(start 88.67394 -83.9851)
		(end 88.67394 -85.9028)
		(width 0.127)
		(layer "In2.Cu")
		(net "FLASH_CLK")
	)
	(segment
		(start 100.2411 -84.1629)
		(end 103.759 -80.645)
		(width 0.127)
		(layer "In2.Cu")
		(net "FLASH_CLK")
	)
	(segment
		(start 96.928686 -83.8581)
		(end 97.233486 -84.1629)
		(width 0.127)
		(layer "In2.Cu")
		(net "FLASH_CLK")
	)
	(segment
		(start 87.5919 -83.8581)
		(end 88.54694 -83.8581)
		(width 0.127)
		(layer "In2.Cu")
		(net "FLASH_CLK")
	)
	(segment
		(start 86.741 -84.709)
		(end 87.5919 -83.8581)
		(width 0.127)
		(layer "In2.Cu")
		(net "FLASH_CLK")
	)
	(segment
		(start 103.759 -80.645)
		(end 103.759 -80.391)
		(width 0.127)
		(layer "In2.Cu")
		(net "FLASH_CLK")
	)
	(segment
		(start 89.30894 -85.9028)
		(end 89.30894 -83.9851)
		(width 0.127)
		(layer "In2.Cu")
		(net "FLASH_CLK")
	)
	(segment
		(start 97.233486 -84.1629)
		(end 100.2411 -84.1629)
		(width 0.127)
		(layer "In2.Cu")
		(net "FLASH_CLK")
	)
	(segment
		(start 19.304 -33.909)
		(end 20.32 -33.909)
		(width 0.11938)
		(layer "F.Cu")
		(net "EEPROM_SDA")
	)
	(segment
		(start 31.02356 -16.72844)
		(end 30.87878 -16.72844)
		(width 0.11938)
		(layer "F.Cu")
		(net "EEPROM_SDA")
	)
	(segment
		(start 32.1056 -15.748)
		(end 32.004 -15.748)
		(width 0.11938)
		(layer "F.Cu")
		(net "EEPROM_SDA")
	)
	(segment
		(start 33.2359 -15.5702)
		(end 33.2359 -16.7132)
		(width 0.11938)
		(layer "F.Cu")
		(net "EEPROM_SDA")
	)
	(segment
		(start 33.2359 -15.5702)
		(end 32.2834 -15.5702)
		(width 0.11938)
		(layer "F.Cu")
		(net "EEPROM_SDA")
	)
	(segment
		(start 20.447 -34.036)
		(end 20.447 -36.129976)
		(width 0.11938)
		(layer "F.Cu")
		(net "EEPROM_SDA")
	)
	(segment
		(start 32.2834 -15.5702)
		(end 32.1056 -15.748)
		(width 0.11938)
		(layer "F.Cu")
		(net "EEPROM_SDA")
	)
	(segment
		(start 20.32 -33.909)
		(end 20.447 -34.036)
		(width 0.11938)
		(layer "F.Cu")
		(net "EEPROM_SDA")
	)
	(segment
		(start 18.796 -33.02)
		(end 18.796 -33.401)
		(width 0.11938)
		(layer "F.Cu")
		(net "EEPROM_SDA")
	)
	(segment
		(start 18.796 -33.401)
		(end 19.304 -33.909)
		(width 0.11938)
		(layer "F.Cu")
		(net "EEPROM_SDA")
	)
	(segment
		(start 32.004 -15.748)
		(end 31.02356 -16.72844)
		(width 0.11938)
		(layer "F.Cu")
		(net "EEPROM_SDA")
	)
	(via
		(at 18.796 -33.02)
		(size 0.508)
		(drill 0.254)
		(layers "F.Cu" "B.Cu")
		(net "EEPROM_SDA")
	)
	(via
		(at 32.004 -15.748)
		(size 0.4572)
		(drill 0.2032)
		(layers "F.Cu" "B.Cu")
		(net "EEPROM_SDA")
	)
	(via
		(at 19.939 -20.8915)
		(size 0.508)
		(drill 0.254)
		(layers "F.Cu" "B.Cu")
		(net "EEPROM_SDA")
	)
	(segment
		(start 32.004 -15.748)
		(end 32.2707 -15.748)
		(width 0.11938)
		(layer "B.Cu")
		(net "EEPROM_SDA")
	)
	(segment
		(start 19.8247 -20.8915)
		(end 18.8976 -21.8186)
		(width 0.11938)
		(layer "B.Cu")
		(net "EEPROM_SDA")
	)
	(segment
		(start 18.8976 -21.8186)
		(end 18.3134 -21.8186)
		(width 0.11938)
		(layer "B.Cu")
		(net "EEPROM_SDA")
	)
	(segment
		(start 32.2707 -15.748)
		(end 33.2359 -16.7132)
		(width 0.11938)
		(layer "B.Cu")
		(net "EEPROM_SDA")
	)
	(segment
		(start 19.939 -20.8915)
		(end 19.8247 -20.8915)
		(width 0.11938)
		(layer "B.Cu")
		(net "EEPROM_SDA")
	)
	(segment
		(start 32.004 -15.748)
		(end 31.8643 -15.748)
		(width 0.11938)
		(layer "B.Cu")
		(net "EEPROM_SDA")
	)
	(segment
		(start 31.8643 -15.748)
		(end 30.88132 -16.73098)
		(width 0.11938)
		(layer "B.Cu")
		(net "EEPROM_SDA")
	)
	(segment
		(start 18.796 -33.02)
		(end 19.764756 -32.051244)
		(width 0.127)
		(layer "In7.Cu")
		(net "EEPROM_SDA")
	)
	(segment
		(start 20.701 -22.474428)
		(end 20.5867 -22.360128)
		(width 0.127)
		(layer "In7.Cu")
		(net "EEPROM_SDA")
	)
	(segment
		(start 19.50466 -20.8915)
		(end 18.814034 -20.200874)
		(width 0.127)
		(layer "In7.Cu")
		(net "EEPROM_SDA")
	)
	(segment
		(start 27.82062 -17.907)
		(end 28.23464 -17.49298)
		(width 0.127)
		(layer "In7.Cu")
		(net "EEPROM_SDA")
	)
	(segment
		(start 20.5867 -22.360128)
		(end 20.5867 -21.5392)
		(width 0.127)
		(layer "In7.Cu")
		(net "EEPROM_SDA")
	)
	(segment
		(start 20.5867 -21.5392)
		(end 19.939 -20.8915)
		(width 0.127)
		(layer "In7.Cu")
		(net "EEPROM_SDA")
	)
	(segment
		(start 19.939 -20.8915)
		(end 19.50466 -20.8915)
		(width 0.127)
		(layer "In7.Cu")
		(net "EEPROM_SDA")
	)
	(segment
		(start 19.812 -17.907)
		(end 27.82062 -17.907)
		(width 0.127)
		(layer "In7.Cu")
		(net "EEPROM_SDA")
	)
	(segment
		(start 18.814034 -18.904966)
		(end 19.812 -17.907)
		(width 0.127)
		(layer "In7.Cu")
		(net "EEPROM_SDA")
	)
	(segment
		(start 18.814034 -20.200874)
		(end 18.814034 -18.904966)
		(width 0.127)
		(layer "In7.Cu")
		(net "EEPROM_SDA")
	)
	(segment
		(start 30.25902 -17.49298)
		(end 32.004 -15.748)
		(width 0.127)
		(layer "In7.Cu")
		(net "EEPROM_SDA")
	)
	(segment
		(start 19.764756 -27.733244)
		(end 20.701 -26.797)
		(width 0.127)
		(layer "In7.Cu")
		(net "EEPROM_SDA")
	)
	(segment
		(start 19.764756 -32.051244)
		(end 19.764756 -27.733244)
		(width 0.127)
		(layer "In7.Cu")
		(net "EEPROM_SDA")
	)
	(segment
		(start 20.701 -26.797)
		(end 20.701 -22.474428)
		(width 0.127)
		(layer "In7.Cu")
		(net "EEPROM_SDA")
	)
	(segment
		(start 28.23464 -17.49298)
		(end 30.25902 -17.49298)
		(width 0.127)
		(layer "In7.Cu")
		(net "EEPROM_SDA")
	)
	(segment
		(start 17.653 -33.02)
		(end 17.907 -33.274)
		(width 0.11938)
		(layer "F.Cu")
		(net "EEPROM_SCL")
	)
	(segment
		(start 33.24098 -19.1262)
		(end 33.24098 -17.9832)
		(width 0.11938)
		(layer "F.Cu")
		(net "EEPROM_SCL")
	)
	(segment
		(start 29.81198 -17.99844)
		(end 29.142436 -17.99844)
		(width 0.11938)
		(layer "F.Cu")
		(net "EEPROM_SCL")
	)
	(segment
		(start 31.6484 -17.3736)
		(end 29.93136 -17.3736)
		(width 0.11938)
		(layer "F.Cu")
		(net "EEPROM_SCL")
	)
	(segment
		(start 19.385534 -19.8882)
		(end 19.32686 -19.946874)
		(width 0.11938)
		(layer "F.Cu")
		(net "EEPROM_SCL")
	)
	(segment
		(start 29.025596 -17.8816)
		(end 26.3398 -17.8816)
		(width 0.11938)
		(layer "F.Cu")
		(net "EEPROM_SCL")
	)
	(segment
		(start 29.93136 -17.3736)
		(end 29.81198 -17.49298)
		(width 0.11938)
		(layer "F.Cu")
		(net "EEPROM_SCL")
	)
	(segment
		(start 32.27578 -17.018)
		(end 33.24098 -17.9832)
		(width 0.11938)
		(layer "F.Cu")
		(net "EEPROM_SCL")
	)
	(segment
		(start 18.25244 -20.38096)
		(end 18.77568 -19.85772)
		(width 0.11938)
		(layer "F.Cu")
		(net "EEPROM_SCL")
	)
	(segment
		(start 19.32686 -21.21662)
		(end 19.19478 -21.3487)
		(width 0.11938)
		(layer "F.Cu")
		(net "EEPROM_SCL")
	)
	(segment
		(start 32.004 -17.018)
		(end 31.6484 -17.3736)
		(width 0.11938)
		(layer "F.Cu")
		(net "EEPROM_SCL")
	)
	(segment
		(start 19.32686 -19.946874)
		(end 19.32686 -21.21662)
		(width 0.11938)
		(layer "F.Cu")
		(net "EEPROM_SCL")
	)
	(segment
		(start 29.81198 -17.49298)
		(end 29.81198 -17.99844)
		(width 0.11938)
		(layer "F.Cu")
		(net "EEPROM_SCL")
	)
	(segment
		(start 19.360134 -19.001486)
		(end 19.360134 -17.9959)
		(width 0.11938)
		(layer "F.Cu")
		(net "EEPROM_SCL")
	)
	(segment
		(start 18.57248 -21.3487)
		(end 18.25244 -21.02866)
		(width 0.11938)
		(layer "F.Cu")
		(net "EEPROM_SCL")
	)
	(segment
		(start 29.142436 -17.99844)
		(end 29.025596 -17.8816)
		(width 0.11938)
		(layer "F.Cu")
		(net "EEPROM_SCL")
	)
	(segment
		(start 26.3398 -17.8816)
		(end 25.72004 -18.50136)
		(width 0.11938)
		(layer "F.Cu")
		(net "EEPROM_SCL")
	)
	(segment
		(start 19.19478 -21.3487)
		(end 18.57248 -21.3487)
		(width 0.11938)
		(layer "F.Cu")
		(net "EEPROM_SCL")
	)
	(segment
		(start 32.004 -17.018)
		(end 32.27578 -17.018)
		(width 0.11938)
		(layer "F.Cu")
		(net "EEPROM_SCL")
	)
	(segment
		(start 18.25244 -21.02866)
		(end 18.25244 -20.38096)
		(width 0.11938)
		(layer "F.Cu")
		(net "EEPROM_SCL")
	)
	(segment
		(start 18.77568 -19.85772)
		(end 18.77568 -19.58594)
		(width 0.11938)
		(layer "F.Cu")
		(net "EEPROM_SCL")
	)
	(segment
		(start 17.907 -33.274)
		(end 17.907 -36.129976)
		(width 0.11938)
		(layer "F.Cu")
		(net "EEPROM_SCL")
	)
	(segment
		(start 18.77568 -19.58594)
		(end 19.360134 -19.001486)
		(width 0.11938)
		(layer "F.Cu")
		(net "EEPROM_SCL")
	)
	(segment
		(start 25.72004 -18.50136)
		(end 24.3205 -18.50136)
		(width 0.11938)
		(layer "F.Cu")
		(net "EEPROM_SCL")
	)
	(via
		(at 19.385534 -19.8882)
		(size 0.508)
		(drill 0.254)
		(layers "F.Cu" "B.Cu")
		(net "EEPROM_SCL")
	)
	(via
		(at 32.004 -17.018)
		(size 0.4572)
		(drill 0.2032)
		(layers "F.Cu" "B.Cu")
		(net "EEPROM_SCL")
	)
	(via
		(at 17.653 -33.02)
		(size 0.508)
		(drill 0.254)
		(layers "F.Cu" "B.Cu")
		(net "EEPROM_SCL")
	)
	(segment
		(start 32.27578 -17.018)
		(end 32.004 -17.018)
		(width 0.11938)
		(layer "B.Cu")
		(net "EEPROM_SCL")
	)
	(segment
		(start 33.24098 -17.9832)
		(end 32.27578 -17.018)
		(width 0.11938)
		(layer "B.Cu")
		(net "EEPROM_SCL")
	)
	(segment
		(start 23.462488 -19.05254)
		(end 23.589488 -19.17954)
		(width 0.127)
		(layer "In7.Cu")
		(net "EEPROM_SCL")
	)
	(segment
		(start 23.335488 -18.415)
		(end 23.462488 -18.542)
		(width 0.127)
		(layer "In7.Cu")
		(net "EEPROM_SCL")
	)
	(segment
		(start 24.859488 -19.17954)
		(end 25.240488 -19.17954)
		(width 0.127)
		(layer "In7.Cu")
		(net "EEPROM_SCL")
	)
	(segment
		(start 22.954488 -18.415)
		(end 23.335488 -18.415)
		(width 0.127)
		(layer "In7.Cu")
		(net "EEPROM_SCL")
	)
	(segment
		(start 22.827488 -18.542)
		(end 22.954488 -18.415)
		(width 0.127)
		(layer "In7.Cu")
		(net "EEPROM_SCL")
	)
	(segment
		(start 23.462488 -18.542)
		(end 23.462488 -19.05254)
		(width 0.127)
		(layer "In7.Cu")
		(net "EEPROM_SCL")
	)
	(segment
		(start 19.385534 -19.8882)
		(end 19.385534 -19.052032)
		(width 0.127)
		(layer "In7.Cu")
		(net "EEPROM_SCL")
	)
	(segment
		(start 19.177 -33.655)
		(end 18.288 -33.655)
		(width 0.127)
		(layer "In7.Cu")
		(net "EEPROM_SCL")
	)
	(segment
		(start 25.367488 -19.05254)
		(end 25.367488 -18.542)
		(width 0.127)
		(layer "In7.Cu")
		(net "EEPROM_SCL")
	)
	(segment
		(start 25.494488 -18.415)
		(end 28.031186 -18.415)
		(width 0.127)
		(layer "In7.Cu")
		(net "EEPROM_SCL")
	)
	(segment
		(start 18.288 -33.655)
		(end 17.653 -33.02)
		(width 0.127)
		(layer "In7.Cu")
		(net "EEPROM_SCL")
	)
	(segment
		(start 19.790918 -19.8882)
		(end 22.0345 -22.131782)
		(width 0.127)
		(layer "In7.Cu")
		(net "EEPROM_SCL")
	)
	(segment
		(start 22.827488 -18.66138)
		(end 22.827488 -18.542)
		(width 0.127)
		(layer "In7.Cu")
		(net "EEPROM_SCL")
	)
	(segment
		(start 22.700488 -18.78838)
		(end 22.827488 -18.66138)
		(width 0.127)
		(layer "In7.Cu")
		(net "EEPROM_SCL")
	)
	(segment
		(start 22.192488 -18.542)
		(end 22.192488 -18.66138)
		(width 0.127)
		(layer "In7.Cu")
		(net "EEPROM_SCL")
	)
	(segment
		(start 28.031186 -18.415)
		(end 28.445206 -18.00098)
		(width 0.127)
		(layer "In7.Cu")
		(net "EEPROM_SCL")
	)
	(segment
		(start 22.0345 -22.131782)
		(end 22.0345 -26.2255)
		(width 0.127)
		(layer "In7.Cu")
		(net "EEPROM_SCL")
	)
	(segment
		(start 24.224488 -18.415)
		(end 24.605488 -18.415)
		(width 0.127)
		(layer "In7.Cu")
		(net "EEPROM_SCL")
	)
	(segment
		(start 20.022566 -18.415)
		(end 22.065488 -18.415)
		(width 0.127)
		(layer "In7.Cu")
		(net "EEPROM_SCL")
	)
	(segment
		(start 20.32 -32.512)
		(end 19.177 -33.655)
		(width 0.127)
		(layer "In7.Cu")
		(net "EEPROM_SCL")
	)
	(segment
		(start 22.0345 -26.2255)
		(end 20.32 -27.94)
		(width 0.127)
		(layer "In7.Cu")
		(net "EEPROM_SCL")
	)
	(segment
		(start 30.64002 -18.00098)
		(end 31.4706 -17.1704)
		(width 0.127)
		(layer "In7.Cu")
		(net "EEPROM_SCL")
	)
	(segment
		(start 25.367488 -18.542)
		(end 25.494488 -18.415)
		(width 0.127)
		(layer "In7.Cu")
		(net "EEPROM_SCL")
	)
	(segment
		(start 22.065488 -18.415)
		(end 22.192488 -18.542)
		(width 0.127)
		(layer "In7.Cu")
		(net "EEPROM_SCL")
	)
	(segment
		(start 24.097488 -19.05254)
		(end 24.097488 -18.542)
		(width 0.127)
		(layer "In7.Cu")
		(net "EEPROM_SCL")
	)
	(segment
		(start 24.732488 -19.05254)
		(end 24.859488 -19.17954)
		(width 0.127)
		(layer "In7.Cu")
		(net "EEPROM_SCL")
	)
	(segment
		(start 28.445206 -18.00098)
		(end 30.64002 -18.00098)
		(width 0.127)
		(layer "In7.Cu")
		(net "EEPROM_SCL")
	)
	(segment
		(start 19.385534 -19.052032)
		(end 20.022566 -18.415)
		(width 0.127)
		(layer "In7.Cu")
		(net "EEPROM_SCL")
	)
	(segment
		(start 24.732488 -18.542)
		(end 24.732488 -19.05254)
		(width 0.127)
		(layer "In7.Cu")
		(net "EEPROM_SCL")
	)
	(segment
		(start 23.589488 -19.17954)
		(end 23.970488 -19.17954)
		(width 0.127)
		(layer "In7.Cu")
		(net "EEPROM_SCL")
	)
	(segment
		(start 23.970488 -19.17954)
		(end 24.097488 -19.05254)
		(width 0.127)
		(layer "In7.Cu")
		(net "EEPROM_SCL")
	)
	(segment
		(start 19.385534 -19.8882)
		(end 19.790918 -19.8882)
		(width 0.127)
		(layer "In7.Cu")
		(net "EEPROM_SCL")
	)
	(segment
		(start 22.319488 -18.78838)
		(end 22.700488 -18.78838)
		(width 0.127)
		(layer "In7.Cu")
		(net "EEPROM_SCL")
	)
	(segment
		(start 31.8516 -17.1704)
		(end 32.004 -17.018)
		(width 0.127)
		(layer "In7.Cu")
		(net "EEPROM_SCL")
	)
	(segment
		(start 22.192488 -18.66138)
		(end 22.319488 -18.78838)
		(width 0.127)
		(layer "In7.Cu")
		(net "EEPROM_SCL")
	)
	(segment
		(start 24.605488 -18.415)
		(end 24.732488 -18.542)
		(width 0.127)
		(layer "In7.Cu")
		(net "EEPROM_SCL")
	)
	(segment
		(start 25.240488 -19.17954)
		(end 25.367488 -19.05254)
		(width 0.127)
		(layer "In7.Cu")
		(net "EEPROM_SCL")
	)
	(segment
		(start 24.097488 -18.542)
		(end 24.224488 -18.415)
		(width 0.127)
		(layer "In7.Cu")
		(net "EEPROM_SCL")
	)
	(segment
		(start 31.4706 -17.1704)
		(end 31.8516 -17.1704)
		(width 0.127)
		(layer "In7.Cu")
		(net "EEPROM_SCL")
	)
	(segment
		(start 20.32 -27.94)
		(end 20.32 -32.512)
		(width 0.127)
		(layer "In7.Cu")
		(net "EEPROM_SCL")
	)
	(segment
		(start 85.973158 -76.581)
		(end 84.328 -76.581)
		(width 0.11938)
		(layer "B.Cu")
		(net "BNO080_EVN_SDA")
	)
	(segment
		(start 89.281 -74.889106)
		(end 89.281 -75.565)
		(width 0.11938)
		(layer "B.Cu")
		(net "BNO080_EVN_SDA")
	)
	(segment
		(start 89.13749 -73.23709)
		(end 89.13749 -74.745596)
		(width 0.11938)
		(layer "B.Cu")
		(net "BNO080_EVN_SDA")
	)
	(segment
		(start 89.281 -75.565)
		(end 88.9 -75.946)
		(width 0.11938)
		(layer "B.Cu")
		(net "BNO080_EVN_SDA")
	)
	(segment
		(start 86.608158 -75.946)
		(end 85.973158 -76.581)
		(width 0.11938)
		(layer "B.Cu")
		(net "BNO080_EVN_SDA")
	)
	(segment
		(start 88.646 -72.7456)
		(end 89.13749 -73.23709)
		(width 0.11938)
		(layer "B.Cu")
		(net "BNO080_EVN_SDA")
	)
	(segment
		(start 88.9 -75.946)
		(end 86.608158 -75.946)
		(width 0.11938)
		(layer "B.Cu")
		(net "BNO080_EVN_SDA")
	)
	(segment
		(start 87.376 -72.7456)
		(end 88.519 -72.7456)
		(width 0.11938)
		(layer "B.Cu")
		(net "BNO080_EVN_SDA")
	)
	(segment
		(start 89.13749 -74.745596)
		(end 89.281 -74.889106)
		(width 0.11938)
		(layer "B.Cu")
		(net "BNO080_EVN_SDA")
	)
	(segment
		(start 88.519 -72.7456)
		(end 88.646 -72.7456)
		(width 0.11938)
		(layer "B.Cu")
		(net "BNO080_EVN_SDA")
	)
	(segment
		(start 86.233 -74.549)
		(end 86.233 -73.8124)
		(width 0.11938)
		(layer "B.Cu")
		(net "BNO080_EVN_SCL")
	)
	(segment
		(start 82.99831 -75.75169)
		(end 86.18093 -75.75169)
		(width 0.11938)
		(layer "B.Cu")
		(net "BNO080_EVN_SCL")
	)
	(segment
		(start 86.487 -75.44562)
		(end 86.487 -74.803)
		(width 0.11938)
		(layer "B.Cu")
		(net "BNO080_EVN_SCL")
	)
	(segment
		(start 86.487 -74.803)
		(end 86.233 -74.549)
		(width 0.11938)
		(layer "B.Cu")
		(net "BNO080_EVN_SCL")
	)
	(segment
		(start 86.233 -73.8124)
		(end 85.09 -73.8124)
		(width 0.11938)
		(layer "B.Cu")
		(net "BNO080_EVN_SCL")
	)
	(segment
		(start 82.296 -76.454)
		(end 82.99831 -75.75169)
		(width 0.11938)
		(layer "B.Cu")
		(net "BNO080_EVN_SCL")
	)
	(segment
		(start 86.18093 -75.75169)
		(end 86.487 -75.44562)
		(width 0.11938)
		(layer "B.Cu")
		(net "BNO080_EVN_SCL")
	)
	(segment
		(start 16.854424 -41.340024)
		(end 17.907 -41.340024)
		(width 0.11938)
		(layer "F.Cu")
		(net "UNNAMED_5_CONNHDR2X2MSSMT_I12_1")
	)
	(segment
		(start 15.3924 -39.878)
		(end 16.854424 -41.340024)
		(width 0.11938)
		(layer "F.Cu")
		(net "UNNAMED_5_CONNHDR2X2MSSMT_I12_1")
	)
	(via
		(at 15.3924 -39.878)
		(size 0.508)
		(drill 0.254)
		(layers "F.Cu" "B.Cu")
		(net "UNNAMED_5_CONNHDR2X2MSSMT_I12_1")
	)
	(segment
		(start 15.3924 -39.7002)
		(end 17.1196 -37.973)
		(width 0.11938)
		(layer "B.Cu")
		(net "UNNAMED_5_CONNHDR2X2MSSMT_I12_1")
	)
	(segment
		(start 15.3924 -39.878)
		(end 15.3924 -39.7002)
		(width 0.11938)
		(layer "B.Cu")
		(net "UNNAMED_5_CONNHDR2X2MSSMT_I12_1")
	)
	(segment
		(start 20.447 -42.418)
		(end 20.447 -41.340024)
		(width 0.11938)
		(layer "F.Cu")
		(net "UNNAMED_5_CONNHDR2X2MSSMT_I126_")
	)
	(segment
		(start 21.209 -43.942)
		(end 21.209 -43.18)
		(width 0.11938)
		(layer "F.Cu")
		(net "UNNAMED_5_CONNHDR2X2MSSMT_I126_")
	)
	(segment
		(start 21.209 -43.18)
		(end 20.447 -42.418)
		(width 0.11938)
		(layer "F.Cu")
		(net "UNNAMED_5_CONNHDR2X2MSSMT_I126_")
	)
	(via
		(at 21.209 -43.942)
		(size 0.508)
		(drill 0.254)
		(layers "F.Cu" "B.Cu")
		(net "UNNAMED_5_CONNHDR2X2MSSMT_I126_")
	)
	(segment
		(start 21.209 -43.942)
		(end 21.59 -43.561)
		(width 0.11938)
		(layer "B.Cu")
		(net "UNNAMED_5_CONNHDR2X2MSSMT_I126_")
	)
	(segment
		(start 21.59 -43.561)
		(end 21.59 -42.7736)
		(width 0.11938)
		(layer "B.Cu")
		(net "UNNAMED_5_CONNHDR2X2MSSMT_I126_")
	)
	(segment
		(start 1.745996 -83.925156)
		(end 8.149844 -83.925156)
		(width 0.11938)
		(layer "F.Cu")
		(net "UNNAMED_14_LED4PV14_I269_4")
	)
	(segment
		(start 10.922 -82.0674)
		(end 9.652 -82.0674)
		(width 0.11938)
		(layer "F.Cu")
		(net "UNNAMED_14_LED4PV14_I269_4")
	)
	(segment
		(start 9.017 -83.058)
		(end 9.652 -82.423)
		(width 0.11938)
		(layer "F.Cu")
		(net "UNNAMED_14_LED4PV14_I269_4")
	)
	(segment
		(start 8.149844 -83.925156)
		(end 9.017 -83.058)
		(width 0.11938)
		(layer "F.Cu")
		(net "UNNAMED_14_LED4PV14_I269_4")
	)
	(segment
		(start 9.652 -82.423)
		(end 9.652 -82.0674)
		(width 0.11938)
		(layer "F.Cu")
		(net "UNNAMED_14_LED4PV14_I269_4")
	)
	(via
		(at 9.017 -83.058)
		(size 0.508)
		(drill 0.254)
		(layers "F.Cu" "B.Cu")
		(net "UNNAMED_14_LED4PV14_I269_4")
	)
	(segment
		(start 7.112 -83.058)
		(end 3.81 -83.058)
		(width 0.11938)
		(layer "F.Cu")
		(net "UNNAMED_14_LED4PV14_I269_3")
	)
	(segment
		(start 8.382 -82.0674)
		(end 7.112 -82.0674)
		(width 0.11938)
		(layer "F.Cu")
		(net "UNNAMED_14_LED4PV14_I269_3")
	)
	(segment
		(start 3.77698 -83.02498)
		(end 2.096008 -83.02498)
		(width 0.11938)
		(layer "F.Cu")
		(net "UNNAMED_14_LED4PV14_I269_3")
	)
	(segment
		(start 3.81 -83.058)
		(end 3.77698 -83.02498)
		(width 0.11938)
		(layer "F.Cu")
		(net "UNNAMED_14_LED4PV14_I269_3")
	)
	(segment
		(start 7.112 -82.0674)
		(end 7.112 -83.058)
		(width 0.11938)
		(layer "F.Cu")
		(net "UNNAMED_14_LED4PV14_I269_3")
	)
	(via
		(at 7.112 -83.058)
		(size 0.508)
		(drill 0.254)
		(layers "F.Cu" "B.Cu")
		(net "UNNAMED_14_LED4PV14_I269_3")
	)
	(segment
		(start 3.8354 -81.4832)
		(end 3.8354 -81.94802)
		(width 0.11938)
		(layer "F.Cu")
		(net "UNNAMED_14_LED4PV14_I269_1")
	)
	(segment
		(start 3.302 -80.9498)
		(end 3.8354 -81.4832)
		(width 0.11938)
		(layer "F.Cu")
		(net "UNNAMED_14_LED4PV14_I269_1")
	)
	(segment
		(start 3.95478 -82.0674)
		(end 4.572 -82.0674)
		(width 0.11938)
		(layer "F.Cu")
		(net "UNNAMED_14_LED4PV14_I269_1")
	)
	(segment
		(start 2.794 -80.9498)
		(end 3.302 -80.9498)
		(width 0.11938)
		(layer "F.Cu")
		(net "UNNAMED_14_LED4PV14_I269_1")
	)
	(segment
		(start 2.46888 -81.27492)
		(end 2.794 -80.9498)
		(width 0.11938)
		(layer "F.Cu")
		(net "UNNAMED_14_LED4PV14_I269_1")
	)
	(segment
		(start 4.572 -82.0674)
		(end 5.842 -82.0674)
		(width 0.11938)
		(layer "F.Cu")
		(net "UNNAMED_14_LED4PV14_I269_1")
	)
	(segment
		(start 1.745996 -81.27492)
		(end 2.46888 -81.27492)
		(width 0.11938)
		(layer "F.Cu")
		(net "UNNAMED_14_LED4PV14_I269_1")
	)
	(segment
		(start 3.8354 -81.94802)
		(end 3.95478 -82.0674)
		(width 0.11938)
		(layer "F.Cu")
		(net "UNNAMED_14_LED4PV14_I269_1")
	)
	(via
		(at 3.302 -80.9498)
		(size 0.508)
		(drill 0.254)
		(layers "F.Cu" "B.Cu")
		(net "UNNAMED_14_LED4PV14_I269_1")
	)
	(segment
		(start 3.175 -55.753)
		(end 2.347214 -54.925214)
		(width 0.11938)
		(layer "F.Cu")
		(net "UNNAMED_14_LED4PV14_I268_4")
	)
	(segment
		(start 18.934938 -50.165)
		(end 17.791938 -50.165)
		(width 0.11938)
		(layer "F.Cu")
		(net "UNNAMED_14_LED4PV14_I268_4")
	)
	(segment
		(start 2.347214 -54.925214)
		(end 1.745996 -54.925214)
		(width 0.11938)
		(layer "F.Cu")
		(net "UNNAMED_14_LED4PV14_I268_4")
	)
	(segment
		(start 17.791938 -50.165)
		(end 17.531842 -50.425096)
		(width 0.11938)
		(layer "F.Cu")
		(net "UNNAMED_14_LED4PV14_I268_4")
	)
	(segment
		(start 18.934938 -50.165)
		(end 18.934938 -49.022)
		(width 0.11938)
		(layer "F.Cu")
		(net "UNNAMED_14_LED4PV14_I268_4")
	)
	(via
		(at 17.531842 -50.425096)
		(size 0.508)
		(drill 0.254)
		(layers "F.Cu" "B.Cu")
		(net "UNNAMED_14_LED4PV14_I268_4")
	)
	(via
		(at 3.175 -55.753)
		(size 0.508)
		(drill 0.254)
		(layers "F.Cu" "B.Cu")
		(net "UNNAMED_14_LED4PV14_I268_4")
	)
	(segment
		(start 3.175 -55.753)
		(end 6.096 -55.753)
		(width 0.11938)
		(layer "B.Cu")
		(net "UNNAMED_14_LED4PV14_I268_4")
	)
	(segment
		(start 6.096 -55.753)
		(end 12.446 -49.403)
		(width 0.11938)
		(layer "B.Cu")
		(net "UNNAMED_14_LED4PV14_I268_4")
	)
	(segment
		(start 12.446 -49.403)
		(end 16.509746 -49.403)
		(width 0.11938)
		(layer "B.Cu")
		(net "UNNAMED_14_LED4PV14_I268_4")
	)
	(segment
		(start 16.509746 -49.403)
		(end 17.531842 -50.425096)
		(width 0.11938)
		(layer "B.Cu")
		(net "UNNAMED_14_LED4PV14_I268_4")
	)
	(segment
		(start 18.542 -47.879)
		(end 18.934938 -47.879)
		(width 0.11938)
		(layer "F.Cu")
		(net "UNNAMED_14_LED4PV14_I268_3")
	)
	(segment
		(start 18.934938 -47.879)
		(end 18.934938 -46.736)
		(width 0.11938)
		(layer "F.Cu")
		(net "UNNAMED_14_LED4PV14_I268_3")
	)
	(segment
		(start 3.048 -54.483)
		(end 2.590038 -54.025038)
		(width 0.11938)
		(layer "F.Cu")
		(net "UNNAMED_14_LED4PV14_I268_3")
	)
	(segment
		(start 17.526 -48.895)
		(end 18.542 -47.879)
		(width 0.11938)
		(layer "F.Cu")
		(net "UNNAMED_14_LED4PV14_I268_3")
	)
	(segment
		(start 3.175 -54.483)
		(end 3.048 -54.483)
		(width 0.11938)
		(layer "F.Cu")
		(net "UNNAMED_14_LED4PV14_I268_3")
	)
	(segment
		(start 2.590038 -54.025038)
		(end 2.096008 -54.025038)
		(width 0.11938)
		(layer "F.Cu")
		(net "UNNAMED_14_LED4PV14_I268_3")
	)
	(segment
		(start 17.526 -49.022)
		(end 17.526 -48.895)
		(width 0.11938)
		(layer "F.Cu")
		(net "UNNAMED_14_LED4PV14_I268_3")
	)
	(via
		(at 3.175 -54.483)
		(size 0.508)
		(drill 0.254)
		(layers "F.Cu" "B.Cu")
		(net "UNNAMED_14_LED4PV14_I268_3")
	)
	(via
		(at 17.526 -49.022)
		(size 0.508)
		(drill 0.254)
		(layers "F.Cu" "B.Cu")
		(net "UNNAMED_14_LED4PV14_I268_3")
	)
	(segment
		(start 6.731 -54.483)
		(end 12.573 -48.641)
		(width 0.11938)
		(layer "B.Cu")
		(net "UNNAMED_14_LED4PV14_I268_3")
	)
	(segment
		(start 12.573 -48.641)
		(end 17.145 -48.641)
		(width 0.11938)
		(layer "B.Cu")
		(net "UNNAMED_14_LED4PV14_I268_3")
	)
	(segment
		(start 17.145 -48.641)
		(end 17.526 -49.022)
		(width 0.11938)
		(layer "B.Cu")
		(net "UNNAMED_14_LED4PV14_I268_3")
	)
	(segment
		(start 3.175 -54.483)
		(end 6.731 -54.483)
		(width 0.11938)
		(layer "B.Cu")
		(net "UNNAMED_14_LED4PV14_I268_3")
	)
	(segment
		(start 18.934938 -45.593)
		(end 18.669 -45.593)
		(width 0.11938)
		(layer "F.Cu")
		(net "UNNAMED_14_LED4PV14_I268_1")
	)
	(segment
		(start 18.934938 -45.593)
		(end 18.934938 -44.45)
		(width 0.11938)
		(layer "F.Cu")
		(net "UNNAMED_14_LED4PV14_I268_1")
	)
	(segment
		(start 2.843022 -52.274978)
		(end 1.745996 -52.274978)
		(width 0.11938)
		(layer "F.Cu")
		(net "UNNAMED_14_LED4PV14_I268_1")
	)
	(segment
		(start 18.669 -45.593)
		(end 17.526 -46.736)
		(width 0.11938)
		(layer "F.Cu")
		(net "UNNAMED_14_LED4PV14_I268_1")
	)
	(segment
		(start 17.526 -46.736)
		(end 17.526 -47.625)
		(width 0.11938)
		(layer "F.Cu")
		(net "UNNAMED_14_LED4PV14_I268_1")
	)
	(segment
		(start 3.175 -51.943)
		(end 2.843022 -52.274978)
		(width 0.11938)
		(layer "F.Cu")
		(net "UNNAMED_14_LED4PV14_I268_1")
	)
	(via
		(at 17.526 -47.625)
		(size 0.508)
		(drill 0.254)
		(layers "F.Cu" "B.Cu")
		(net "UNNAMED_14_LED4PV14_I268_1")
	)
	(via
		(at 3.175 -51.943)
		(size 0.508)
		(drill 0.254)
		(layers "F.Cu" "B.Cu")
		(net "UNNAMED_14_LED4PV14_I268_1")
	)
	(segment
		(start 13.989304 -45.72)
		(end 15.621 -45.72)
		(width 0.11938)
		(layer "B.Cu")
		(net "UNNAMED_14_LED4PV14_I268_1")
	)
	(segment
		(start 12.37869 -46.530006)
		(end 13.248386 -45.66031)
		(width 0.11938)
		(layer "B.Cu")
		(net "UNNAMED_14_LED4PV14_I268_1")
	)
	(segment
		(start 13.248386 -45.66031)
		(end 13.929614 -45.66031)
		(width 0.11938)
		(layer "B.Cu")
		(net "UNNAMED_14_LED4PV14_I268_1")
	)
	(segment
		(start 12.37869 -46.695614)
		(end 12.37869 -46.530006)
		(width 0.11938)
		(layer "B.Cu")
		(net "UNNAMED_14_LED4PV14_I268_1")
	)
	(segment
		(start 12.192 -47.244)
		(end 12.192 -46.882304)
		(width 0.11938)
		(layer "B.Cu")
		(net "UNNAMED_14_LED4PV14_I268_1")
	)
	(segment
		(start 6.604 -52.832)
		(end 12.192 -47.244)
		(width 0.11938)
		(layer "B.Cu")
		(net "UNNAMED_14_LED4PV14_I268_1")
	)
	(segment
		(start 4.191 -52.832)
		(end 6.604 -52.832)
		(width 0.11938)
		(layer "B.Cu")
		(net "UNNAMED_14_LED4PV14_I268_1")
	)
	(segment
		(start 15.621 -45.72)
		(end 17.526 -47.625)
		(width 0.11938)
		(layer "B.Cu")
		(net "UNNAMED_14_LED4PV14_I268_1")
	)
	(segment
		(start 3.175 -51.943)
		(end 3.302 -51.943)
		(width 0.11938)
		(layer "B.Cu")
		(net "UNNAMED_14_LED4PV14_I268_1")
	)
	(segment
		(start 13.929614 -45.66031)
		(end 13.989304 -45.72)
		(width 0.11938)
		(layer "B.Cu")
		(net "UNNAMED_14_LED4PV14_I268_1")
	)
	(segment
		(start 3.302 -51.943)
		(end 4.191 -52.832)
		(width 0.11938)
		(layer "B.Cu")
		(net "UNNAMED_14_LED4PV14_I268_1")
	)
	(segment
		(start 12.192 -46.882304)
		(end 12.37869 -46.695614)
		(width 0.11938)
		(layer "B.Cu")
		(net "UNNAMED_14_LED4PV14_I268_1")
	)
	(segment
		(start 9.5758 -68.734432)
		(end 10.7188 -68.734432)
		(width 0.11938)
		(layer "F.Cu")
		(net "UNNAMED_14_LED4PV14_I267_4")
	)
	(segment
		(start 1.745996 -69.425058)
		(end 3.302 -69.425058)
		(width 0.11938)
		(layer "F.Cu")
		(net "UNNAMED_14_LED4PV14_I267_4")
	)
	(segment
		(start 7.952232 -70.358)
		(end 9.5758 -68.734432)
		(width 0.11938)
		(layer "F.Cu")
		(net "UNNAMED_14_LED4PV14_I267_4")
	)
	(segment
		(start 3.302 -69.425058)
		(end 4.234942 -70.358)
		(width 0.11938)
		(layer "F.Cu")
		(net "UNNAMED_14_LED4PV14_I267_4")
	)
	(segment
		(start 4.234942 -70.358)
		(end 7.952232 -70.358)
		(width 0.11938)
		(layer "F.Cu")
		(net "UNNAMED_14_LED4PV14_I267_4")
	)
	(via
		(at 3.302 -69.425058)
		(size 0.508)
		(drill 0.254)
		(layers "F.Cu" "B.Cu")
		(net "UNNAMED_14_LED4PV14_I267_4")
	)
	(segment
		(start 7.112 -69.85)
		(end 4.6736 -69.85)
		(width 0.11938)
		(layer "F.Cu")
		(net "UNNAMED_14_LED4PV14_I267_3")
	)
	(segment
		(start 3.348482 -68.524882)
		(end 2.096008 -68.524882)
		(width 0.11938)
		(layer "F.Cu")
		(net "UNNAMED_14_LED4PV14_I267_3")
	)
	(segment
		(start 7.2898 -68.734432)
		(end 7.2898 -69.6722)
		(width 0.11938)
		(layer "F.Cu")
		(net "UNNAMED_14_LED4PV14_I267_3")
	)
	(segment
		(start 4.6736 -69.85)
		(end 3.348482 -68.524882)
		(width 0.11938)
		(layer "F.Cu")
		(net "UNNAMED_14_LED4PV14_I267_3")
	)
	(segment
		(start 7.2898 -69.6722)
		(end 7.112 -69.85)
		(width 0.11938)
		(layer "F.Cu")
		(net "UNNAMED_14_LED4PV14_I267_3")
	)
	(segment
		(start 7.2898 -68.734432)
		(end 8.4328 -68.734432)
		(width 0.11938)
		(layer "F.Cu")
		(net "UNNAMED_14_LED4PV14_I267_3")
	)
	(via
		(at 7.2898 -69.6722)
		(size 0.508)
		(drill 0.254)
		(layers "F.Cu" "B.Cu")
		(net "UNNAMED_14_LED4PV14_I267_3")
	)
	(segment
		(start 4.472432 -68.734432)
		(end 3.9878 -68.2498)
		(width 0.11938)
		(layer "F.Cu")
		(net "UNNAMED_14_LED4PV14_I267_1")
	)
	(segment
		(start 2.794 -66.421)
		(end 2.440178 -66.774822)
		(width 0.11938)
		(layer "F.Cu")
		(net "UNNAMED_14_LED4PV14_I267_1")
	)
	(segment
		(start 3.429 -66.421)
		(end 3.175 -66.421)
		(width 0.11938)
		(layer "F.Cu")
		(net "UNNAMED_14_LED4PV14_I267_1")
	)
	(segment
		(start 2.440178 -66.774822)
		(end 1.745996 -66.774822)
		(width 0.11938)
		(layer "F.Cu")
		(net "UNNAMED_14_LED4PV14_I267_1")
	)
	(segment
		(start 3.175 -66.421)
		(end 2.794 -66.421)
		(width 0.11938)
		(layer "F.Cu")
		(net "UNNAMED_14_LED4PV14_I267_1")
	)
	(segment
		(start 5.0038 -68.734432)
		(end 6.1468 -68.734432)
		(width 0.11938)
		(layer "F.Cu")
		(net "UNNAMED_14_LED4PV14_I267_1")
	)
	(segment
		(start 5.0038 -68.734432)
		(end 4.472432 -68.734432)
		(width 0.11938)
		(layer "F.Cu")
		(net "UNNAMED_14_LED4PV14_I267_1")
	)
	(segment
		(start 3.9878 -66.9798)
		(end 3.429 -66.421)
		(width 0.11938)
		(layer "F.Cu")
		(net "UNNAMED_14_LED4PV14_I267_1")
	)
	(segment
		(start 3.9878 -68.2498)
		(end 3.9878 -66.9798)
		(width 0.11938)
		(layer "F.Cu")
		(net "UNNAMED_14_LED4PV14_I267_1")
	)
	(via
		(at 3.175 -66.421)
		(size 0.508)
		(drill 0.254)
		(layers "F.Cu" "B.Cu")
		(net "UNNAMED_14_LED4PV14_I267_1")
	)
	(segment
		(start 18.669 -30.226)
		(end 18.669 -30.6324)
		(width 0.11938)
		(layer "F.Cu")
		(net "UNNAMED_14_LED4PV14_I266_4")
	)
	(segment
		(start 2.744978 -26.924)
		(end 1.745996 -25.925018)
		(width 0.11938)
		(layer "F.Cu")
		(net "UNNAMED_14_LED4PV14_I266_4")
	)
	(segment
		(start 19.7866 -31.75)
		(end 19.7866 -33.02)
		(width 0.11938)
		(layer "F.Cu")
		(net "UNNAMED_14_LED4PV14_I266_4")
	)
	(segment
		(start 18.669 -30.6324)
		(end 19.7866 -31.75)
		(width 0.11938)
		(layer "F.Cu")
		(net "UNNAMED_14_LED4PV14_I266_4")
	)
	(segment
		(start 3.175 -26.924)
		(end 2.744978 -26.924)
		(width 0.11938)
		(layer "F.Cu")
		(net "UNNAMED_14_LED4PV14_I266_4")
	)
	(via
		(at 18.669 -30.226)
		(size 0.508)
		(drill 0.254)
		(layers "F.Cu" "B.Cu")
		(net "UNNAMED_14_LED4PV14_I266_4")
	)
	(via
		(at 3.175 -26.924)
		(size 0.508)
		(drill 0.254)
		(layers "F.Cu" "B.Cu")
		(net "UNNAMED_14_LED4PV14_I266_4")
	)
	(segment
		(start 15.251176 -29.89707)
		(end 15.639796 -30.28569)
		(width 0.11938)
		(layer "B.Cu")
		(net "UNNAMED_14_LED4PV14_I266_4")
	)
	(segment
		(start 16.442944 -30.28569)
		(end 16.950944 -30.79369)
		(width 0.11938)
		(layer "B.Cu")
		(net "UNNAMED_14_LED4PV14_I266_4")
	)
	(segment
		(start 16.950944 -30.79369)
		(end 18.10131 -30.79369)
		(width 0.11938)
		(layer "B.Cu")
		(net "UNNAMED_14_LED4PV14_I266_4")
	)
	(segment
		(start 7.239 -26.924)
		(end 10.02538 -29.71038)
		(width 0.11938)
		(layer "B.Cu")
		(net "UNNAMED_14_LED4PV14_I266_4")
	)
	(segment
		(start 10.02538 -29.71038)
		(end 13.66901 -29.71038)
		(width 0.11938)
		(layer "B.Cu")
		(net "UNNAMED_14_LED4PV14_I266_4")
	)
	(segment
		(start 18.10131 -30.79369)
		(end 18.669 -30.226)
		(width 0.11938)
		(layer "B.Cu")
		(net "UNNAMED_14_LED4PV14_I266_4")
	)
	(segment
		(start 15.639796 -30.28569)
		(end 16.442944 -30.28569)
		(width 0.11938)
		(layer "B.Cu")
		(net "UNNAMED_14_LED4PV14_I266_4")
	)
	(segment
		(start 13.8557 -29.89707)
		(end 15.251176 -29.89707)
		(width 0.11938)
		(layer "B.Cu")
		(net "UNNAMED_14_LED4PV14_I266_4")
	)
	(segment
		(start 13.66901 -29.71038)
		(end 13.8557 -29.89707)
		(width 0.11938)
		(layer "B.Cu")
		(net "UNNAMED_14_LED4PV14_I266_4")
	)
	(segment
		(start 3.175 -26.924)
		(end 7.239 -26.924)
		(width 0.11938)
		(layer "B.Cu")
		(net "UNNAMED_14_LED4PV14_I266_4")
	)
	(segment
		(start 17.399 -30.226)
		(end 18.415 -29.21)
		(width 0.11938)
		(layer "F.Cu")
		(net "UNNAMED_14_LED4PV14_I266_3")
	)
	(segment
		(start 3.175 -25.609804)
		(end 2.590038 -25.024842)
		(width 0.11938)
		(layer "F.Cu")
		(net "UNNAMED_14_LED4PV14_I266_3")
	)
	(segment
		(start 18.415 -29.21)
		(end 19.7866 -29.21)
		(width 0.11938)
		(layer "F.Cu")
		(net "UNNAMED_14_LED4PV14_I266_3")
	)
	(segment
		(start 2.590038 -25.024842)
		(end 2.096008 -25.024842)
		(width 0.11938)
		(layer "F.Cu")
		(net "UNNAMED_14_LED4PV14_I266_3")
	)
	(segment
		(start 3.175 -25.654)
		(end 3.175 -25.609804)
		(width 0.11938)
		(layer "F.Cu")
		(net "UNNAMED_14_LED4PV14_I266_3")
	)
	(segment
		(start 19.7866 -30.48)
		(end 19.7866 -29.21)
		(width 0.11938)
		(layer "F.Cu")
		(net "UNNAMED_14_LED4PV14_I266_3")
	)
	(segment
		(start 17.272 -30.226)
		(end 17.399 -30.226)
		(width 0.11938)
		(layer "F.Cu")
		(net "UNNAMED_14_LED4PV14_I266_3")
	)
	(via
		(at 17.272 -30.226)
		(size 0.508)
		(drill 0.254)
		(layers "F.Cu" "B.Cu")
		(net "UNNAMED_14_LED4PV14_I266_3")
	)
	(via
		(at 3.175 -25.654)
		(size 0.508)
		(drill 0.254)
		(layers "F.Cu" "B.Cu")
		(net "UNNAMED_14_LED4PV14_I266_3")
	)
	(segment
		(start 13.823696 -29.337)
		(end 10.922 -29.337)
		(width 0.11938)
		(layer "B.Cu")
		(net "UNNAMED_14_LED4PV14_I266_3")
	)
	(segment
		(start 17.272 -30.226)
		(end 17.185894 -30.226)
		(width 0.11938)
		(layer "B.Cu")
		(net "UNNAMED_14_LED4PV14_I266_3")
	)
	(segment
		(start 7.239 -25.654)
		(end 3.175 -25.654)
		(width 0.11938)
		(layer "B.Cu")
		(net "UNNAMED_14_LED4PV14_I266_3")
	)
	(segment
		(start 16.042894 -29.083)
		(end 15.132304 -29.083)
		(width 0.11938)
		(layer "B.Cu")
		(net "UNNAMED_14_LED4PV14_I266_3")
	)
	(segment
		(start 15.132304 -29.083)
		(end 14.691614 -29.52369)
		(width 0.11938)
		(layer "B.Cu")
		(net "UNNAMED_14_LED4PV14_I266_3")
	)
	(segment
		(start 14.010386 -29.52369)
		(end 13.823696 -29.337)
		(width 0.11938)
		(layer "B.Cu")
		(net "UNNAMED_14_LED4PV14_I266_3")
	)
	(segment
		(start 14.691614 -29.52369)
		(end 14.010386 -29.52369)
		(width 0.11938)
		(layer "B.Cu")
		(net "UNNAMED_14_LED4PV14_I266_3")
	)
	(segment
		(start 17.185894 -30.226)
		(end 16.042894 -29.083)
		(width 0.11938)
		(layer "B.Cu")
		(net "UNNAMED_14_LED4PV14_I266_3")
	)
	(segment
		(start 10.922 -29.337)
		(end 7.239 -25.654)
		(width 0.11938)
		(layer "B.Cu")
		(net "UNNAMED_14_LED4PV14_I266_3")
	)
	(segment
		(start 3.175 -23.114)
		(end 3.048 -23.114)
		(width 0.11938)
		(layer "F.Cu")
		(net "UNNAMED_14_LED4PV14_I266_1")
	)
	(segment
		(start 3.048 -23.114)
		(end 2.887218 -23.274782)
		(width 0.11938)
		(layer "F.Cu")
		(net "UNNAMED_14_LED4PV14_I266_1")
	)
	(segment
		(start 19.7866 -27.94)
		(end 19.7866 -26.67)
		(width 0.11938)
		(layer "F.Cu")
		(net "UNNAMED_14_LED4PV14_I266_1")
	)
	(segment
		(start 18.288 -27.94)
		(end 19.7866 -27.94)
		(width 0.11938)
		(layer "F.Cu")
		(net "UNNAMED_14_LED4PV14_I266_1")
	)
	(segment
		(start 17.145 -29.083)
		(end 18.288 -27.94)
		(width 0.11938)
		(layer "F.Cu")
		(net "UNNAMED_14_LED4PV14_I266_1")
	)
	(segment
		(start 2.887218 -23.274782)
		(end 1.745996 -23.274782)
		(width 0.11938)
		(layer "F.Cu")
		(net "UNNAMED_14_LED4PV14_I266_1")
	)
	(via
		(at 17.145 -29.083)
		(size 0.508)
		(drill 0.254)
		(layers "F.Cu" "B.Cu")
		(net "UNNAMED_14_LED4PV14_I266_1")
	)
	(via
		(at 3.175 -23.114)
		(size 0.508)
		(drill 0.254)
		(layers "F.Cu" "B.Cu")
		(net "UNNAMED_14_LED4PV14_I266_1")
	)
	(segment
		(start 4.191 -24.003)
		(end 7.493 -24.003)
		(width 0.11938)
		(layer "B.Cu")
		(net "UNNAMED_14_LED4PV14_I266_1")
	)
	(segment
		(start 15.520924 -28.70962)
		(end 16.19758 -28.70962)
		(width 0.11938)
		(layer "B.Cu")
		(net "UNNAMED_14_LED4PV14_I266_1")
	)
	(segment
		(start 16.19758 -28.70962)
		(end 16.57096 -29.083)
		(width 0.11938)
		(layer "B.Cu")
		(net "UNNAMED_14_LED4PV14_I266_1")
	)
	(segment
		(start 3.175 -23.114)
		(end 3.302 -23.114)
		(width 0.11938)
		(layer "B.Cu")
		(net "UNNAMED_14_LED4PV14_I266_1")
	)
	(segment
		(start 16.57096 -29.083)
		(end 17.145 -29.083)
		(width 0.11938)
		(layer "B.Cu")
		(net "UNNAMED_14_LED4PV14_I266_1")
	)
	(segment
		(start 14.497304 -27.686)
		(end 15.520924 -28.70962)
		(width 0.11938)
		(layer "B.Cu")
		(net "UNNAMED_14_LED4PV14_I266_1")
	)
	(segment
		(start 7.493 -24.003)
		(end 11.176 -27.686)
		(width 0.11938)
		(layer "B.Cu")
		(net "UNNAMED_14_LED4PV14_I266_1")
	)
	(segment
		(start 3.302 -23.114)
		(end 4.191 -24.003)
		(width 0.11938)
		(layer "B.Cu")
		(net "UNNAMED_14_LED4PV14_I266_1")
	)
	(segment
		(start 11.176 -27.686)
		(end 14.497304 -27.686)
		(width 0.11938)
		(layer "B.Cu")
		(net "UNNAMED_14_LED4PV14_I266_1")
	)
	(segment
		(start 9.4234 -39.852092)
		(end 8.127492 -41.148)
		(width 0.11938)
		(layer "F.Cu")
		(net "UNNAMED_14_LED4PV14_I265_4")
	)
	(segment
		(start 2.452116 -40.425116)
		(end 1.745996 -40.425116)
		(width 0.11938)
		(layer "F.Cu")
		(net "UNNAMED_14_LED4PV14_I265_4")
	)
	(segment
		(start 8.127492 -41.148)
		(end 3.175 -41.148)
		(width 0.11938)
		(layer "F.Cu")
		(net "UNNAMED_14_LED4PV14_I265_4")
	)
	(segment
		(start 9.4234 -39.852092)
		(end 10.5664 -39.852092)
		(width 0.11938)
		(layer "F.Cu")
		(net "UNNAMED_14_LED4PV14_I265_4")
	)
	(segment
		(start 3.175 -41.148)
		(end 2.452116 -40.425116)
		(width 0.11938)
		(layer "F.Cu")
		(net "UNNAMED_14_LED4PV14_I265_4")
	)
	(via
		(at 3.175 -41.148)
		(size 0.508)
		(drill 0.254)
		(layers "F.Cu" "B.Cu")
		(net "UNNAMED_14_LED4PV14_I265_4")
	)
	(segment
		(start 2.94894 -39.52494)
		(end 3.302 -39.878)
		(width 0.11938)
		(layer "F.Cu")
		(net "UNNAMED_14_LED4PV14_I265_3")
	)
	(segment
		(start 7.1374 -39.852092)
		(end 8.2804 -39.852092)
		(width 0.11938)
		(layer "F.Cu")
		(net "UNNAMED_14_LED4PV14_I265_3")
	)
	(segment
		(start 6.222492 -40.767)
		(end 7.1374 -39.852092)
		(width 0.11938)
		(layer "F.Cu")
		(net "UNNAMED_14_LED4PV14_I265_3")
	)
	(segment
		(start 4.191 -40.767)
		(end 6.222492 -40.767)
		(width 0.11938)
		(layer "F.Cu")
		(net "UNNAMED_14_LED4PV14_I265_3")
	)
	(segment
		(start 2.096008 -39.52494)
		(end 2.94894 -39.52494)
		(width 0.11938)
		(layer "F.Cu")
		(net "UNNAMED_14_LED4PV14_I265_3")
	)
	(segment
		(start 3.302 -39.878)
		(end 4.191 -40.767)
		(width 0.11938)
		(layer "F.Cu")
		(net "UNNAMED_14_LED4PV14_I265_3")
	)
	(via
		(at 3.302 -39.878)
		(size 0.508)
		(drill 0.254)
		(layers "F.Cu" "B.Cu")
		(net "UNNAMED_14_LED4PV14_I265_3")
	)
	(segment
		(start 1.745996 -37.77488)
		(end 3.45948 -37.77488)
		(width 0.11938)
		(layer "F.Cu")
		(net "UNNAMED_14_LED4PV14_I265_1")
	)
	(segment
		(start 4.232656 -39.852092)
		(end 4.8514 -39.852092)
		(width 0.11938)
		(layer "F.Cu")
		(net "UNNAMED_14_LED4PV14_I265_1")
	)
	(segment
		(start 3.45948 -37.77488)
		(end 3.531362 -37.846762)
		(width 0.11938)
		(layer "F.Cu")
		(net "UNNAMED_14_LED4PV14_I265_1")
	)
	(segment
		(start 4.8514 -39.852092)
		(end 5.9944 -39.852092)
		(width 0.11938)
		(layer "F.Cu")
		(net "UNNAMED_14_LED4PV14_I265_1")
	)
	(segment
		(start 3.531362 -39.150798)
		(end 4.232656 -39.852092)
		(width 0.11938)
		(layer "F.Cu")
		(net "UNNAMED_14_LED4PV14_I265_1")
	)
	(segment
		(start 3.531362 -37.846762)
		(end 3.531362 -39.150798)
		(width 0.11938)
		(layer "F.Cu")
		(net "UNNAMED_14_LED4PV14_I265_1")
	)
	(via
		(at 3.45948 -37.77488)
		(size 0.508)
		(drill 0.254)
		(layers "F.Cu" "B.Cu")
		(net "UNNAMED_14_LED4PV14_I265_1")
	)
	(segment
		(start 74.5998 -81.4324)
		(end 74.5998 -80.5942)
		(width 0.3048)
		(layer "F.Cu")
		(net "VDD_PCA9546A")
	)
	(segment
		(start 74.5998 -81.4324)
		(end 76.785978 -81.4324)
		(width 0.3048)
		(layer "F.Cu")
		(net "VDD_PCA9546A")
	)
	(segment
		(start 76.785978 -81.4324)
		(end 77.2795 -81.925922)
		(width 0.3048)
		(layer "F.Cu")
		(net "VDD_PCA9546A")
	)
	(via
		(at 74.5998 -80.5942)
		(size 0.508)
		(drill 0.254)
		(layers "F.Cu" "B.Cu")
		(net "VDD_PCA9546A")
	)
	(via
		(at 76.454 -80.518)
		(size 0.508)
		(drill 0.254)
		(layers "F.Cu" "B.Cu")
		(net "VDD_PCA9546A")
	)
	(segment
		(start 76.454 -80.518)
		(end 76.8604 -80.9244)
		(width 0.3048)
		(layer "B.Cu")
		(net "VDD_PCA9546A")
	)
	(segment
		(start 76.8604 -80.9244)
		(end 76.8604 -81.534)
		(width 0.3048)
		(layer "B.Cu")
		(net "VDD_PCA9546A")
	)
	(segment
		(start 76.8604 -82.804)
		(end 76.8604 -81.534)
		(width 0.3048)
		(layer "B.Cu")
		(net "VDD_PCA9546A")
	)
	(segment
		(start 76.454 -80.518)
		(end 74.676 -80.518)
		(width 0.381)
		(layer "In7.Cu")
		(net "VDD_PCA9546A")
	)
	(segment
		(start 74.676 -80.518)
		(end 74.5998 -80.5942)
		(width 0.381)
		(layer "In7.Cu")
		(net "VDD_PCA9546A")
	)
	(segment
		(start 22.7584 -63.2206)
		(end 21.82876 -62.29096)
		(width 0.11938)
		(layer "F.Cu")
		(net "UNNAMED_8_PCA9508DPTSSOP8_I51_E")
	)
	(segment
		(start 21.82876 -62.29096)
		(end 21.82876 -61.6585)
		(width 0.11938)
		(layer "F.Cu")
		(net "UNNAMED_8_PCA9508DPTSSOP8_I51_E")
	)
	(via
		(at 22.7584 -63.2206)
		(size 0.4572)
		(drill 0.2032)
		(layers "F.Cu" "B.Cu")
		(net "UNNAMED_8_PCA9508DPTSSOP8_I51_E")
	)
	(segment
		(start 22.7584 -62.0776)
		(end 22.7584 -63.2206)
		(width 0.11938)
		(layer "B.Cu")
		(net "UNNAMED_8_PCA9508DPTSSOP8_I51_E")
	)
	(segment
		(start 109.516926 -101.896926)
		(end 107.67314 -101.896926)
		(width 0.11938)
		(layer "F.Cu")
		(net "UNNAMED_14_IS32FL3207QWLA3TRQ_1")
	)
	(segment
		(start 110.5916 -101.981)
		(end 109.601 -101.981)
		(width 0.11938)
		(layer "F.Cu")
		(net "UNNAMED_14_IS32FL3207QWLA3TRQ_1")
	)
	(segment
		(start 109.601 -101.981)
		(end 109.516926 -101.896926)
		(width 0.11938)
		(layer "F.Cu")
		(net "UNNAMED_14_IS32FL3207QWLA3TRQ_1")
	)
	(via
		(at 109.516926 -101.896926)
		(size 0.4572)
		(drill 0.2032)
		(layers "F.Cu" "B.Cu")
		(net "UNNAMED_14_IS32FL3207QWLA3TRQ_1")
	)
	(segment
		(start 108.924598 -100.396802)
		(end 109.7026 -99.6188)
		(width 0.11938)
		(layer "F.Cu")
		(net "UNNAMED_14_IS32FL3207QWLA3TRQFN")
	)
	(segment
		(start 109.8804 -99.441)
		(end 110.5916 -99.441)
		(width 0.11938)
		(layer "F.Cu")
		(net "UNNAMED_14_IS32FL3207QWLA3TRQFN")
	)
	(segment
		(start 107.67314 -100.396802)
		(end 108.924598 -100.396802)
		(width 0.11938)
		(layer "F.Cu")
		(net "UNNAMED_14_IS32FL3207QWLA3TRQFN")
	)
	(segment
		(start 109.7026 -99.6188)
		(end 109.8804 -99.441)
		(width 0.11938)
		(layer "F.Cu")
		(net "UNNAMED_14_IS32FL3207QWLA3TRQFN")
	)
	(via
		(at 109.7026 -99.6188)
		(size 0.4572)
		(drill 0.2032)
		(layers "F.Cu" "B.Cu")
		(net "UNNAMED_14_IS32FL3207QWLA3TRQFN")
	)
	(segment
		(start 114.3 -104.521)
		(end 113.665 -104.521)
		(width 0.11938)
		(layer "F.Cu")
		(net "RGB_LED_I2C_SDA")
	)
	(segment
		(start 112.395 -103.886)
		(end 111.76 -103.251)
		(width 0.11938)
		(layer "F.Cu")
		(net "RGB_LED_I2C_SDA")
	)
	(segment
		(start 113.03 -103.886)
		(end 112.395 -103.886)
		(width 0.11938)
		(layer "F.Cu")
		(net "RGB_LED_I2C_SDA")
	)
	(segment
		(start 35.11931 -16.7132)
		(end 34.3027 -16.7132)
		(width 0.11938)
		(layer "F.Cu")
		(net "RGB_LED_I2C_SDA")
	)
	(segment
		(start 74.1934 -83.693)
		(end 73.533 -83.0326)
		(width 0.11938)
		(layer "F.Cu")
		(net "RGB_LED_I2C_SDA")
	)
	(segment
		(start 113.665 -104.521)
		(end 113.03 -103.886)
		(width 0.11938)
		(layer "F.Cu")
		(net "RGB_LED_I2C_SDA")
	)
	(segment
		(start 36.068 -17.66189)
		(end 35.11931 -16.7132)
		(width 0.11938)
		(layer "F.Cu")
		(net "RGB_LED_I2C_SDA")
	)
	(segment
		(start 74.4728 -83.693)
		(end 74.1934 -83.693)
		(width 0.11938)
		(layer "F.Cu")
		(net "RGB_LED_I2C_SDA")
	)
	(segment
		(start 73.533 -83.0326)
		(end 73.533 -82.7786)
		(width 0.11938)
		(layer "F.Cu")
		(net "RGB_LED_I2C_SDA")
	)
	(segment
		(start 111.76 -103.251)
		(end 111.6584 -103.251)
		(width 0.11938)
		(layer "F.Cu")
		(net "RGB_LED_I2C_SDA")
	)
	(via
		(at 23.241 -35.56)
		(size 0.508)
		(drill 0.254)
		(layers "F.Cu" "B.Cu")
		(net "RGB_LED_I2C_SDA")
	)
	(via
		(at 114.3 -104.521)
		(size 0.508)
		(drill 0.254)
		(layers "F.Cu" "B.Cu")
		(net "RGB_LED_I2C_SDA")
	)
	(via
		(at 36.068 -17.66189)
		(size 0.4572)
		(drill 0.2032)
		(layers "F.Cu" "B.Cu")
		(net "RGB_LED_I2C_SDA")
	)
	(via
		(at 33.401 -73.787)
		(size 0.4572)
		(drill 0.2032)
		(layers "F.Cu" "B.Cu")
		(net "RGB_LED_I2C_SDA")
	)
	(via
		(at 74.4728 -83.693)
		(size 0.4572)
		(drill 0.2032)
		(layers "F.Cu" "B.Cu")
		(net "RGB_LED_I2C_SDA")
	)
	(segment
		(start 56.255158 -71.43242)
		(end 58.35142 -73.528682)
		(width 0.11938)
		(layer "B.Cu")
		(net "RGB_LED_I2C_SDA")
	)
	(segment
		(start 58.35142 -73.528682)
		(end 58.35142 -83.652614)
		(width 0.11938)
		(layer "B.Cu")
		(net "RGB_LED_I2C_SDA")
	)
	(segment
		(start 95.504 -99.200462)
		(end 99.935538 -103.632)
		(width 0.11938)
		(layer "B.Cu")
		(net "RGB_LED_I2C_SDA")
	)
	(segment
		(start 82.294476 -89.46642)
		(end 90.86342 -89.46642)
		(width 0.11938)
		(layer "B.Cu")
		(net "RGB_LED_I2C_SDA")
	)
	(segment
		(start 75.438 -87.63)
		(end 80.458056 -87.63)
		(width 0.11938)
		(layer "B.Cu")
		(net "RGB_LED_I2C_SDA")
	)
	(segment
		(start 74.1934 -83.9724)
		(end 74.1934 -86.3854)
		(width 0.11938)
		(layer "B.Cu")
		(net "RGB_LED_I2C_SDA")
	)
	(segment
		(start 90.86342 -89.46642)
		(end 95.504 -94.107)
		(width 0.11938)
		(layer "B.Cu")
		(net "RGB_LED_I2C_SDA")
	)
	(segment
		(start 40.750236 -72.63384)
		(end 41.951656 -71.43242)
		(width 0.11938)
		(layer "B.Cu")
		(net "RGB_LED_I2C_SDA")
	)
	(segment
		(start 74.09942 -82.423)
		(end 74.2188 -82.54238)
		(width 0.11938)
		(layer "B.Cu")
		(net "RGB_LED_I2C_SDA")
	)
	(segment
		(start 33.401 -73.279)
		(end 34.04616 -72.63384)
		(width 0.11938)
		(layer "B.Cu")
		(net "RGB_LED_I2C_SDA")
	)
	(segment
		(start 41.951656 -71.43242)
		(end 56.255158 -71.43242)
		(width 0.11938)
		(layer "B.Cu")
		(net "RGB_LED_I2C_SDA")
	)
	(segment
		(start 58.35142 -83.652614)
		(end 60.385706 -85.6869)
		(width 0.11938)
		(layer "B.Cu")
		(net "RGB_LED_I2C_SDA")
	)
	(segment
		(start 95.504 -94.107)
		(end 95.504 -99.200462)
		(width 0.11938)
		(layer "B.Cu")
		(net "RGB_LED_I2C_SDA")
	)
	(segment
		(start 113.31829 -105.50271)
		(end 114.3 -104.521)
		(width 0.11938)
		(layer "B.Cu")
		(net "RGB_LED_I2C_SDA")
	)
	(segment
		(start 60.385706 -85.6869)
		(end 67.600068 -85.6869)
		(width 0.11938)
		(layer "B.Cu")
		(net "RGB_LED_I2C_SDA")
	)
	(segment
		(start 74.4728 -83.693)
		(end 74.1934 -83.9724)
		(width 0.11938)
		(layer "B.Cu")
		(net "RGB_LED_I2C_SDA")
	)
	(segment
		(start 33.401 -73.787)
		(end 33.401 -73.279)
		(width 0.11938)
		(layer "B.Cu")
		(net "RGB_LED_I2C_SDA")
	)
	(segment
		(start 74.2188 -83.439)
		(end 74.4728 -83.693)
		(width 0.11938)
		(layer "B.Cu")
		(net "RGB_LED_I2C_SDA")
	)
	(segment
		(start 74.1934 -86.3854)
		(end 75.438 -87.63)
		(width 0.11938)
		(layer "B.Cu")
		(net "RGB_LED_I2C_SDA")
	)
	(segment
		(start 34.04616 -72.63384)
		(end 40.750236 -72.63384)
		(width 0.11938)
		(layer "B.Cu")
		(net "RGB_LED_I2C_SDA")
	)
	(segment
		(start 113.31829 -106.01579)
		(end 113.31829 -105.50271)
		(width 0.11938)
		(layer "B.Cu")
		(net "RGB_LED_I2C_SDA")
	)
	(segment
		(start 67.600068 -85.6869)
		(end 70.863968 -82.423)
		(width 0.11938)
		(layer "B.Cu")
		(net "RGB_LED_I2C_SDA")
	)
	(segment
		(start 74.2188 -82.54238)
		(end 74.2188 -83.439)
		(width 0.11938)
		(layer "B.Cu")
		(net "RGB_LED_I2C_SDA")
	)
	(segment
		(start 80.458056 -87.63)
		(end 82.294476 -89.46642)
		(width 0.11938)
		(layer "B.Cu")
		(net "RGB_LED_I2C_SDA")
	)
	(segment
		(start 112.90808 -106.426)
		(end 113.31829 -106.01579)
		(width 0.11938)
		(layer "B.Cu")
		(net "RGB_LED_I2C_SDA")
	)
	(segment
		(start 104.14 -103.632)
		(end 106.934 -106.426)
		(width 0.11938)
		(layer "B.Cu")
		(net "RGB_LED_I2C_SDA")
	)
	(segment
		(start 106.934 -106.426)
		(end 112.90808 -106.426)
		(width 0.11938)
		(layer "B.Cu")
		(net "RGB_LED_I2C_SDA")
	)
	(segment
		(start 70.863968 -82.423)
		(end 74.09942 -82.423)
		(width 0.11938)
		(layer "B.Cu")
		(net "RGB_LED_I2C_SDA")
	)
	(segment
		(start 99.935538 -103.632)
		(end 104.14 -103.632)
		(width 0.11938)
		(layer "B.Cu")
		(net "RGB_LED_I2C_SDA")
	)
	(segment
		(start 24.511 -36.195)
		(end 23.876 -36.195)
		(width 0.127)
		(layer "In2.Cu")
		(net "RGB_LED_I2C_SDA")
	)
	(segment
		(start 28.321 -68.707)
		(end 28.321 -40.442388)
		(width 0.127)
		(layer "In2.Cu")
		(net "RGB_LED_I2C_SDA")
	)
	(segment
		(start 33.401 -73.787)
		(end 28.321 -68.707)
		(width 0.127)
		(layer "In2.Cu")
		(net "RGB_LED_I2C_SDA")
	)
	(segment
		(start 23.876 -36.195)
		(end 23.241 -35.56)
		(width 0.127)
		(layer "In2.Cu")
		(net "RGB_LED_I2C_SDA")
	)
	(segment
		(start 25.146 -36.83)
		(end 24.511 -36.195)
		(width 0.127)
		(layer "In2.Cu")
		(net "RGB_LED_I2C_SDA")
	)
	(segment
		(start 28.321 -40.442388)
		(end 25.146 -37.267388)
		(width 0.127)
		(layer "In2.Cu")
		(net "RGB_LED_I2C_SDA")
	)
	(segment
		(start 25.146 -37.267388)
		(end 25.146 -36.83)
		(width 0.127)
		(layer "In2.Cu")
		(net "RGB_LED_I2C_SDA")
	)
	(segment
		(start 35.22599 -18.5039)
		(end 34.201354 -18.5039)
		(width 0.127)
		(layer "In7.Cu")
		(net "RGB_LED_I2C_SDA")
	)
	(segment
		(start 26.035 -23.92426)
		(end 26.035 -32.004)
		(width 0.127)
		(layer "In7.Cu")
		(net "RGB_LED_I2C_SDA")
	)
	(segment
		(start 29.89326 -20.066)
		(end 26.035 -23.92426)
		(width 0.127)
		(layer "In7.Cu")
		(net "RGB_LED_I2C_SDA")
	)
	(segment
		(start 32.639254 -20.066)
		(end 29.89326 -20.066)
		(width 0.127)
		(layer "In7.Cu")
		(net "RGB_LED_I2C_SDA")
	)
	(segment
		(start 36.068 -17.66189)
		(end 35.22599 -18.5039)
		(width 0.127)
		(layer "In7.Cu")
		(net "RGB_LED_I2C_SDA")
	)
	(segment
		(start 23.241 -34.798)
		(end 23.241 -35.56)
		(width 0.127)
		(layer "In7.Cu")
		(net "RGB_LED_I2C_SDA")
	)
	(segment
		(start 34.201354 -18.5039)
		(end 32.639254 -20.066)
		(width 0.127)
		(layer "In7.Cu")
		(net "RGB_LED_I2C_SDA")
	)
	(segment
		(start 26.035 -32.004)
		(end 23.241 -34.798)
		(width 0.127)
		(layer "In7.Cu")
		(net "RGB_LED_I2C_SDA")
	)
	(segment
		(start 73.5584 -83.8454)
		(end 73.5584 -84.6328)
		(width 0.11938)
		(layer "F.Cu")
		(net "RGB_LED_I2C_SCL")
	)
	(segment
		(start 114.3 -105.791)
		(end 113.665 -105.156)
		(width 0.11938)
		(layer "F.Cu")
		(net "RGB_LED_I2C_SCL")
	)
	(segment
		(start 34.96818 -19.7866)
		(end 34.30778 -19.1262)
		(width 0.11938)
		(layer "F.Cu")
		(net "RGB_LED_I2C_SCL")
	)
	(segment
		(start 36.08578 -19.7866)
		(end 34.96818 -19.7866)
		(width 0.11938)
		(layer "F.Cu")
		(net "RGB_LED_I2C_SCL")
	)
	(segment
		(start 113.665 -105.156)
		(end 112.2934 -105.156)
		(width 0.11938)
		(layer "F.Cu")
		(net "RGB_LED_I2C_SCL")
	)
	(segment
		(start 112.2934 -105.156)
		(end 111.6584 -104.521)
		(width 0.11938)
		(layer "F.Cu")
		(net "RGB_LED_I2C_SCL")
	)
	(via
		(at 34.544 -73.787)
		(size 0.4572)
		(drill 0.2032)
		(layers "F.Cu" "B.Cu")
		(net "RGB_LED_I2C_SCL")
	)
	(via
		(at 36.08578 -19.7866)
		(size 0.4572)
		(drill 0.2032)
		(layers "F.Cu" "B.Cu")
		(net "RGB_LED_I2C_SCL")
	)
	(via
		(at 73.5584 -83.8454)
		(size 0.4572)
		(drill 0.2032)
		(layers "F.Cu" "B.Cu")
		(net "RGB_LED_I2C_SCL")
	)
	(via
		(at 114.3 -105.791)
		(size 0.508)
		(drill 0.254)
		(layers "F.Cu" "B.Cu")
		(net "RGB_LED_I2C_SCL")
	)
	(via
		(at 24.511 -35.56)
		(size 0.508)
		(drill 0.254)
		(layers "F.Cu" "B.Cu")
		(net "RGB_LED_I2C_SCL")
	)
	(segment
		(start 40.932354 -73.07326)
		(end 42.123614 -71.882)
		(width 0.11938)
		(layer "B.Cu")
		(net "RGB_LED_I2C_SCL")
	)
	(segment
		(start 90.54084 -89.90584)
		(end 82.112358 -89.90584)
		(width 0.11938)
		(layer "B.Cu")
		(net "RGB_LED_I2C_SCL")
	)
	(segment
		(start 68.686426 -85.390736)
		(end 69.007736 -85.7123)
		(width 0.11938)
		(layer "B.Cu")
		(net "RGB_LED_I2C_SCL")
	)
	(segment
		(start 99.949 -104.267)
		(end 95.05442 -99.37242)
		(width 0.11938)
		(layer "B.Cu")
		(net "RGB_LED_I2C_SCL")
	)
	(segment
		(start 104.013 -104.267)
		(end 99.949 -104.267)
		(width 0.11938)
		(layer "B.Cu")
		(net "RGB_LED_I2C_SCL")
	)
	(segment
		(start 68.51777 -85.390736)
		(end 68.686426 -85.390736)
		(width 0.11938)
		(layer "B.Cu")
		(net "RGB_LED_I2C_SCL")
	)
	(segment
		(start 70.977506 -82.931)
		(end 73.61682 -82.931)
		(width 0.11938)
		(layer "B.Cu")
		(net "RGB_LED_I2C_SCL")
	)
	(segment
		(start 70.01764 -84.059776)
		(end 70.01764 -83.890866)
		(width 0.11938)
		(layer "B.Cu")
		(net "RGB_LED_I2C_SCL")
	)
	(segment
		(start 55.96382 -71.882)
		(end 57.912 -73.83018)
		(width 0.11938)
		(layer "B.Cu")
		(net "RGB_LED_I2C_SCL")
	)
	(segment
		(start 35.25774 -73.07326)
		(end 40.932354 -73.07326)
		(width 0.11938)
		(layer "B.Cu")
		(net "RGB_LED_I2C_SCL")
	)
	(segment
		(start 69.451474 -85.268562)
		(end 69.130164 -84.946998)
		(width 0.11938)
		(layer "B.Cu")
		(net "RGB_LED_I2C_SCL")
	)
	(segment
		(start 69.573648 -84.50326)
		(end 69.806566 -84.736178)
		(width 0.11938)
		(layer "B.Cu")
		(net "RGB_LED_I2C_SCL")
	)
	(segment
		(start 69.975222 -84.736178)
		(end 70.250304 -84.461096)
		(width 0.11938)
		(layer "B.Cu")
		(net "RGB_LED_I2C_SCL")
	)
	(segment
		(start 69.176392 -85.7123)
		(end 69.451474 -85.437218)
		(width 0.11938)
		(layer "B.Cu")
		(net "RGB_LED_I2C_SCL")
	)
	(segment
		(start 106.68 -106.934)
		(end 104.013 -104.267)
		(width 0.11938)
		(layer "B.Cu")
		(net "RGB_LED_I2C_SCL")
	)
	(segment
		(start 70.01764 -83.890866)
		(end 70.977506 -82.931)
		(width 0.11938)
		(layer "B.Cu")
		(net "RGB_LED_I2C_SCL")
	)
	(segment
		(start 73.75398 -84.04098)
		(end 73.5584 -83.8454)
		(width 0.11938)
		(layer "B.Cu")
		(net "RGB_LED_I2C_SCL")
	)
	(segment
		(start 69.451474 -85.437218)
		(end 69.451474 -85.268562)
		(width 0.11938)
		(layer "B.Cu")
		(net "RGB_LED_I2C_SCL")
	)
	(segment
		(start 114.3 -105.791)
		(end 113.157 -106.934)
		(width 0.11938)
		(layer "B.Cu")
		(net "RGB_LED_I2C_SCL")
	)
	(segment
		(start 95.05442 -94.41942)
		(end 90.54084 -89.90584)
		(width 0.11938)
		(layer "B.Cu")
		(net "RGB_LED_I2C_SCL")
	)
	(segment
		(start 75.255882 -88.06942)
		(end 73.75398 -86.567518)
		(width 0.11938)
		(layer "B.Cu")
		(net "RGB_LED_I2C_SCL")
	)
	(segment
		(start 57.912 -73.83018)
		(end 57.912 -83.985608)
		(width 0.11938)
		(layer "B.Cu")
		(net "RGB_LED_I2C_SCL")
	)
	(segment
		(start 42.123614 -71.882)
		(end 55.96382 -71.882)
		(width 0.11938)
		(layer "B.Cu")
		(net "RGB_LED_I2C_SCL")
	)
	(segment
		(start 73.7362 -83.05038)
		(end 73.7362 -83.6676)
		(width 0.11938)
		(layer "B.Cu")
		(net "RGB_LED_I2C_SCL")
	)
	(segment
		(start 95.05442 -99.37242)
		(end 95.05442 -94.41942)
		(width 0.11938)
		(layer "B.Cu")
		(net "RGB_LED_I2C_SCL")
	)
	(segment
		(start 69.405246 -84.50326)
		(end 69.573648 -84.50326)
		(width 0.11938)
		(layer "B.Cu")
		(net "RGB_LED_I2C_SCL")
	)
	(segment
		(start 69.806566 -84.736178)
		(end 69.975222 -84.736178)
		(width 0.11938)
		(layer "B.Cu")
		(net "RGB_LED_I2C_SCL")
	)
	(segment
		(start 69.007736 -85.7123)
		(end 69.176392 -85.7123)
		(width 0.11938)
		(layer "B.Cu")
		(net "RGB_LED_I2C_SCL")
	)
	(segment
		(start 113.157 -106.934)
		(end 106.68 -106.934)
		(width 0.11938)
		(layer "B.Cu")
		(net "RGB_LED_I2C_SCL")
	)
	(segment
		(start 73.75398 -86.567518)
		(end 73.75398 -84.04098)
		(width 0.11938)
		(layer "B.Cu")
		(net "RGB_LED_I2C_SCL")
	)
	(segment
		(start 69.130164 -84.778342)
		(end 69.405246 -84.50326)
		(width 0.11938)
		(layer "B.Cu")
		(net "RGB_LED_I2C_SCL")
	)
	(segment
		(start 73.61682 -82.931)
		(end 73.7362 -83.05038)
		(width 0.11938)
		(layer "B.Cu")
		(net "RGB_LED_I2C_SCL")
	)
	(segment
		(start 69.130164 -84.946998)
		(end 69.130164 -84.778342)
		(width 0.11938)
		(layer "B.Cu")
		(net "RGB_LED_I2C_SCL")
	)
	(segment
		(start 60.159392 -86.233)
		(end 67.675506 -86.233)
		(width 0.11938)
		(layer "B.Cu")
		(net "RGB_LED_I2C_SCL")
	)
	(segment
		(start 80.275938 -88.06942)
		(end 75.255882 -88.06942)
		(width 0.11938)
		(layer "B.Cu")
		(net "RGB_LED_I2C_SCL")
	)
	(segment
		(start 34.544 -73.787)
		(end 35.25774 -73.07326)
		(width 0.11938)
		(layer "B.Cu")
		(net "RGB_LED_I2C_SCL")
	)
	(segment
		(start 70.250304 -84.29244)
		(end 70.01764 -84.059776)
		(width 0.11938)
		(layer "B.Cu")
		(net "RGB_LED_I2C_SCL")
	)
	(segment
		(start 57.912 -83.985608)
		(end 60.159392 -86.233)
		(width 0.11938)
		(layer "B.Cu")
		(net "RGB_LED_I2C_SCL")
	)
	(segment
		(start 73.7362 -83.6676)
		(end 73.5584 -83.8454)
		(width 0.11938)
		(layer "B.Cu")
		(net "RGB_LED_I2C_SCL")
	)
	(segment
		(start 70.250304 -84.461096)
		(end 70.250304 -84.29244)
		(width 0.11938)
		(layer "B.Cu")
		(net "RGB_LED_I2C_SCL")
	)
	(segment
		(start 82.112358 -89.90584)
		(end 80.275938 -88.06942)
		(width 0.11938)
		(layer "B.Cu")
		(net "RGB_LED_I2C_SCL")
	)
	(segment
		(start 67.675506 -86.233)
		(end 68.51777 -85.390736)
		(width 0.11938)
		(layer "B.Cu")
		(net "RGB_LED_I2C_SCL")
	)
	(segment
		(start 24.638 -35.56)
		(end 25.794462 -36.716462)
		(width 0.127)
		(layer "In2.Cu")
		(net "RGB_LED_I2C_SCL")
	)
	(segment
		(start 24.511 -35.56)
		(end 24.638 -35.56)
		(width 0.127)
		(layer "In2.Cu")
		(net "RGB_LED_I2C_SCL")
	)
	(segment
		(start 33.528 -72.771)
		(end 34.544 -73.787)
		(width 0.127)
		(layer "In2.Cu")
		(net "RGB_LED_I2C_SCL")
	)
	(segment
		(start 25.794462 -37.197284)
		(end 28.829 -40.231822)
		(width 0.127)
		(layer "In2.Cu")
		(net "RGB_LED_I2C_SCL")
	)
	(segment
		(start 28.829 -40.231822)
		(end 28.829 -68.453)
		(width 0.127)
		(layer "In2.Cu")
		(net "RGB_LED_I2C_SCL")
	)
	(segment
		(start 25.794462 -36.716462)
		(end 25.794462 -37.197284)
		(width 0.127)
		(layer "In2.Cu")
		(net "RGB_LED_I2C_SCL")
	)
	(segment
		(start 33.147 -72.771)
		(end 33.528 -72.771)
		(width 0.127)
		(layer "In2.Cu")
		(net "RGB_LED_I2C_SCL")
	)
	(segment
		(start 28.829 -68.453)
		(end 33.147 -72.771)
		(width 0.127)
		(layer "In2.Cu")
		(net "RGB_LED_I2C_SCL")
	)
	(segment
		(start 29.26969 -21.77923)
		(end 29.449522 -21.77923)
		(width 0.127)
		(layer "In7.Cu")
		(net "RGB_LED_I2C_SCL")
	)
	(segment
		(start 26.67 -32.258)
		(end 26.67 -25.4)
		(width 0.127)
		(layer "In7.Cu")
		(net "RGB_LED_I2C_SCL")
	)
	(segment
		(start 29.960062 -22.109938)
		(end 30.229302 -21.840698)
		(width 0.127)
		(layer "In7.Cu")
		(net "RGB_LED_I2C_SCL")
	)
	(segment
		(start 29.00045 -22.228302)
		(end 29.00045 -22.04847)
		(width 0.127)
		(layer "In7.Cu")
		(net "RGB_LED_I2C_SCL")
	)
	(segment
		(start 27.983942 -23.906226)
		(end 28.163774 -23.906226)
		(width 0.127)
		(layer "In7.Cu")
		(net "RGB_LED_I2C_SCL")
	)
	(segment
		(start 29.061918 -23.008082)
		(end 29.331158 -22.738842)
		(width 0.127)
		(layer "In7.Cu")
		(net "RGB_LED_I2C_SCL")
	)
	(segment
		(start 35.17138 -20.701)
		(end 36.08578 -19.7866)
		(width 0.127)
		(layer "In7.Cu")
		(net "RGB_LED_I2C_SCL")
	)
	(segment
		(start 28.433014 -23.457154)
		(end 28.102306 -23.126446)
		(width 0.127)
		(layer "In7.Cu")
		(net "RGB_LED_I2C_SCL")
	)
	(segment
		(start 33.934146 -20.2946)
		(end 34.061146 -20.1676)
		(width 0.127)
		(layer "In7.Cu")
		(net "RGB_LED_I2C_SCL")
	)
	(segment
		(start 30.229302 -21.840698)
		(end 30.229302 -21.660866)
		(width 0.127)
		(layer "In7.Cu")
		(net "RGB_LED_I2C_SCL")
	)
	(segment
		(start 28.102306 -22.946614)
		(end 28.371546 -22.677374)
		(width 0.127)
		(layer "In7.Cu")
		(net "RGB_LED_I2C_SCL")
	)
	(segment
		(start 33.934146 -20.574)
		(end 33.934146 -20.2946)
		(width 0.127)
		(layer "In7.Cu")
		(net "RGB_LED_I2C_SCL")
	)
	(segment
		(start 28.102306 -23.126446)
		(end 28.102306 -22.946614)
		(width 0.127)
		(layer "In7.Cu")
		(net "RGB_LED_I2C_SCL")
	)
	(segment
		(start 30.678374 -21.211794)
		(end 30.858206 -21.211794)
		(width 0.127)
		(layer "In7.Cu")
		(net "RGB_LED_I2C_SCL")
	)
	(segment
		(start 27.204162 -23.844758)
		(end 27.473402 -23.575518)
		(width 0.127)
		(layer "In7.Cu")
		(net "RGB_LED_I2C_SCL")
	)
	(segment
		(start 27.473402 -23.575518)
		(end 27.653234 -23.575518)
		(width 0.127)
		(layer "In7.Cu")
		(net "RGB_LED_I2C_SCL")
	)
	(segment
		(start 28.882086 -23.008082)
		(end 29.061918 -23.008082)
		(width 0.127)
		(layer "In7.Cu")
		(net "RGB_LED_I2C_SCL")
	)
	(segment
		(start 29.78023 -22.109938)
		(end 29.960062 -22.109938)
		(width 0.127)
		(layer "In7.Cu")
		(net "RGB_LED_I2C_SCL")
	)
	(segment
		(start 30.347666 -20.881086)
		(end 30.678374 -21.211794)
		(width 0.127)
		(layer "In7.Cu")
		(net "RGB_LED_I2C_SCL")
	)
	(segment
		(start 34.061146 -20.1676)
		(end 34.442146 -20.1676)
		(width 0.127)
		(layer "In7.Cu")
		(net "RGB_LED_I2C_SCL")
	)
	(segment
		(start 28.433014 -23.636986)
		(end 28.433014 -23.457154)
		(width 0.127)
		(layer "In7.Cu")
		(net "RGB_LED_I2C_SCL")
	)
	(segment
		(start 28.551378 -22.677374)
		(end 28.882086 -23.008082)
		(width 0.127)
		(layer "In7.Cu")
		(net "RGB_LED_I2C_SCL")
	)
	(segment
		(start 30.167834 -20.881086)
		(end 30.347666 -20.881086)
		(width 0.127)
		(layer "In7.Cu")
		(net "RGB_LED_I2C_SCL")
	)
	(segment
		(start 34.696146 -20.701)
		(end 35.17138 -20.701)
		(width 0.127)
		(layer "In7.Cu")
		(net "RGB_LED_I2C_SCL")
	)
	(segment
		(start 34.569146 -20.574)
		(end 34.696146 -20.701)
		(width 0.127)
		(layer "In7.Cu")
		(net "RGB_LED_I2C_SCL")
	)
	(segment
		(start 24.511 -34.417)
		(end 26.67 -32.258)
		(width 0.127)
		(layer "In7.Cu")
		(net "RGB_LED_I2C_SCL")
	)
	(segment
		(start 29.00045 -22.04847)
		(end 29.26969 -21.77923)
		(width 0.127)
		(layer "In7.Cu")
		(net "RGB_LED_I2C_SCL")
	)
	(segment
		(start 24.511 -35.56)
		(end 24.511 -34.417)
		(width 0.127)
		(layer "In7.Cu")
		(net "RGB_LED_I2C_SCL")
	)
	(segment
		(start 27.204162 -24.02459)
		(end 27.204162 -23.844758)
		(width 0.127)
		(layer "In7.Cu")
		(net "RGB_LED_I2C_SCL")
	)
	(segment
		(start 29.898594 -21.150326)
		(end 30.167834 -20.881086)
		(width 0.127)
		(layer "In7.Cu")
		(net "RGB_LED_I2C_SCL")
	)
	(segment
		(start 26.67 -25.4)
		(end 27.53487 -24.53513)
		(width 0.127)
		(layer "In7.Cu")
		(net "RGB_LED_I2C_SCL")
	)
	(segment
		(start 34.442146 -20.1676)
		(end 34.569146 -20.2946)
		(width 0.127)
		(layer "In7.Cu")
		(net "RGB_LED_I2C_SCL")
	)
	(segment
		(start 28.371546 -22.677374)
		(end 28.551378 -22.677374)
		(width 0.127)
		(layer "In7.Cu")
		(net "RGB_LED_I2C_SCL")
	)
	(segment
		(start 29.449522 -21.77923)
		(end 29.78023 -22.109938)
		(width 0.127)
		(layer "In7.Cu")
		(net "RGB_LED_I2C_SCL")
	)
	(segment
		(start 27.53487 -24.355298)
		(end 27.204162 -24.02459)
		(width 0.127)
		(layer "In7.Cu")
		(net "RGB_LED_I2C_SCL")
	)
	(segment
		(start 27.53487 -24.53513)
		(end 27.53487 -24.355298)
		(width 0.127)
		(layer "In7.Cu")
		(net "RGB_LED_I2C_SCL")
	)
	(segment
		(start 31.369 -20.701)
		(end 33.807146 -20.701)
		(width 0.127)
		(layer "In7.Cu")
		(net "RGB_LED_I2C_SCL")
	)
	(segment
		(start 34.569146 -20.2946)
		(end 34.569146 -20.574)
		(width 0.127)
		(layer "In7.Cu")
		(net "RGB_LED_I2C_SCL")
	)
	(segment
		(start 28.163774 -23.906226)
		(end 28.433014 -23.636986)
		(width 0.127)
		(layer "In7.Cu")
		(net "RGB_LED_I2C_SCL")
	)
	(segment
		(start 29.331158 -22.55901)
		(end 29.00045 -22.228302)
		(width 0.127)
		(layer "In7.Cu")
		(net "RGB_LED_I2C_SCL")
	)
	(segment
		(start 33.807146 -20.701)
		(end 33.934146 -20.574)
		(width 0.127)
		(layer "In7.Cu")
		(net "RGB_LED_I2C_SCL")
	)
	(segment
		(start 29.331158 -22.738842)
		(end 29.331158 -22.55901)
		(width 0.127)
		(layer "In7.Cu")
		(net "RGB_LED_I2C_SCL")
	)
	(segment
		(start 29.898594 -21.330158)
		(end 29.898594 -21.150326)
		(width 0.127)
		(layer "In7.Cu")
		(net "RGB_LED_I2C_SCL")
	)
	(segment
		(start 30.229302 -21.660866)
		(end 29.898594 -21.330158)
		(width 0.127)
		(layer "In7.Cu")
		(net "RGB_LED_I2C_SCL")
	)
	(segment
		(start 30.858206 -21.211794)
		(end 31.369 -20.701)
		(width 0.127)
		(layer "In7.Cu")
		(net "RGB_LED_I2C_SCL")
	)
	(segment
		(start 27.653234 -23.575518)
		(end 27.983942 -23.906226)
		(width 0.127)
		(layer "In7.Cu")
		(net "RGB_LED_I2C_SCL")
	)
	(segment
		(start 117.84711 -50.823114)
		(end 118.346982 -51.322986)
		(width 0.11938)
		(layer "F.Cu")
		(net "FPGA_OUT_RGB_LED_SHUTDOWN_N")
	)
	(via
		(at 118.346982 -51.322986)
		(size 0.4572)
		(drill 0.2032)
		(layers "F.Cu" "B.Cu")
		(net "FPGA_OUT_RGB_LED_SHUTDOWN_N")
	)
	(via
		(at 109.982 -89.789)
		(size 0.508)
		(drill 0.254)
		(layers "F.Cu" "B.Cu")
		(net "FPGA_OUT_RGB_LED_SHUTDOWN_N")
	)
	(segment
		(start 111.6584 -98.171)
		(end 112.014 -97.8154)
		(width 0.11938)
		(layer "B.Cu")
		(net "FPGA_OUT_RGB_LED_SHUTDOWN_N")
	)
	(segment
		(start 109.22 -90.805)
		(end 109.982 -90.043)
		(width 0.11938)
		(layer "B.Cu")
		(net "FPGA_OUT_RGB_LED_SHUTDOWN_N")
	)
	(segment
		(start 112.014 -96.52)
		(end 109.22 -93.726)
		(width 0.11938)
		(layer "B.Cu")
		(net "FPGA_OUT_RGB_LED_SHUTDOWN_N")
	)
	(segment
		(start 109.982 -90.043)
		(end 109.982 -89.789)
		(width 0.11938)
		(layer "B.Cu")
		(net "FPGA_OUT_RGB_LED_SHUTDOWN_N")
	)
	(segment
		(start 109.22 -93.726)
		(end 109.22 -90.805)
		(width 0.11938)
		(layer "B.Cu")
		(net "FPGA_OUT_RGB_LED_SHUTDOWN_N")
	)
	(segment
		(start 112.014 -97.8154)
		(end 112.014 -96.52)
		(width 0.11938)
		(layer "B.Cu")
		(net "FPGA_OUT_RGB_LED_SHUTDOWN_N")
	)
	(segment
		(start 119.432832 -51.816)
		(end 118.839996 -51.816)
		(width 0.127)
		(layer "In7.Cu")
		(net "FPGA_OUT_RGB_LED_SHUTDOWN_N")
	)
	(segment
		(start 119.76608 -52.299108)
		(end 119.76608 -52.149248)
		(width 0.127)
		(layer "In7.Cu")
		(net "FPGA_OUT_RGB_LED_SHUTDOWN_N")
	)
	(segment
		(start 118.872 -83.312)
		(end 118.872 -81.098898)
		(width 0.127)
		(layer "In7.Cu")
		(net "FPGA_OUT_RGB_LED_SHUTDOWN_N")
	)
	(segment
		(start 124.1679 -59.75096)
		(end 122.174 -57.75706)
		(width 0.127)
		(layer "In7.Cu")
		(net "FPGA_OUT_RGB_LED_SHUTDOWN_N")
	)
	(segment
		(start 115.653566 -85.344)
		(end 116.84 -85.344)
		(width 0.127)
		(layer "In7.Cu")
		(net "FPGA_OUT_RGB_LED_SHUTDOWN_N")
	)
	(segment
		(start 119.76608 -52.149248)
		(end 119.432832 -51.816)
		(width 0.127)
		(layer "In7.Cu")
		(net "FPGA_OUT_RGB_LED_SHUTDOWN_N")
	)
	(segment
		(start 111.125 -88.646)
		(end 112.351566 -88.646)
		(width 0.127)
		(layer "In7.Cu")
		(net "FPGA_OUT_RGB_LED_SHUTDOWN_N")
	)
	(segment
		(start 118.872 -81.098898)
		(end 120.6246 -79.346298)
		(width 0.127)
		(layer "In7.Cu")
		(net "FPGA_OUT_RGB_LED_SHUTDOWN_N")
	)
	(segment
		(start 120.766078 -55.487824)
		(end 120.766078 -53.149246)
		(width 0.127)
		(layer "In7.Cu")
		(net "FPGA_OUT_RGB_LED_SHUTDOWN_N")
	)
	(segment
		(start 109.982 -89.789)
		(end 111.125 -88.646)
		(width 0.127)
		(layer "In7.Cu")
		(net "FPGA_OUT_RGB_LED_SHUTDOWN_N")
	)
	(segment
		(start 116.84 -85.344)
		(end 118.872 -83.312)
		(width 0.127)
		(layer "In7.Cu")
		(net "FPGA_OUT_RGB_LED_SHUTDOWN_N")
	)
	(segment
		(start 120.6246 -73.5584)
		(end 124.1679 -70.0151)
		(width 0.127)
		(layer "In7.Cu")
		(net "FPGA_OUT_RGB_LED_SHUTDOWN_N")
	)
	(segment
		(start 122.174 -56.895746)
		(end 120.766078 -55.487824)
		(width 0.127)
		(layer "In7.Cu")
		(net "FPGA_OUT_RGB_LED_SHUTDOWN_N")
	)
	(segment
		(start 120.766078 -53.149246)
		(end 120.448832 -52.832)
		(width 0.127)
		(layer "In7.Cu")
		(net "FPGA_OUT_RGB_LED_SHUTDOWN_N")
	)
	(segment
		(start 112.351566 -88.646)
		(end 115.653566 -85.344)
		(width 0.127)
		(layer "In7.Cu")
		(net "FPGA_OUT_RGB_LED_SHUTDOWN_N")
	)
	(segment
		(start 122.174 -57.75706)
		(end 122.174 -56.895746)
		(width 0.127)
		(layer "In7.Cu")
		(net "FPGA_OUT_RGB_LED_SHUTDOWN_N")
	)
	(segment
		(start 120.448832 -52.832)
		(end 120.298972 -52.832)
		(width 0.127)
		(layer "In7.Cu")
		(net "FPGA_OUT_RGB_LED_SHUTDOWN_N")
	)
	(segment
		(start 124.1679 -70.0151)
		(end 124.1679 -59.75096)
		(width 0.127)
		(layer "In7.Cu")
		(net "FPGA_OUT_RGB_LED_SHUTDOWN_N")
	)
	(segment
		(start 120.298972 -52.832)
		(end 119.76608 -52.299108)
		(width 0.127)
		(layer "In7.Cu")
		(net "FPGA_OUT_RGB_LED_SHUTDOWN_N")
	)
	(segment
		(start 120.6246 -79.346298)
		(end 120.6246 -73.5584)
		(width 0.127)
		(layer "In7.Cu")
		(net "FPGA_OUT_RGB_LED_SHUTDOWN_N")
	)
	(segment
		(start 118.839996 -51.816)
		(end 118.346982 -51.322986)
		(width 0.127)
		(layer "In7.Cu")
		(net "FPGA_OUT_RGB_LED_SHUTDOWN_N")
	)
	(segment
		(start 116.847112 -51.823112)
		(end 117.346984 -52.322984)
		(width 0.11938)
		(layer "F.Cu")
		(net "FPGA_M_RGB_LED_I2C_SDA")
	)
	(via
		(at 111.633 -86.741)
		(size 0.4572)
		(drill 0.2032)
		(layers "F.Cu" "B.Cu")
		(net "FPGA_M_RGB_LED_I2C_SDA")
	)
	(via
		(at 117.346984 -52.322984)
		(size 0.4572)
		(drill 0.2032)
		(layers "F.Cu" "B.Cu")
		(net "FPGA_M_RGB_LED_I2C_SDA")
	)
	(via
		(at 112.776 -103.251)
		(size 0.4572)
		(drill 0.2032)
		(layers "F.Cu" "B.Cu")
		(net "FPGA_M_RGB_LED_I2C_SDA")
	)
	(segment
		(start 112.776 -103.251)
		(end 111.6584 -103.251)
		(width 0.11938)
		(layer "B.Cu")
		(net "FPGA_M_RGB_LED_I2C_SDA")
	)
	(segment
		(start 113.284 -102.743)
		(end 113.284 -96.774)
		(width 0.11938)
		(layer "B.Cu")
		(net "FPGA_M_RGB_LED_I2C_SDA")
	)
	(segment
		(start 112.20958 -92.932504)
		(end 112.20069 -92.923614)
		(width 0.11938)
		(layer "B.Cu")
		(net "FPGA_M_RGB_LED_I2C_SDA")
	)
	(segment
		(start 112.20069 -92.923614)
		(end 112.20069 -87.30869)
		(width 0.11938)
		(layer "B.Cu")
		(net "FPGA_M_RGB_LED_I2C_SDA")
	)
	(segment
		(start 113.284 -96.774)
		(end 112.20958 -95.69958)
		(width 0.11938)
		(layer "B.Cu")
		(net "FPGA_M_RGB_LED_I2C_SDA")
	)
	(segment
		(start 112.20069 -87.30869)
		(end 111.633 -86.741)
		(width 0.11938)
		(layer "B.Cu")
		(net "FPGA_M_RGB_LED_I2C_SDA")
	)
	(segment
		(start 112.776 -103.251)
		(end 113.284 -102.743)
		(width 0.11938)
		(layer "B.Cu")
		(net "FPGA_M_RGB_LED_I2C_SDA")
	)
	(segment
		(start 112.20958 -95.69958)
		(end 112.20958 -92.932504)
		(width 0.11938)
		(layer "B.Cu")
		(net "FPGA_M_RGB_LED_I2C_SDA")
	)
	(segment
		(start 117.8814 -53.4924)
		(end 118.364 -53.975)
		(width 0.127)
		(layer "In7.Cu")
		(net "FPGA_M_RGB_LED_I2C_SDA")
	)
	(segment
		(start 121.031 -66.601848)
		(end 121.031 -70.612)
		(width 0.127)
		(layer "In7.Cu")
		(net "FPGA_M_RGB_LED_I2C_SDA")
	)
	(segment
		(start 111.930434 -86.741)
		(end 111.633 -86.741)
		(width 0.127)
		(layer "In7.Cu")
		(net "FPGA_M_RGB_LED_I2C_SDA")
	)
	(segment
		(start 113.665 -85.006434)
		(end 111.930434 -86.741)
		(width 0.127)
		(layer "In7.Cu")
		(net "FPGA_M_RGB_LED_I2C_SDA")
	)
	(segment
		(start 118.364 -56.356758)
		(end 119.634 -57.626758)
		(width 0.127)
		(layer "In7.Cu")
		(net "FPGA_M_RGB_LED_I2C_SDA")
	)
	(segment
		(start 120.269 -59.138566)
		(end 120.269 -62.992)
		(width 0.127)
		(layer "In7.Cu")
		(net "FPGA_M_RGB_LED_I2C_SDA")
	)
	(segment
		(start 119.634 -57.626758)
		(end 119.634 -58.503566)
		(width 0.127)
		(layer "In7.Cu")
		(net "FPGA_M_RGB_LED_I2C_SDA")
	)
	(segment
		(start 120.7135 -63.4365)
		(end 120.7135 -66.284348)
		(width 0.127)
		(layer "In7.Cu")
		(net "FPGA_M_RGB_LED_I2C_SDA")
	)
	(segment
		(start 120.269 -62.992)
		(end 120.7135 -63.4365)
		(width 0.127)
		(layer "In7.Cu")
		(net "FPGA_M_RGB_LED_I2C_SDA")
	)
	(segment
		(start 117.8814 -52.8574)
		(end 117.8814 -53.4924)
		(width 0.127)
		(layer "In7.Cu")
		(net "FPGA_M_RGB_LED_I2C_SDA")
	)
	(segment
		(start 117.221 -80.391)
		(end 113.665 -83.947)
		(width 0.127)
		(layer "In7.Cu")
		(net "FPGA_M_RGB_LED_I2C_SDA")
	)
	(segment
		(start 120.7135 -66.284348)
		(end 121.031 -66.601848)
		(width 0.127)
		(layer "In7.Cu")
		(net "FPGA_M_RGB_LED_I2C_SDA")
	)
	(segment
		(start 119.1006 -78.7146)
		(end 117.4242 -80.391)
		(width 0.127)
		(layer "In7.Cu")
		(net "FPGA_M_RGB_LED_I2C_SDA")
	)
	(segment
		(start 119.1006 -72.5424)
		(end 119.1006 -78.7146)
		(width 0.127)
		(layer "In7.Cu")
		(net "FPGA_M_RGB_LED_I2C_SDA")
	)
	(segment
		(start 118.364 -53.975)
		(end 118.364 -56.356758)
		(width 0.127)
		(layer "In7.Cu")
		(net "FPGA_M_RGB_LED_I2C_SDA")
	)
	(segment
		(start 117.4242 -80.391)
		(end 117.221 -80.391)
		(width 0.127)
		(layer "In7.Cu")
		(net "FPGA_M_RGB_LED_I2C_SDA")
	)
	(segment
		(start 117.346984 -52.322984)
		(end 117.8814 -52.8574)
		(width 0.127)
		(layer "In7.Cu")
		(net "FPGA_M_RGB_LED_I2C_SDA")
	)
	(segment
		(start 121.031 -70.612)
		(end 119.1006 -72.5424)
		(width 0.127)
		(layer "In7.Cu")
		(net "FPGA_M_RGB_LED_I2C_SDA")
	)
	(segment
		(start 119.634 -58.503566)
		(end 120.269 -59.138566)
		(width 0.127)
		(layer "In7.Cu")
		(net "FPGA_M_RGB_LED_I2C_SDA")
	)
	(segment
		(start 113.665 -83.947)
		(end 113.665 -85.006434)
		(width 0.127)
		(layer "In7.Cu")
		(net "FPGA_M_RGB_LED_I2C_SDA")
	)
	(segment
		(start 116.847112 -52.82311)
		(end 117.346984 -53.322982)
		(width 0.11938)
		(layer "F.Cu")
		(net "FPGA_M_RGB_LED_I2C_SCL")
	)
	(via
		(at 117.346984 -53.322982)
		(size 0.4572)
		(drill 0.2032)
		(layers "F.Cu" "B.Cu")
		(net "FPGA_M_RGB_LED_I2C_SCL")
	)
	(via
		(at 112.395 -85.366606)
		(size 0.4572)
		(drill 0.2032)
		(layers "F.Cu" "B.Cu")
		(net "FPGA_M_RGB_LED_I2C_SCL")
	)
	(via
		(at 112.776 -104.521)
		(size 0.4572)
		(drill 0.2032)
		(layers "F.Cu" "B.Cu")
		(net "FPGA_M_RGB_LED_I2C_SCL")
	)
	(segment
		(start 113.72342 -96.591882)
		(end 113.72342 -103.57358)
		(width 0.11938)
		(layer "B.Cu")
		(net "FPGA_M_RGB_LED_I2C_SCL")
	)
	(segment
		(start 113.72342 -103.57358)
		(end 112.776 -104.521)
		(width 0.11938)
		(layer "B.Cu")
		(net "FPGA_M_RGB_LED_I2C_SCL")
	)
	(segment
		(start 112.70234 -85.673946)
		(end 112.70234 -95.570802)
		(width 0.11938)
		(layer "B.Cu")
		(net "FPGA_M_RGB_LED_I2C_SCL")
	)
	(segment
		(start 112.395 -85.366606)
		(end 112.70234 -85.673946)
		(width 0.11938)
		(layer "B.Cu")
		(net "FPGA_M_RGB_LED_I2C_SCL")
	)
	(segment
		(start 112.776 -104.521)
		(end 111.6584 -104.521)
		(width 0.11938)
		(layer "B.Cu")
		(net "FPGA_M_RGB_LED_I2C_SCL")
	)
	(segment
		(start 112.70234 -95.570802)
		(end 113.72342 -96.591882)
		(width 0.11938)
		(layer "B.Cu")
		(net "FPGA_M_RGB_LED_I2C_SCL")
	)
	(segment
		(start 118.237 -61.722254)
		(end 120.2055 -63.690754)
		(width 0.127)
		(layer "In7.Cu")
		(net "FPGA_M_RGB_LED_I2C_SCL")
	)
	(segment
		(start 112.9665 -84.795106)
		(end 112.395 -85.366606)
		(width 0.127)
		(layer "In7.Cu")
		(net "FPGA_M_RGB_LED_I2C_SCL")
	)
	(segment
		(start 120.523 -66.928746)
		(end 120.523 -70.231254)
		(width 0.127)
		(layer "In7.Cu")
		(net "FPGA_M_RGB_LED_I2C_SCL")
	)
	(segment
		(start 117.8306 -54.1274)
		(end 117.8306 -56.6166)
		(width 0.127)
		(layer "In7.Cu")
		(net "FPGA_M_RGB_LED_I2C_SCL")
	)
	(segment
		(start 113.157508 -83.735926)
		(end 112.9665 -83.926934)
		(width 0.127)
		(layer "In7.Cu")
		(net "FPGA_M_RGB_LED_I2C_SCL")
	)
	(segment
		(start 113.60658 -83.107022)
		(end 113.485168 -82.98561)
		(width 0.127)
		(layer "In7.Cu")
		(net "FPGA_M_RGB_LED_I2C_SCL")
	)
	(segment
		(start 112.9665 -83.926934)
		(end 112.9665 -84.795106)
		(width 0.127)
		(layer "In7.Cu")
		(net "FPGA_M_RGB_LED_I2C_SCL")
	)
	(segment
		(start 113.485168 -82.98561)
		(end 113.305336 -82.98561)
		(width 0.127)
		(layer "In7.Cu")
		(net "FPGA_M_RGB_LED_I2C_SCL")
	)
	(segment
		(start 120.523 -70.231254)
		(end 118.5926 -72.161654)
		(width 0.127)
		(layer "In7.Cu")
		(net "FPGA_M_RGB_LED_I2C_SCL")
	)
	(segment
		(start 113.305336 -82.98561)
		(end 113.036096 -83.25485)
		(width 0.127)
		(layer "In7.Cu")
		(net "FPGA_M_RGB_LED_I2C_SCL")
	)
	(segment
		(start 117.213634 -79.883)
		(end 117.010434 -79.883)
		(width 0.127)
		(layer "In7.Cu")
		(net "FPGA_M_RGB_LED_I2C_SCL")
	)
	(segment
		(start 113.036096 -83.434682)
		(end 113.157508 -83.556094)
		(width 0.127)
		(layer "In7.Cu")
		(net "FPGA_M_RGB_LED_I2C_SCL")
	)
	(segment
		(start 117.346984 -53.643784)
		(end 117.8306 -54.1274)
		(width 0.127)
		(layer "In7.Cu")
		(net "FPGA_M_RGB_LED_I2C_SCL")
	)
	(segment
		(start 118.237 -57.023)
		(end 118.237 -61.722254)
		(width 0.127)
		(layer "In7.Cu")
		(net "FPGA_M_RGB_LED_I2C_SCL")
	)
	(segment
		(start 117.010434 -79.883)
		(end 113.786412 -83.107022)
		(width 0.127)
		(layer "In7.Cu")
		(net "FPGA_M_RGB_LED_I2C_SCL")
	)
	(segment
		(start 118.5926 -72.161654)
		(end 118.5926 -78.504034)
		(width 0.127)
		(layer "In7.Cu")
		(net "FPGA_M_RGB_LED_I2C_SCL")
	)
	(segment
		(start 118.5926 -78.504034)
		(end 117.213634 -79.883)
		(width 0.127)
		(layer "In7.Cu")
		(net "FPGA_M_RGB_LED_I2C_SCL")
	)
	(segment
		(start 113.157508 -83.556094)
		(end 113.157508 -83.735926)
		(width 0.127)
		(layer "In7.Cu")
		(net "FPGA_M_RGB_LED_I2C_SCL")
	)
	(segment
		(start 117.8306 -56.6166)
		(end 118.237 -57.023)
		(width 0.127)
		(layer "In7.Cu")
		(net "FPGA_M_RGB_LED_I2C_SCL")
	)
	(segment
		(start 113.036096 -83.25485)
		(end 113.036096 -83.434682)
		(width 0.127)
		(layer "In7.Cu")
		(net "FPGA_M_RGB_LED_I2C_SCL")
	)
	(segment
		(start 120.2055 -63.690754)
		(end 120.2055 -66.611246)
		(width 0.127)
		(layer "In7.Cu")
		(net "FPGA_M_RGB_LED_I2C_SCL")
	)
	(segment
		(start 113.786412 -83.107022)
		(end 113.60658 -83.107022)
		(width 0.127)
		(layer "In7.Cu")
		(net "FPGA_M_RGB_LED_I2C_SCL")
	)
	(segment
		(start 120.2055 -66.611246)
		(end 120.523 -66.928746)
		(width 0.127)
		(layer "In7.Cu")
		(net "FPGA_M_RGB_LED_I2C_SCL")
	)
	(segment
		(start 117.346984 -53.322982)
		(end 117.346984 -53.643784)
		(width 0.127)
		(layer "In7.Cu")
		(net "FPGA_M_RGB_LED_I2C_SCL")
	)
	(segment
		(start 21.17852 -58.32348)
		(end 21.17852 -57.0611)
		(width 0.11938)
		(layer "F.Cu")
		(net "BF_ICP10100_I2C_SDA")
	)
	(segment
		(start 16.318992 -67.6656)
		(end 16.318992 -68.8086)
		(width 0.11938)
		(layer "F.Cu")
		(net "BF_ICP10100_I2C_SDA")
	)
	(segment
		(start 20.955 -58.547)
		(end 21.17852 -58.32348)
		(width 0.11938)
		(layer "F.Cu")
		(net "BF_ICP10100_I2C_SDA")
	)
	(segment
		(start 16.318992 -69.482208)
		(end 16.2052 -69.596)
		(width 0.11938)
		(layer "F.Cu")
		(net "BF_ICP10100_I2C_SDA")
	)
	(segment
		(start 16.318992 -68.8086)
		(end 16.318992 -69.482208)
		(width 0.11938)
		(layer "F.Cu")
		(net "BF_ICP10100_I2C_SDA")
	)
	(via
		(at 20.955 -58.547)
		(size 0.4572)
		(drill 0.2032)
		(layers "F.Cu" "B.Cu")
		(net "BF_ICP10100_I2C_SDA")
	)
	(via
		(at 16.2052 -69.596)
		(size 0.4572)
		(drill 0.2032)
		(layers "F.Cu" "B.Cu")
		(net "BF_ICP10100_I2C_SDA")
	)
	(segment
		(start 20.955 -58.547)
		(end 21.082 -58.674)
		(width 0.11938)
		(layer "B.Cu")
		(net "BF_ICP10100_I2C_SDA")
	)
	(segment
		(start 21.082 -58.674)
		(end 21.082 -59.950096)
		(width 0.11938)
		(layer "B.Cu")
		(net "BF_ICP10100_I2C_SDA")
	)
	(segment
		(start 20.447 -60.585096)
		(end 20.447 -61.0108)
		(width 0.11938)
		(layer "B.Cu")
		(net "BF_ICP10100_I2C_SDA")
	)
	(segment
		(start 21.082 -59.950096)
		(end 20.447 -60.585096)
		(width 0.11938)
		(layer "B.Cu")
		(net "BF_ICP10100_I2C_SDA")
	)
	(segment
		(start 16.2052 -69.596)
		(end 16.318992 -69.482208)
		(width 0.127)
		(layer "In7.Cu")
		(net "BF_ICP10100_I2C_SDA")
	)
	(segment
		(start 20.193 -58.547)
		(end 20.955 -58.547)
		(width 0.127)
		(layer "In7.Cu")
		(net "BF_ICP10100_I2C_SDA")
	)
	(segment
		(start 19.5326 -64.4652)
		(end 19.5326 -59.2074)
		(width 0.127)
		(layer "In7.Cu")
		(net "BF_ICP10100_I2C_SDA")
	)
	(segment
		(start 16.318992 -67.678808)
		(end 19.5326 -64.4652)
		(width 0.127)
		(layer "In7.Cu")
		(net "BF_ICP10100_I2C_SDA")
	)
	(segment
		(start 16.318992 -69.482208)
		(end 16.318992 -67.678808)
		(width 0.127)
		(layer "In7.Cu")
		(net "BF_ICP10100_I2C_SDA")
	)
	(segment
		(start 19.5326 -59.2074)
		(end 20.193 -58.547)
		(width 0.127)
		(layer "In7.Cu")
		(net "BF_ICP10100_I2C_SDA")
	)
	(segment
		(start 20.193 -58.293)
		(end 20.52828 -57.95772)
		(width 0.11938)
		(layer "F.Cu")
		(net "BF_ICP10100_I2C_SCL")
	)
	(segment
		(start 20.484592 -71.9074)
		(end 19.3294 -71.9074)
		(width 0.11938)
		(layer "F.Cu")
		(net "BF_ICP10100_I2C_SCL")
	)
	(segment
		(start 19.2024 -71.7296)
		(end 19.177 -71.755)
		(width 0.11938)
		(layer "F.Cu")
		(net "BF_ICP10100_I2C_SCL")
	)
	(segment
		(start 19.3294 -71.9074)
		(end 19.177 -71.755)
		(width 0.11938)
		(layer "F.Cu")
		(net "BF_ICP10100_I2C_SCL")
	)
	(segment
		(start 20.193 -59.563)
		(end 20.193 -58.293)
		(width 0.11938)
		(layer "F.Cu")
		(net "BF_ICP10100_I2C_SCL")
	)
	(segment
		(start 19.2024 -70.866)
		(end 19.2024 -71.7296)
		(width 0.11938)
		(layer "F.Cu")
		(net "BF_ICP10100_I2C_SCL")
	)
	(segment
		(start 20.52828 -57.95772)
		(end 20.52828 -57.0611)
		(width 0.11938)
		(layer "F.Cu")
		(net "BF_ICP10100_I2C_SCL")
	)
	(via
		(at 20.193 -59.563)
		(size 0.4572)
		(drill 0.2032)
		(layers "F.Cu" "B.Cu")
		(net "BF_ICP10100_I2C_SCL")
	)
	(via
		(at 19.177 -71.755)
		(size 0.4572)
		(drill 0.2032)
		(layers "F.Cu" "B.Cu")
		(net "BF_ICP10100_I2C_SCL")
	)
	(segment
		(start 20.193 -59.563)
		(end 20.193 -59.677046)
		(width 0.11938)
		(layer "B.Cu")
		(net "BF_ICP10100_I2C_SCL")
	)
	(segment
		(start 20.193 -59.677046)
		(end 19.304 -60.566046)
		(width 0.11938)
		(layer "B.Cu")
		(net "BF_ICP10100_I2C_SCL")
	)
	(segment
		(start 19.304 -60.566046)
		(end 19.304 -61.0108)
		(width 0.11938)
		(layer "B.Cu")
		(net "BF_ICP10100_I2C_SCL")
	)
	(segment
		(start 20.374102 -59.744102)
		(end 20.193 -59.563)
		(width 0.127)
		(layer "In7.Cu")
		(net "BF_ICP10100_I2C_SCL")
	)
	(segment
		(start 19.1008 -69.052186)
		(end 19.1008 -65.615566)
		(width 0.127)
		(layer "In7.Cu")
		(net "BF_ICP10100_I2C_SCL")
	)
	(segment
		(start 19.718274 -64.998092)
		(end 20.594574 -64.998092)
		(width 0.127)
		(layer "In7.Cu")
		(net "BF_ICP10100_I2C_SCL")
	)
	(segment
		(start 20.7645 -62.994286)
		(end 20.374102 -62.603888)
		(width 0.127)
		(layer "In7.Cu")
		(net "BF_ICP10100_I2C_SCL")
	)
	(segment
		(start 20.929092 -64.18961)
		(end 20.7645 -64.025018)
		(width 0.127)
		(layer "In7.Cu")
		(net "BF_ICP10100_I2C_SCL")
	)
	(segment
		(start 20.7645 -64.025018)
		(end 20.7645 -62.994286)
		(width 0.127)
		(layer "In7.Cu")
		(net "BF_ICP10100_I2C_SCL")
	)
	(segment
		(start 18.7071 -71.2851)
		(end 18.7071 -69.445886)
		(width 0.127)
		(layer "In7.Cu")
		(net "BF_ICP10100_I2C_SCL")
	)
	(segment
		(start 19.177 -71.755)
		(end 18.7071 -71.2851)
		(width 0.127)
		(layer "In7.Cu")
		(net "BF_ICP10100_I2C_SCL")
	)
	(segment
		(start 18.7071 -69.445886)
		(end 19.1008 -69.052186)
		(width 0.127)
		(layer "In7.Cu")
		(net "BF_ICP10100_I2C_SCL")
	)
	(segment
		(start 20.929092 -64.663574)
		(end 20.929092 -64.18961)
		(width 0.127)
		(layer "In7.Cu")
		(net "BF_ICP10100_I2C_SCL")
	)
	(segment
		(start 19.1008 -65.615566)
		(end 19.718274 -64.998092)
		(width 0.127)
		(layer "In7.Cu")
		(net "BF_ICP10100_I2C_SCL")
	)
	(segment
		(start 20.594574 -64.998092)
		(end 20.929092 -64.663574)
		(width 0.127)
		(layer "In7.Cu")
		(net "BF_ICP10100_I2C_SCL")
	)
	(segment
		(start 20.374102 -62.603888)
		(end 20.374102 -59.744102)
		(width 0.127)
		(layer "In7.Cu")
		(net "BF_ICP10100_I2C_SCL")
	)
	(segment
		(start 153.049986 -105.099866)
		(end 151.793702 -105.099866)
		(width 0.11938)
		(layer "F.Cu")
		(net "UNNAMED_14_OPTICAL_I194_A")
	)
	(via
		(at 151.793702 -105.099866)
		(size 0.508)
		(drill 0.254)
		(layers "F.Cu" "B.Cu")
		(net "UNNAMED_14_OPTICAL_I194_A")
	)
	(segment
		(start 151.793702 -105.099866)
		(end 151.966168 -104.9274)
		(width 0.11938)
		(layer "B.Cu")
		(net "UNNAMED_14_OPTICAL_I194_A")
	)
	(segment
		(start 151.966168 -104.9274)
		(end 153.035 -104.9274)
		(width 0.11938)
		(layer "B.Cu")
		(net "UNNAMED_14_OPTICAL_I194_A")
	)
	(segment
		(start 150.049992 -105.099866)
		(end 150.049992 -106.35615)
		(width 0.11938)
		(layer "F.Cu")
		(net "UNNAMED_14_OPTICAL_I191_A")
	)
	(via
		(at 150.049992 -106.35615)
		(size 0.508)
		(drill 0.254)
		(layers "F.Cu" "B.Cu")
		(net "UNNAMED_14_OPTICAL_I191_A")
	)
	(segment
		(start 150.049992 -106.35615)
		(end 150.114 -106.292142)
		(width 0.11938)
		(layer "B.Cu")
		(net "UNNAMED_14_OPTICAL_I191_A")
	)
	(segment
		(start 150.114 -106.292142)
		(end 150.114 -104.9274)
		(width 0.11938)
		(layer "B.Cu")
		(net "UNNAMED_14_OPTICAL_I191_A")
	)
	(segment
		(start 21.77669 -47.42307)
		(end 21.08962 -46.736)
		(width 0.11938)
		(layer "F.Cu")
		(net "FPGA_OUT_SMA4_LED_RED_N")
	)
	(segment
		(start 21.08962 -46.736)
		(end 20.001738 -46.736)
		(width 0.11938)
		(layer "F.Cu")
		(net "FPGA_OUT_SMA4_LED_RED_N")
	)
	(segment
		(start 103.847138 -50.823114)
		(end 103.347266 -51.322986)
		(width 0.11938)
		(layer "F.Cu")
		(net "FPGA_OUT_SMA4_LED_RED_N")
	)
	(segment
		(start 22.987 -49.149)
		(end 21.77669 -47.93869)
		(width 0.11938)
		(layer "F.Cu")
		(net "FPGA_OUT_SMA4_LED_RED_N")
	)
	(segment
		(start 21.77669 -47.93869)
		(end 21.77669 -47.42307)
		(width 0.11938)
		(layer "F.Cu")
		(net "FPGA_OUT_SMA4_LED_RED_N")
	)
	(via
		(at 22.987 -49.149)
		(size 0.508)
		(drill 0.254)
		(layers "F.Cu" "B.Cu")
		(net "FPGA_OUT_SMA4_LED_RED_N")
	)
	(via
		(at 103.347266 -51.322986)
		(size 0.4572)
		(drill 0.2032)
		(layers "F.Cu" "B.Cu")
		(net "FPGA_OUT_SMA4_LED_RED_N")
	)
	(segment
		(start 96.03994 -66.167)
		(end 95.03918 -66.167)
		(width 0.127)
		(layer "In7.Cu")
		(net "FPGA_OUT_SMA4_LED_RED_N")
	)
	(segment
		(start 92.242386 -64.897)
		(end 88.631014 -64.897)
		(width 0.127)
		(layer "In7.Cu")
		(net "FPGA_OUT_SMA4_LED_RED_N")
	)
	(segment
		(start 23.368 -51.054)
		(end 22.987 -50.673)
		(width 0.127)
		(layer "In7.Cu")
		(net "FPGA_OUT_SMA4_LED_RED_N")
	)
	(segment
		(start 30.099 -61.4426)
		(end 25.7556 -57.0992)
		(width 0.127)
		(layer "In7.Cu")
		(net "FPGA_OUT_SMA4_LED_RED_N")
	)
	(segment
		(start 74.738484 -60.9727)
		(end 64.8335 -60.9727)
		(width 0.127)
		(layer "In7.Cu")
		(net "FPGA_OUT_SMA4_LED_RED_N")
	)
	(segment
		(start 100.457 -63.373)
		(end 99.1997 -64.6303)
		(width 0.127)
		(layer "In7.Cu")
		(net "FPGA_OUT_SMA4_LED_RED_N")
	)
	(segment
		(start 101.9175 -59.4995)
		(end 100.457 -60.96)
		(width 0.127)
		(layer "In7.Cu")
		(net "FPGA_OUT_SMA4_LED_RED_N")
	)
	(segment
		(start 102.87 -54.609746)
		(end 101.9175 -55.562246)
		(width 0.127)
		(layer "In7.Cu")
		(net "FPGA_OUT_SMA4_LED_RED_N")
	)
	(segment
		(start 94.72168 -65.8495)
		(end 93.194886 -65.8495)
		(width 0.127)
		(layer "In7.Cu")
		(net "FPGA_OUT_SMA4_LED_RED_N")
	)
	(segment
		(start 25.7556 -57.0992)
		(end 24.454612 -57.0992)
		(width 0.127)
		(layer "In7.Cu")
		(net "FPGA_OUT_SMA4_LED_RED_N")
	)
	(segment
		(start 63.6524 -62.1538)
		(end 59.1312 -62.1538)
		(width 0.127)
		(layer "In7.Cu")
		(net "FPGA_OUT_SMA4_LED_RED_N")
	)
	(segment
		(start 64.8335 -60.9727)
		(end 63.6524 -62.1538)
		(width 0.127)
		(layer "In7.Cu")
		(net "FPGA_OUT_SMA4_LED_RED_N")
	)
	(segment
		(start 101.9175 -55.562246)
		(end 101.9175 -59.4995)
		(width 0.127)
		(layer "In7.Cu")
		(net "FPGA_OUT_SMA4_LED_RED_N")
	)
	(segment
		(start 100.457 -60.96)
		(end 100.457 -63.373)
		(width 0.127)
		(layer "In7.Cu")
		(net "FPGA_OUT_SMA4_LED_RED_N")
	)
	(segment
		(start 83.342988 -64.1731)
		(end 82.580988 -63.4111)
		(width 0.127)
		(layer "In7.Cu")
		(net "FPGA_OUT_SMA4_LED_RED_N")
	)
	(segment
		(start 82.580988 -63.4111)
		(end 77.176884 -63.4111)
		(width 0.127)
		(layer "In7.Cu")
		(net "FPGA_OUT_SMA4_LED_RED_N")
	)
	(segment
		(start 102.87 -51.800252)
		(end 102.87 -54.609746)
		(width 0.127)
		(layer "In7.Cu")
		(net "FPGA_OUT_SMA4_LED_RED_N")
	)
	(segment
		(start 88.631014 -64.897)
		(end 87.907114 -64.1731)
		(width 0.127)
		(layer "In7.Cu")
		(net "FPGA_OUT_SMA4_LED_RED_N")
	)
	(segment
		(start 23.368 -56.012588)
		(end 23.368 -51.054)
		(width 0.127)
		(layer "In7.Cu")
		(net "FPGA_OUT_SMA4_LED_RED_N")
	)
	(segment
		(start 93.194886 -65.8495)
		(end 92.242386 -64.897)
		(width 0.127)
		(layer "In7.Cu")
		(net "FPGA_OUT_SMA4_LED_RED_N")
	)
	(segment
		(start 58.42 -61.4426)
		(end 30.099 -61.4426)
		(width 0.127)
		(layer "In7.Cu")
		(net "FPGA_OUT_SMA4_LED_RED_N")
	)
	(segment
		(start 95.03918 -66.167)
		(end 94.72168 -65.8495)
		(width 0.127)
		(layer "In7.Cu")
		(net "FPGA_OUT_SMA4_LED_RED_N")
	)
	(segment
		(start 103.347266 -51.322986)
		(end 102.87 -51.800252)
		(width 0.127)
		(layer "In7.Cu")
		(net "FPGA_OUT_SMA4_LED_RED_N")
	)
	(segment
		(start 87.907114 -64.1731)
		(end 83.342988 -64.1731)
		(width 0.127)
		(layer "In7.Cu")
		(net "FPGA_OUT_SMA4_LED_RED_N")
	)
	(segment
		(start 99.1997 -64.6303)
		(end 97.57664 -64.6303)
		(width 0.127)
		(layer "In7.Cu")
		(net "FPGA_OUT_SMA4_LED_RED_N")
	)
	(segment
		(start 77.176884 -63.4111)
		(end 74.738484 -60.9727)
		(width 0.127)
		(layer "In7.Cu")
		(net "FPGA_OUT_SMA4_LED_RED_N")
	)
	(segment
		(start 59.1312 -62.1538)
		(end 58.42 -61.4426)
		(width 0.127)
		(layer "In7.Cu")
		(net "FPGA_OUT_SMA4_LED_RED_N")
	)
	(segment
		(start 22.987 -50.673)
		(end 22.987 -49.149)
		(width 0.127)
		(layer "In7.Cu")
		(net "FPGA_OUT_SMA4_LED_RED_N")
	)
	(segment
		(start 24.454612 -57.0992)
		(end 23.368 -56.012588)
		(width 0.127)
		(layer "In7.Cu")
		(net "FPGA_OUT_SMA4_LED_RED_N")
	)
	(segment
		(start 97.57664 -64.6303)
		(end 96.03994 -66.167)
		(width 0.127)
		(layer "In7.Cu")
		(net "FPGA_OUT_SMA4_LED_RED_N")
	)
	(segment
		(start 101.847142 -51.823112)
		(end 101.34727 -52.322984)
		(width 0.11938)
		(layer "F.Cu")
		(net "FPGA_OUT_SMA4_LED_GREEN_N")
	)
	(segment
		(start 23.876 -50.165)
		(end 20.001738 -50.165)
		(width 0.11938)
		(layer "F.Cu")
		(net "FPGA_OUT_SMA4_LED_GREEN_N")
	)
	(segment
		(start 24.003 -50.038)
		(end 23.876 -50.165)
		(width 0.11938)
		(layer "F.Cu")
		(net "FPGA_OUT_SMA4_LED_GREEN_N")
	)
	(via
		(at 24.003 -50.038)
		(size 0.508)
		(drill 0.254)
		(layers "F.Cu" "B.Cu")
		(net "FPGA_OUT_SMA4_LED_GREEN_N")
	)
	(via
		(at 101.34727 -52.322984)
		(size 0.4572)
		(drill 0.2032)
		(layers "F.Cu" "B.Cu")
		(net "FPGA_OUT_SMA4_LED_GREEN_N")
	)
	(segment
		(start 99.695 -57.37606)
		(end 99.695 -59.309)
		(width 0.127)
		(layer "In7.Cu")
		(net "FPGA_OUT_SMA4_LED_GREEN_N")
	)
	(segment
		(start 59.3598 -60.2488)
		(end 30.2514 -60.2488)
		(width 0.127)
		(layer "In7.Cu")
		(net "FPGA_OUT_SMA4_LED_GREEN_N")
	)
	(segment
		(start 88.94699 -64.135)
		(end 88.22309 -63.4111)
		(width 0.127)
		(layer "In7.Cu")
		(net "FPGA_OUT_SMA4_LED_GREEN_N")
	)
	(segment
		(start 88.22309 -63.4111)
		(end 86.1441 -63.4111)
		(width 0.127)
		(layer "In7.Cu")
		(net "FPGA_OUT_SMA4_LED_GREEN_N")
	)
	(segment
		(start 99.695 -59.309)
		(end 97.155 -61.849)
		(width 0.127)
		(layer "In7.Cu")
		(net "FPGA_OUT_SMA4_LED_GREEN_N")
	)
	(segment
		(start 30.2514 -60.2488)
		(end 26.2636 -56.261)
		(width 0.127)
		(layer "In7.Cu")
		(net "FPGA_OUT_SMA4_LED_GREEN_N")
	)
	(segment
		(start 86.1441 -63.4111)
		(end 84.8233 -62.0903)
		(width 0.127)
		(layer "In7.Cu")
		(net "FPGA_OUT_SMA4_LED_GREEN_N")
	)
	(segment
		(start 24.13 -55.6006)
		(end 24.13 -50.165)
		(width 0.127)
		(layer "In7.Cu")
		(net "FPGA_OUT_SMA4_LED_GREEN_N")
	)
	(segment
		(start 62.5856 -61.3918)
		(end 60.5028 -61.3918)
		(width 0.127)
		(layer "In7.Cu")
		(net "FPGA_OUT_SMA4_LED_GREEN_N")
	)
	(segment
		(start 100.88372 -54.753256)
		(end 99.3775 -56.259476)
		(width 0.127)
		(layer "In7.Cu")
		(net "FPGA_OUT_SMA4_LED_GREEN_N")
	)
	(segment
		(start 99.3775 -57.05856)
		(end 99.695 -57.37606)
		(width 0.127)
		(layer "In7.Cu")
		(net "FPGA_OUT_SMA4_LED_GREEN_N")
	)
	(segment
		(start 100.88372 -52.786534)
		(end 100.88372 -54.753256)
		(width 0.127)
		(layer "In7.Cu")
		(net "FPGA_OUT_SMA4_LED_GREEN_N")
	)
	(segment
		(start 24.7904 -56.261)
		(end 24.13 -55.6006)
		(width 0.127)
		(layer "In7.Cu")
		(net "FPGA_OUT_SMA4_LED_GREEN_N")
	)
	(segment
		(start 97.155 -61.849)
		(end 94.488 -61.849)
		(width 0.127)
		(layer "In7.Cu")
		(net "FPGA_OUT_SMA4_LED_GREEN_N")
	)
	(segment
		(start 101.34727 -52.322984)
		(end 100.88372 -52.786534)
		(width 0.127)
		(layer "In7.Cu")
		(net "FPGA_OUT_SMA4_LED_GREEN_N")
	)
	(segment
		(start 84.8233 -62.0903)
		(end 82.04708 -62.0903)
		(width 0.127)
		(layer "In7.Cu")
		(net "FPGA_OUT_SMA4_LED_GREEN_N")
	)
	(segment
		(start 81.48828 -62.6491)
		(end 77.49286 -62.6491)
		(width 0.127)
		(layer "In7.Cu")
		(net "FPGA_OUT_SMA4_LED_GREEN_N")
	)
	(segment
		(start 26.2636 -56.261)
		(end 24.7904 -56.261)
		(width 0.127)
		(layer "In7.Cu")
		(net "FPGA_OUT_SMA4_LED_GREEN_N")
	)
	(segment
		(start 24.13 -50.165)
		(end 24.003 -50.038)
		(width 0.127)
		(layer "In7.Cu")
		(net "FPGA_OUT_SMA4_LED_GREEN_N")
	)
	(segment
		(start 92.583 -64.135)
		(end 88.94699 -64.135)
		(width 0.127)
		(layer "In7.Cu")
		(net "FPGA_OUT_SMA4_LED_GREEN_N")
	)
	(segment
		(start 77.49286 -62.6491)
		(end 75.05446 -60.2107)
		(width 0.127)
		(layer "In7.Cu")
		(net "FPGA_OUT_SMA4_LED_GREEN_N")
	)
	(segment
		(start 99.3775 -56.259476)
		(end 99.3775 -57.05856)
		(width 0.127)
		(layer "In7.Cu")
		(net "FPGA_OUT_SMA4_LED_GREEN_N")
	)
	(segment
		(start 63.7667 -60.2107)
		(end 62.5856 -61.3918)
		(width 0.127)
		(layer "In7.Cu")
		(net "FPGA_OUT_SMA4_LED_GREEN_N")
	)
	(segment
		(start 93.98 -62.738)
		(end 92.583 -64.135)
		(width 0.127)
		(layer "In7.Cu")
		(net "FPGA_OUT_SMA4_LED_GREEN_N")
	)
	(segment
		(start 60.5028 -61.3918)
		(end 59.3598 -60.2488)
		(width 0.127)
		(layer "In7.Cu")
		(net "FPGA_OUT_SMA4_LED_GREEN_N")
	)
	(segment
		(start 82.04708 -62.0903)
		(end 81.48828 -62.6491)
		(width 0.127)
		(layer "In7.Cu")
		(net "FPGA_OUT_SMA4_LED_GREEN_N")
	)
	(segment
		(start 75.05446 -60.2107)
		(end 63.7667 -60.2107)
		(width 0.127)
		(layer "In7.Cu")
		(net "FPGA_OUT_SMA4_LED_GREEN_N")
	)
	(segment
		(start 94.488 -61.849)
		(end 93.98 -62.357)
		(width 0.127)
		(layer "In7.Cu")
		(net "FPGA_OUT_SMA4_LED_GREEN_N")
	)
	(segment
		(start 93.98 -62.357)
		(end 93.98 -62.738)
		(width 0.127)
		(layer "In7.Cu")
		(net "FPGA_OUT_SMA4_LED_GREEN_N")
	)
	(segment
		(start 102.84714 -51.823112)
		(end 102.347268 -52.322984)
		(width 0.11938)
		(layer "F.Cu")
		(net "FPGA_OUT_SMA4_LED_BLUE_N")
	)
	(segment
		(start 22.987 -47.879)
		(end 20.701 -45.593)
		(width 0.11938)
		(layer "F.Cu")
		(net "FPGA_OUT_SMA4_LED_BLUE_N")
	)
	(segment
		(start 20.701 -45.593)
		(end 20.001738 -45.593)
		(width 0.11938)
		(layer "F.Cu")
		(net "FPGA_OUT_SMA4_LED_BLUE_N")
	)
	(via
		(at 102.347268 -52.322984)
		(size 0.4572)
		(drill 0.2032)
		(layers "F.Cu" "B.Cu")
		(net "FPGA_OUT_SMA4_LED_BLUE_N")
	)
	(via
		(at 22.987 -47.879)
		(size 0.508)
		(drill 0.254)
		(layers "F.Cu" "B.Cu")
		(net "FPGA_OUT_SMA4_LED_BLUE_N")
	)
	(segment
		(start 23.749 -50.8)
		(end 23.368 -50.419)
		(width 0.127)
		(layer "In7.Cu")
		(net "FPGA_OUT_SMA4_LED_BLUE_N")
	)
	(segment
		(start 26.0096 -56.6928)
		(end 24.5872 -56.6928)
		(width 0.127)
		(layer "In7.Cu")
		(net "FPGA_OUT_SMA4_LED_BLUE_N")
	)
	(segment
		(start 58.4962 -60.6298)
		(end 29.9466 -60.6298)
		(width 0.127)
		(layer "In7.Cu")
		(net "FPGA_OUT_SMA4_LED_BLUE_N")
	)
	(segment
		(start 77.334872 -63.0301)
		(end 74.896472 -60.5917)
		(width 0.127)
		(layer "In7.Cu")
		(net "FPGA_OUT_SMA4_LED_BLUE_N")
	)
	(segment
		(start 92.71 -64.516)
		(end 88.789002 -64.516)
		(width 0.127)
		(layer "In7.Cu")
		(net "FPGA_OUT_SMA4_LED_BLUE_N")
	)
	(segment
		(start 23.368 -50.419)
		(end 23.368 -49.656746)
		(width 0.127)
		(layer "In7.Cu")
		(net "FPGA_OUT_SMA4_LED_BLUE_N")
	)
	(segment
		(start 100.7745 -59.6265)
		(end 100.076 -60.325)
		(width 0.127)
		(layer "In7.Cu")
		(net "FPGA_OUT_SMA4_LED_BLUE_N")
	)
	(segment
		(start 101.953568 -54.764432)
		(end 100.7745 -55.9435)
		(width 0.127)
		(layer "In7.Cu")
		(net "FPGA_OUT_SMA4_LED_BLUE_N")
	)
	(segment
		(start 100.076 -63.215012)
		(end 99.041712 -64.2493)
		(width 0.127)
		(layer "In7.Cu")
		(net "FPGA_OUT_SMA4_LED_BLUE_N")
	)
	(segment
		(start 93.6625 -65.4685)
		(end 92.71 -64.516)
		(width 0.127)
		(layer "In7.Cu")
		(net "FPGA_OUT_SMA4_LED_BLUE_N")
	)
	(segment
		(start 23.5585 -49.466246)
		(end 23.5585 -48.4505)
		(width 0.127)
		(layer "In7.Cu")
		(net "FPGA_OUT_SMA4_LED_BLUE_N")
	)
	(segment
		(start 101.953568 -52.716684)
		(end 101.953568 -54.764432)
		(width 0.127)
		(layer "In7.Cu")
		(net "FPGA_OUT_SMA4_LED_BLUE_N")
	)
	(segment
		(start 100.076 -60.325)
		(end 100.076 -63.215012)
		(width 0.127)
		(layer "In7.Cu")
		(net "FPGA_OUT_SMA4_LED_BLUE_N")
	)
	(segment
		(start 24.5872 -56.6928)
		(end 23.749 -55.8546)
		(width 0.127)
		(layer "In7.Cu")
		(net "FPGA_OUT_SMA4_LED_BLUE_N")
	)
	(segment
		(start 88.065102 -63.7921)
		(end 83.500976 -63.7921)
		(width 0.127)
		(layer "In7.Cu")
		(net "FPGA_OUT_SMA4_LED_BLUE_N")
	)
	(segment
		(start 97.2947 -64.2493)
		(end 95.758 -65.786)
		(width 0.127)
		(layer "In7.Cu")
		(net "FPGA_OUT_SMA4_LED_BLUE_N")
	)
	(segment
		(start 63.373 -61.7728)
		(end 59.6392 -61.7728)
		(width 0.127)
		(layer "In7.Cu")
		(net "FPGA_OUT_SMA4_LED_BLUE_N")
	)
	(segment
		(start 95.197168 -65.786)
		(end 94.879668 -65.4685)
		(width 0.127)
		(layer "In7.Cu")
		(net "FPGA_OUT_SMA4_LED_BLUE_N")
	)
	(segment
		(start 94.879668 -65.4685)
		(end 93.6625 -65.4685)
		(width 0.127)
		(layer "In7.Cu")
		(net "FPGA_OUT_SMA4_LED_BLUE_N")
	)
	(segment
		(start 29.9466 -60.6298)
		(end 26.0096 -56.6928)
		(width 0.127)
		(layer "In7.Cu")
		(net "FPGA_OUT_SMA4_LED_BLUE_N")
	)
	(segment
		(start 23.749 -55.8546)
		(end 23.749 -50.8)
		(width 0.127)
		(layer "In7.Cu")
		(net "FPGA_OUT_SMA4_LED_BLUE_N")
	)
	(segment
		(start 82.738976 -63.0301)
		(end 77.334872 -63.0301)
		(width 0.127)
		(layer "In7.Cu")
		(net "FPGA_OUT_SMA4_LED_BLUE_N")
	)
	(segment
		(start 100.7745 -55.9435)
		(end 100.7745 -59.6265)
		(width 0.127)
		(layer "In7.Cu")
		(net "FPGA_OUT_SMA4_LED_BLUE_N")
	)
	(segment
		(start 83.500976 -63.7921)
		(end 82.738976 -63.0301)
		(width 0.127)
		(layer "In7.Cu")
		(net "FPGA_OUT_SMA4_LED_BLUE_N")
	)
	(segment
		(start 88.789002 -64.516)
		(end 88.065102 -63.7921)
		(width 0.127)
		(layer "In7.Cu")
		(net "FPGA_OUT_SMA4_LED_BLUE_N")
	)
	(segment
		(start 95.758 -65.786)
		(end 95.197168 -65.786)
		(width 0.127)
		(layer "In7.Cu")
		(net "FPGA_OUT_SMA4_LED_BLUE_N")
	)
	(segment
		(start 23.5585 -48.4505)
		(end 22.987 -47.879)
		(width 0.127)
		(layer "In7.Cu")
		(net "FPGA_OUT_SMA4_LED_BLUE_N")
	)
	(segment
		(start 23.368 -49.656746)
		(end 23.5585 -49.466246)
		(width 0.127)
		(layer "In7.Cu")
		(net "FPGA_OUT_SMA4_LED_BLUE_N")
	)
	(segment
		(start 99.041712 -64.2493)
		(end 97.2947 -64.2493)
		(width 0.127)
		(layer "In7.Cu")
		(net "FPGA_OUT_SMA4_LED_BLUE_N")
	)
	(segment
		(start 59.6392 -61.7728)
		(end 58.4962 -60.6298)
		(width 0.127)
		(layer "In7.Cu")
		(net "FPGA_OUT_SMA4_LED_BLUE_N")
	)
	(segment
		(start 102.347268 -52.322984)
		(end 101.953568 -52.716684)
		(width 0.127)
		(layer "In7.Cu")
		(net "FPGA_OUT_SMA4_LED_BLUE_N")
	)
	(segment
		(start 74.896472 -60.5917)
		(end 64.5541 -60.5917)
		(width 0.127)
		(layer "In7.Cu")
		(net "FPGA_OUT_SMA4_LED_BLUE_N")
	)
	(segment
		(start 64.5541 -60.5917)
		(end 63.373 -61.7728)
		(width 0.127)
		(layer "In7.Cu")
		(net "FPGA_OUT_SMA4_LED_BLUE_N")
	)
	(segment
		(start 100.84689 -50.823114)
		(end 100.347018 -51.322986)
		(width 0.11938)
		(layer "F.Cu")
		(net "FPGA_OUT_SMA3_LED_RED_N")
	)
	(segment
		(start 7.2898 -67.667632)
		(end 7.2898 -66.677032)
		(width 0.11938)
		(layer "F.Cu")
		(net "FPGA_OUT_SMA3_LED_RED_N")
	)
	(via
		(at 100.347018 -51.322986)
		(size 0.4572)
		(drill 0.2032)
		(layers "F.Cu" "B.Cu")
		(net "FPGA_OUT_SMA3_LED_RED_N")
	)
	(via
		(at 7.2898 -66.677032)
		(size 0.508)
		(drill 0.254)
		(layers "F.Cu" "B.Cu")
		(net "FPGA_OUT_SMA3_LED_RED_N")
	)
	(via
		(at 16.002 -54.61)
		(size 0.508)
		(drill 0.254)
		(layers "F.Cu" "B.Cu")
		(net "FPGA_OUT_SMA3_LED_RED_N")
	)
	(via
		(at 25.019 -55.499)
		(size 0.508)
		(drill 0.254)
		(layers "F.Cu" "B.Cu")
		(net "FPGA_OUT_SMA3_LED_RED_N")
	)
	(segment
		(start 24.511 -55.499)
		(end 22.987 -53.975)
		(width 0.11938)
		(layer "B.Cu")
		(net "FPGA_OUT_SMA3_LED_RED_N")
	)
	(segment
		(start 16.637 -53.975)
		(end 16.002 -54.61)
		(width 0.11938)
		(layer "B.Cu")
		(net "FPGA_OUT_SMA3_LED_RED_N")
	)
	(segment
		(start 22.987 -53.975)
		(end 16.637 -53.975)
		(width 0.11938)
		(layer "B.Cu")
		(net "FPGA_OUT_SMA3_LED_RED_N")
	)
	(segment
		(start 25.019 -55.499)
		(end 24.511 -55.499)
		(width 0.11938)
		(layer "B.Cu")
		(net "FPGA_OUT_SMA3_LED_RED_N")
	)
	(segment
		(start 26.040588 -55.499)
		(end 25.019 -55.499)
		(width 0.127)
		(layer "In7.Cu")
		(net "FPGA_OUT_SMA3_LED_RED_N")
	)
	(segment
		(start 89.408 -63.627)
		(end 88.519 -62.738)
		(width 0.127)
		(layer "In7.Cu")
		(net "FPGA_OUT_SMA3_LED_RED_N")
	)
	(segment
		(start 11.303 -59.182)
		(end 11.303 -62.992254)
		(width 0.127)
		(layer "In7.Cu")
		(net "FPGA_OUT_SMA3_LED_RED_N")
	)
	(segment
		(start 79.9211 -61.2521)
		(end 76.634848 -61.2521)
		(width 0.127)
		(layer "In7.Cu")
		(net "FPGA_OUT_SMA3_LED_RED_N")
	)
	(segment
		(start 75.212448 -59.8297)
		(end 30.371288 -59.8297)
		(width 0.127)
		(layer "In7.Cu")
		(net "FPGA_OUT_SMA3_LED_RED_N")
	)
	(segment
		(start 97.155 -61.214)
		(end 94.088204 -61.214)
		(width 0.127)
		(layer "In7.Cu")
		(net "FPGA_OUT_SMA3_LED_RED_N")
	)
	(segment
		(start 94.088204 -61.214)
		(end 93.454982 -61.847222)
		(width 0.127)
		(layer "In7.Cu")
		(net "FPGA_OUT_SMA3_LED_RED_N")
	)
	(segment
		(start 11.303 -62.992254)
		(end 7.618222 -66.677032)
		(width 0.127)
		(layer "In7.Cu")
		(net "FPGA_OUT_SMA3_LED_RED_N")
	)
	(segment
		(start 30.371288 -59.8297)
		(end 26.040588 -55.499)
		(width 0.127)
		(layer "In7.Cu")
		(net "FPGA_OUT_SMA3_LED_RED_N")
	)
	(segment
		(start 99.8728 -55.08498)
		(end 98.552 -56.40578)
		(width 0.127)
		(layer "In7.Cu")
		(net "FPGA_OUT_SMA3_LED_RED_N")
	)
	(segment
		(start 86.891114 -61.7093)
		(end 80.3783 -61.7093)
		(width 0.127)
		(layer "In7.Cu")
		(net "FPGA_OUT_SMA3_LED_RED_N")
	)
	(segment
		(start 15.1765 -55.4355)
		(end 15.1765 -55.735982)
		(width 0.127)
		(layer "In7.Cu")
		(net "FPGA_OUT_SMA3_LED_RED_N")
	)
	(segment
		(start 90.787982 -63.627)
		(end 89.408 -63.627)
		(width 0.127)
		(layer "In7.Cu")
		(net "FPGA_OUT_SMA3_LED_RED_N")
	)
	(segment
		(start 98.552 -56.40578)
		(end 98.552 -59.309)
		(width 0.127)
		(layer "In7.Cu")
		(net "FPGA_OUT_SMA3_LED_RED_N")
	)
	(segment
		(start 16.002 -54.61)
		(end 15.1765 -55.4355)
		(width 0.127)
		(layer "In7.Cu")
		(net "FPGA_OUT_SMA3_LED_RED_N")
	)
	(segment
		(start 93.454982 -61.847222)
		(end 92.56776 -61.847222)
		(width 0.127)
		(layer "In7.Cu")
		(net "FPGA_OUT_SMA3_LED_RED_N")
	)
	(segment
		(start 87.919814 -62.738)
		(end 86.891114 -61.7093)
		(width 0.127)
		(layer "In7.Cu")
		(net "FPGA_OUT_SMA3_LED_RED_N")
	)
	(segment
		(start 88.519 -62.738)
		(end 87.919814 -62.738)
		(width 0.127)
		(layer "In7.Cu")
		(net "FPGA_OUT_SMA3_LED_RED_N")
	)
	(segment
		(start 98.044 -59.817)
		(end 98.044 -60.325)
		(width 0.127)
		(layer "In7.Cu")
		(net "FPGA_OUT_SMA3_LED_RED_N")
	)
	(segment
		(start 76.634848 -61.2521)
		(end 75.212448 -59.8297)
		(width 0.127)
		(layer "In7.Cu")
		(net "FPGA_OUT_SMA3_LED_RED_N")
	)
	(segment
		(start 100.347018 -51.322986)
		(end 99.8728 -51.797204)
		(width 0.127)
		(layer "In7.Cu")
		(net "FPGA_OUT_SMA3_LED_RED_N")
	)
	(segment
		(start 14.651482 -56.261)
		(end 14.224 -56.261)
		(width 0.127)
		(layer "In7.Cu")
		(net "FPGA_OUT_SMA3_LED_RED_N")
	)
	(segment
		(start 98.044 -60.325)
		(end 97.155 -61.214)
		(width 0.127)
		(layer "In7.Cu")
		(net "FPGA_OUT_SMA3_LED_RED_N")
	)
	(segment
		(start 92.56776 -61.847222)
		(end 90.787982 -63.627)
		(width 0.127)
		(layer "In7.Cu")
		(net "FPGA_OUT_SMA3_LED_RED_N")
	)
	(segment
		(start 7.618222 -66.677032)
		(end 7.2898 -66.677032)
		(width 0.127)
		(layer "In7.Cu")
		(net "FPGA_OUT_SMA3_LED_RED_N")
	)
	(segment
		(start 14.224 -56.261)
		(end 11.303 -59.182)
		(width 0.127)
		(layer "In7.Cu")
		(net "FPGA_OUT_SMA3_LED_RED_N")
	)
	(segment
		(start 99.8728 -51.797204)
		(end 99.8728 -55.08498)
		(width 0.127)
		(layer "In7.Cu")
		(net "FPGA_OUT_SMA3_LED_RED_N")
	)
	(segment
		(start 80.3783 -61.7093)
		(end 79.9211 -61.2521)
		(width 0.127)
		(layer "In7.Cu")
		(net "FPGA_OUT_SMA3_LED_RED_N")
	)
	(segment
		(start 98.552 -59.309)
		(end 98.044 -59.817)
		(width 0.127)
		(layer "In7.Cu")
		(net "FPGA_OUT_SMA3_LED_RED_N")
	)
	(segment
		(start 15.1765 -55.735982)
		(end 14.651482 -56.261)
		(width 0.127)
		(layer "In7.Cu")
		(net "FPGA_OUT_SMA3_LED_RED_N")
	)
	(segment
		(start 10.922 -67.056)
		(end 10.7188 -67.2592)
		(width 0.11938)
		(layer "F.Cu")
		(net "FPGA_OUT_SMA3_LED_GREEN_N")
	)
	(segment
		(start 10.922 -64.897)
		(end 10.922 -67.056)
		(width 0.11938)
		(layer "F.Cu")
		(net "FPGA_OUT_SMA3_LED_GREEN_N")
	)
	(segment
		(start 100.347018 -50.322988)
		(end 100.531676 -50.138076)
		(width 0.11938)
		(layer "F.Cu")
		(net "FPGA_OUT_SMA3_LED_GREEN_N")
	)
	(segment
		(start 10.7188 -67.2592)
		(end 10.7188 -67.667632)
		(width 0.11938)
		(layer "F.Cu")
		(net "FPGA_OUT_SMA3_LED_GREEN_N")
	)
	(segment
		(start 100.531676 -50.138076)
		(end 100.84689 -49.823116)
		(width 0.11938)
		(layer "F.Cu")
		(net "FPGA_OUT_SMA3_LED_GREEN_N")
	)
	(via
		(at 100.347018 -50.322988)
		(size 0.4572)
		(drill 0.2032)
		(layers "F.Cu" "B.Cu")
		(net "FPGA_OUT_SMA3_LED_GREEN_N")
	)
	(via
		(at 16.002 -53.467)
		(size 0.508)
		(drill 0.254)
		(layers "F.Cu" "B.Cu")
		(net "FPGA_OUT_SMA3_LED_GREEN_N")
	)
	(via
		(at 25.146 -51.181)
		(size 0.508)
		(drill 0.254)
		(layers "F.Cu" "B.Cu")
		(net "FPGA_OUT_SMA3_LED_GREEN_N")
	)
	(via
		(at 10.922 -64.897)
		(size 0.508)
		(drill 0.254)
		(layers "F.Cu" "B.Cu")
		(net "FPGA_OUT_SMA3_LED_GREEN_N")
	)
	(segment
		(start 24.511 -51.816)
		(end 23.241 -51.816)
		(width 0.11938)
		(layer "B.Cu")
		(net "FPGA_OUT_SMA3_LED_GREEN_N")
	)
	(segment
		(start 23.241 -51.816)
		(end 21.59 -53.467)
		(width 0.11938)
		(layer "B.Cu")
		(net "FPGA_OUT_SMA3_LED_GREEN_N")
	)
	(segment
		(start 25.146 -51.181)
		(end 24.511 -51.816)
		(width 0.11938)
		(layer "B.Cu")
		(net "FPGA_OUT_SMA3_LED_GREEN_N")
	)
	(segment
		(start 21.59 -53.467)
		(end 16.002 -53.467)
		(width 0.11938)
		(layer "B.Cu")
		(net "FPGA_OUT_SMA3_LED_GREEN_N")
	)
	(segment
		(start 96.1009 -58.3311)
		(end 96.52 -57.912)
		(width 0.127)
		(layer "In7.Cu")
		(net "FPGA_OUT_SMA3_LED_GREEN_N")
	)
	(segment
		(start 14.478 -56.642)
		(end 14.80947 -56.642)
		(width 0.127)
		(layer "In7.Cu")
		(net "FPGA_OUT_SMA3_LED_GREEN_N")
	)
	(segment
		(start 11.684 -64.135)
		(end 11.684 -59.436)
		(width 0.127)
		(layer "In7.Cu")
		(net "FPGA_OUT_SMA3_LED_GREEN_N")
	)
	(segment
		(start 96.52 -57.912)
		(end 96.52 -55.245)
		(width 0.127)
		(layer "In7.Cu")
		(net "FPGA_OUT_SMA3_LED_GREEN_N")
	)
	(segment
		(start 99.72167 -50.322988)
		(end 100.347018 -50.322988)
		(width 0.127)
		(layer "In7.Cu")
		(net "FPGA_OUT_SMA3_LED_GREEN_N")
	)
	(segment
		(start 82.423 -58.547)
		(end 82.677 -58.293)
		(width 0.127)
		(layer "In7.Cu")
		(net "FPGA_OUT_SMA3_LED_GREEN_N")
	)
	(segment
		(start 89.9541 -58.3311)
		(end 96.1009 -58.3311)
		(width 0.127)
		(layer "In7.Cu")
		(net "FPGA_OUT_SMA3_LED_GREEN_N")
	)
	(segment
		(start 80.645 -58.547)
		(end 82.423 -58.547)
		(width 0.127)
		(layer "In7.Cu")
		(net "FPGA_OUT_SMA3_LED_GREEN_N")
	)
	(segment
		(start 79.9211 -57.8231)
		(end 80.645 -58.547)
		(width 0.127)
		(layer "In7.Cu")
		(net "FPGA_OUT_SMA3_LED_GREEN_N")
	)
	(segment
		(start 97.742756 -54.022244)
		(end 97.742756 -53.075586)
		(width 0.127)
		(layer "In7.Cu")
		(net "FPGA_OUT_SMA3_LED_GREEN_N")
	)
	(segment
		(start 16.637 -54.81447)
		(end 16.637 -54.102)
		(width 0.127)
		(layer "In7.Cu")
		(net "FPGA_OUT_SMA3_LED_GREEN_N")
	)
	(segment
		(start 10.922 -64.897)
		(end 11.684 -64.135)
		(width 0.127)
		(layer "In7.Cu")
		(net "FPGA_OUT_SMA3_LED_GREEN_N")
	)
	(segment
		(start 78.3463 -58.3057)
		(end 78.8289 -57.8231)
		(width 0.127)
		(layer "In7.Cu")
		(net "FPGA_OUT_SMA3_LED_GREEN_N")
	)
	(segment
		(start 96.52 -55.245)
		(end 97.742756 -54.022244)
		(width 0.127)
		(layer "In7.Cu")
		(net "FPGA_OUT_SMA3_LED_GREEN_N")
	)
	(segment
		(start 82.677 -58.293)
		(end 85.0265 -58.293)
		(width 0.127)
		(layer "In7.Cu")
		(net "FPGA_OUT_SMA3_LED_GREEN_N")
	)
	(segment
		(start 89.2175 -57.5945)
		(end 89.9541 -58.3311)
		(width 0.127)
		(layer "In7.Cu")
		(net "FPGA_OUT_SMA3_LED_GREEN_N")
	)
	(segment
		(start 14.80947 -56.642)
		(end 16.637 -54.81447)
		(width 0.127)
		(layer "In7.Cu")
		(net "FPGA_OUT_SMA3_LED_GREEN_N")
	)
	(segment
		(start 11.684 -59.436)
		(end 14.478 -56.642)
		(width 0.127)
		(layer "In7.Cu")
		(net "FPGA_OUT_SMA3_LED_GREEN_N")
	)
	(segment
		(start 16.637 -54.102)
		(end 16.002 -53.467)
		(width 0.127)
		(layer "In7.Cu")
		(net "FPGA_OUT_SMA3_LED_GREEN_N")
	)
	(segment
		(start 98.6282 -51.416458)
		(end 99.72167 -50.322988)
		(width 0.127)
		(layer "In7.Cu")
		(net "FPGA_OUT_SMA3_LED_GREEN_N")
	)
	(segment
		(start 98.6282 -52.190142)
		(end 98.6282 -51.416458)
		(width 0.127)
		(layer "In7.Cu")
		(net "FPGA_OUT_SMA3_LED_GREEN_N")
	)
	(segment
		(start 78.8289 -57.8231)
		(end 79.9211 -57.8231)
		(width 0.127)
		(layer "In7.Cu")
		(net "FPGA_OUT_SMA3_LED_GREEN_N")
	)
	(segment
		(start 97.742756 -53.075586)
		(end 98.6282 -52.190142)
		(width 0.127)
		(layer "In7.Cu")
		(net "FPGA_OUT_SMA3_LED_GREEN_N")
	)
	(segment
		(start 31.8897 -58.3057)
		(end 78.3463 -58.3057)
		(width 0.127)
		(layer "In7.Cu")
		(net "FPGA_OUT_SMA3_LED_GREEN_N")
	)
	(segment
		(start 85.725 -57.5945)
		(end 89.2175 -57.5945)
		(width 0.127)
		(layer "In7.Cu")
		(net "FPGA_OUT_SMA3_LED_GREEN_N")
	)
	(segment
		(start 25.146 -51.562)
		(end 31.8897 -58.3057)
		(width 0.127)
		(layer "In7.Cu")
		(net "FPGA_OUT_SMA3_LED_GREEN_N")
	)
	(segment
		(start 85.0265 -58.293)
		(end 85.725 -57.5945)
		(width 0.127)
		(layer "In7.Cu")
		(net "FPGA_OUT_SMA3_LED_GREEN_N")
	)
	(segment
		(start 25.146 -51.181)
		(end 25.146 -51.562)
		(width 0.127)
		(layer "In7.Cu")
		(net "FPGA_OUT_SMA3_LED_GREEN_N")
	)
	(segment
		(start 101.847142 -49.823116)
		(end 101.34727 -50.322988)
		(width 0.11938)
		(layer "F.Cu")
		(net "FPGA_OUT_SMA3_LED_BLUE_N")
	)
	(segment
		(start 6.1468 -67.667632)
		(end 6.1468 -66.677032)
		(width 0.11938)
		(layer "F.Cu")
		(net "FPGA_OUT_SMA3_LED_BLUE_N")
	)
	(via
		(at 25.146 -50.165)
		(size 0.508)
		(drill 0.254)
		(layers "F.Cu" "B.Cu")
		(net "FPGA_OUT_SMA3_LED_BLUE_N")
	)
	(via
		(at 16.002 -52.324)
		(size 0.508)
		(drill 0.254)
		(layers "F.Cu" "B.Cu")
		(net "FPGA_OUT_SMA3_LED_BLUE_N")
	)
	(via
		(at 101.34727 -50.322988)
		(size 0.4572)
		(drill 0.2032)
		(layers "F.Cu" "B.Cu")
		(net "FPGA_OUT_SMA3_LED_BLUE_N")
	)
	(via
		(at 6.1468 -66.677032)
		(size 0.508)
		(drill 0.254)
		(layers "F.Cu" "B.Cu")
		(net "FPGA_OUT_SMA3_LED_BLUE_N")
	)
	(segment
		(start 25.146 -50.165)
		(end 24.003 -51.308)
		(width 0.11938)
		(layer "B.Cu")
		(net "FPGA_OUT_SMA3_LED_BLUE_N")
	)
	(segment
		(start 24.003 -51.308)
		(end 22.86 -51.308)
		(width 0.11938)
		(layer "B.Cu")
		(net "FPGA_OUT_SMA3_LED_BLUE_N")
	)
	(segment
		(start 21.844 -52.324)
		(end 16.002 -52.324)
		(width 0.11938)
		(layer "B.Cu")
		(net "FPGA_OUT_SMA3_LED_BLUE_N")
	)
	(segment
		(start 22.86 -51.308)
		(end 21.844 -52.324)
		(width 0.11938)
		(layer "B.Cu")
		(net "FPGA_OUT_SMA3_LED_BLUE_N")
	)
	(segment
		(start 16.002 -52.324)
		(end 15.367 -52.959)
		(width 0.127)
		(layer "In7.Cu")
		(net "FPGA_OUT_SMA3_LED_BLUE_N")
	)
	(segment
		(start 84.963 -59.944)
		(end 85.7885 -60.7695)
		(width 0.127)
		(layer "In7.Cu")
		(net "FPGA_OUT_SMA3_LED_BLUE_N")
	)
	(segment
		(start 76.950824 -60.4901)
		(end 82.638646 -60.4901)
		(width 0.127)
		(layer "In7.Cu")
		(net "FPGA_OUT_SMA3_LED_BLUE_N")
	)
	(segment
		(start 13.843 -54.991)
		(end 13.843 -56.007)
		(width 0.127)
		(layer "In7.Cu")
		(net "FPGA_OUT_SMA3_LED_BLUE_N")
	)
	(segment
		(start 6.783832 -66.04)
		(end 6.1468 -66.677032)
		(width 0.127)
		(layer "In7.Cu")
		(net "FPGA_OUT_SMA3_LED_BLUE_N")
	)
	(segment
		(start 89.54897 -61.1505)
		(end 90.12047 -60.579)
		(width 0.127)
		(layer "In7.Cu")
		(net "FPGA_OUT_SMA3_LED_BLUE_N")
	)
	(segment
		(start 98.89744 -53.75656)
		(end 98.89744 -51.83378)
		(width 0.127)
		(layer "In7.Cu")
		(net "FPGA_OUT_SMA3_LED_BLUE_N")
	)
	(segment
		(start 97.282 -58.231024)
		(end 97.282 -55.372)
		(width 0.127)
		(layer "In7.Cu")
		(net "FPGA_OUT_SMA3_LED_BLUE_N")
	)
	(segment
		(start 10.795 -56.515)
		(end 9.017 -58.293)
		(width 0.127)
		(layer "In7.Cu")
		(net "FPGA_OUT_SMA3_LED_BLUE_N")
	)
	(segment
		(start 24.511 -52.705)
		(end 30.8737 -59.0677)
		(width 0.127)
		(layer "In7.Cu")
		(net "FPGA_OUT_SMA3_LED_BLUE_N")
	)
	(segment
		(start 85.7885 -60.7695)
		(end 88.37803 -60.7695)
		(width 0.127)
		(layer "In7.Cu")
		(net "FPGA_OUT_SMA3_LED_BLUE_N")
	)
	(segment
		(start 100.814378 -50.85588)
		(end 101.34727 -50.322988)
		(width 0.1016)
		(layer "In7.Cu")
		(net "FPGA_OUT_SMA3_LED_BLUE_N")
	)
	(segment
		(start 88.37803 -60.7695)
		(end 88.75903 -61.1505)
		(width 0.127)
		(layer "In7.Cu")
		(net "FPGA_OUT_SMA3_LED_BLUE_N")
	)
	(segment
		(start 24.511 -50.8)
		(end 24.511 -52.705)
		(width 0.127)
		(layer "In7.Cu")
		(net "FPGA_OUT_SMA3_LED_BLUE_N")
	)
	(segment
		(start 30.8737 -59.0677)
		(end 75.528424 -59.0677)
		(width 0.127)
		(layer "In7.Cu")
		(net "FPGA_OUT_SMA3_LED_BLUE_N")
	)
	(segment
		(start 13.843 -56.007)
		(end 13.335 -56.515)
		(width 0.127)
		(layer "In7.Cu")
		(net "FPGA_OUT_SMA3_LED_BLUE_N")
	)
	(segment
		(start 15.367 -54.483)
		(end 14.986 -54.864)
		(width 0.127)
		(layer "In7.Cu")
		(net "FPGA_OUT_SMA3_LED_BLUE_N")
	)
	(segment
		(start 92.537534 -59.942222)
		(end 95.570802 -59.942222)
		(width 0.127)
		(layer "In7.Cu")
		(net "FPGA_OUT_SMA3_LED_BLUE_N")
	)
	(segment
		(start 90.12047 -60.579)
		(end 91.900756 -60.579)
		(width 0.127)
		(layer "In7.Cu")
		(net "FPGA_OUT_SMA3_LED_BLUE_N")
	)
	(segment
		(start 14.986 -54.864)
		(end 13.97 -54.864)
		(width 0.127)
		(layer "In7.Cu")
		(net "FPGA_OUT_SMA3_LED_BLUE_N")
	)
	(segment
		(start 82.638646 -60.4901)
		(end 83.184746 -59.944)
		(width 0.127)
		(layer "In7.Cu")
		(net "FPGA_OUT_SMA3_LED_BLUE_N")
	)
	(segment
		(start 99.87534 -50.85588)
		(end 100.814378 -50.85588)
		(width 0.1016)
		(layer "In7.Cu")
		(net "FPGA_OUT_SMA3_LED_BLUE_N")
	)
	(segment
		(start 88.75903 -61.1505)
		(end 89.54897 -61.1505)
		(width 0.127)
		(layer "In7.Cu")
		(net "FPGA_OUT_SMA3_LED_BLUE_N")
	)
	(segment
		(start 13.97 -54.864)
		(end 13.843 -54.991)
		(width 0.127)
		(layer "In7.Cu")
		(net "FPGA_OUT_SMA3_LED_BLUE_N")
	)
	(segment
		(start 83.184746 -59.944)
		(end 84.963 -59.944)
		(width 0.127)
		(layer "In7.Cu")
		(net "FPGA_OUT_SMA3_LED_BLUE_N")
	)
	(segment
		(start 9.017 -64.739266)
		(end 7.716266 -66.04)
		(width 0.127)
		(layer "In7.Cu")
		(net "FPGA_OUT_SMA3_LED_BLUE_N")
	)
	(segment
		(start 15.367 -52.959)
		(end 15.367 -54.483)
		(width 0.127)
		(layer "In7.Cu")
		(net "FPGA_OUT_SMA3_LED_BLUE_N")
	)
	(segment
		(start 13.335 -56.515)
		(end 10.795 -56.515)
		(width 0.127)
		(layer "In7.Cu")
		(net "FPGA_OUT_SMA3_LED_BLUE_N")
	)
	(segment
		(start 98.89744 -51.83378)
		(end 99.87534 -50.85588)
		(width 0.127)
		(layer "In7.Cu")
		(net "FPGA_OUT_SMA3_LED_BLUE_N")
	)
	(segment
		(start 91.900756 -60.579)
		(end 92.537534 -59.942222)
		(width 0.127)
		(layer "In7.Cu")
		(net "FPGA_OUT_SMA3_LED_BLUE_N")
	)
	(segment
		(start 25.146 -50.165)
		(end 24.511 -50.8)
		(width 0.127)
		(layer "In7.Cu")
		(net "FPGA_OUT_SMA3_LED_BLUE_N")
	)
	(segment
		(start 7.716266 -66.04)
		(end 6.783832 -66.04)
		(width 0.127)
		(layer "In7.Cu")
		(net "FPGA_OUT_SMA3_LED_BLUE_N")
	)
	(segment
		(start 9.017 -58.293)
		(end 9.017 -64.739266)
		(width 0.127)
		(layer "In7.Cu")
		(net "FPGA_OUT_SMA3_LED_BLUE_N")
	)
	(segment
		(start 97.282 -55.372)
		(end 98.89744 -53.75656)
		(width 0.127)
		(layer "In7.Cu")
		(net "FPGA_OUT_SMA3_LED_BLUE_N")
	)
	(segment
		(start 95.570802 -59.942222)
		(end 97.282 -58.231024)
		(width 0.127)
		(layer "In7.Cu")
		(net "FPGA_OUT_SMA3_LED_BLUE_N")
	)
	(segment
		(start 75.528424 -59.0677)
		(end 76.950824 -60.4901)
		(width 0.127)
		(layer "In7.Cu")
		(net "FPGA_OUT_SMA3_LED_BLUE_N")
	)
	(segment
		(start 102.347268 -46.322996)
		(end 102.84714 -45.823124)
		(width 0.11938)
		(layer "F.Cu")
		(net "FPGA_OUT_SMA2_LED_RED_N")
	)
	(segment
		(start 23.114 -32.385)
		(end 23.114 -30.607)
		(width 0.11938)
		(layer "F.Cu")
		(net "FPGA_OUT_SMA2_LED_RED_N")
	)
	(segment
		(start 23.749 -33.02)
		(end 23.114 -32.385)
		(width 0.11938)
		(layer "F.Cu")
		(net "FPGA_OUT_SMA2_LED_RED_N")
	)
	(segment
		(start 23.114 -30.607)
		(end 21.717 -29.21)
		(width 0.11938)
		(layer "F.Cu")
		(net "FPGA_OUT_SMA2_LED_RED_N")
	)
	(segment
		(start 21.717 -29.21)
		(end 20.8534 -29.21)
		(width 0.11938)
		(layer "F.Cu")
		(net "FPGA_OUT_SMA2_LED_RED_N")
	)
	(via
		(at 23.749 -33.02)
		(size 0.508)
		(drill 0.254)
		(layers "F.Cu" "B.Cu")
		(net "FPGA_OUT_SMA2_LED_RED_N")
	)
	(via
		(at 102.347268 -46.322996)
		(size 0.4572)
		(drill 0.2032)
		(layers "F.Cu" "B.Cu")
		(net "FPGA_OUT_SMA2_LED_RED_N")
	)
	(segment
		(start 75.819 -51.435)
		(end 75.184 -52.07)
		(width 0.127)
		(layer "In7.Cu")
		(net "FPGA_OUT_SMA2_LED_RED_N")
	)
	(segment
		(start 24.5364 -39.5732)
		(end 23.8506 -40.259)
		(width 0.127)
		(layer "In7.Cu")
		(net "FPGA_OUT_SMA2_LED_RED_N")
	)
	(segment
		(start 63.373 -51.435)
		(end 62.6872 -50.7492)
		(width 0.127)
		(layer "In7.Cu")
		(net "FPGA_OUT_SMA2_LED_RED_N")
	)
	(segment
		(start 23.8506 -40.259)
		(end 22.559772 -40.259)
		(width 0.127)
		(layer "In7.Cu")
		(net "FPGA_OUT_SMA2_LED_RED_N")
	)
	(segment
		(start 78.872588 -50.8635)
		(end 77.851 -50.8635)
		(width 0.127)
		(layer "In7.Cu")
		(net "FPGA_OUT_SMA2_LED_RED_N")
	)
	(segment
		(start 93.30944 -50.624486)
		(end 90.91549 -50.624486)
		(width 0.127)
		(layer "In7.Cu")
		(net "FPGA_OUT_SMA2_LED_RED_N")
	)
	(segment
		(start 21.0185 -36.0045)
		(end 23.749 -33.274)
		(width 0.127)
		(layer "In7.Cu")
		(net "FPGA_OUT_SMA2_LED_RED_N")
	)
	(segment
		(start 62.6872 -50.7492)
		(end 62.6618 -50.7492)
		(width 0.127)
		(layer "In7.Cu")
		(net "FPGA_OUT_SMA2_LED_RED_N")
	)
	(segment
		(start 77.2795 -51.435)
		(end 75.819 -51.435)
		(width 0.127)
		(layer "In7.Cu")
		(net "FPGA_OUT_SMA2_LED_RED_N")
	)
	(segment
		(start 90.91549 -50.624486)
		(end 90.270076 -51.2699)
		(width 0.127)
		(layer "In7.Cu")
		(net "FPGA_OUT_SMA2_LED_RED_N")
	)
	(segment
		(start 97.822004 -46.703996)
		(end 97.22993 -46.703996)
		(width 0.127)
		(layer "In7.Cu")
		(net "FPGA_OUT_SMA2_LED_RED_N")
	)
	(segment
		(start 62.6618 -50.7492)
		(end 51.4858 -39.5732)
		(width 0.127)
		(layer "In7.Cu")
		(net "FPGA_OUT_SMA2_LED_RED_N")
	)
	(segment
		(start 102.347268 -46.322996)
		(end 101.966268 -46.703996)
		(width 0.1016)
		(layer "In7.Cu")
		(net "FPGA_OUT_SMA2_LED_RED_N")
	)
	(segment
		(start 101.966268 -46.703996)
		(end 97.822004 -46.703996)
		(width 0.1016)
		(layer "In7.Cu")
		(net "FPGA_OUT_SMA2_LED_RED_N")
	)
	(segment
		(start 97.22993 -46.703996)
		(end 93.30944 -50.624486)
		(width 0.127)
		(layer "In7.Cu")
		(net "FPGA_OUT_SMA2_LED_RED_N")
	)
	(segment
		(start 66.929 -52.07)
		(end 66.294 -51.435)
		(width 0.127)
		(layer "In7.Cu")
		(net "FPGA_OUT_SMA2_LED_RED_N")
	)
	(segment
		(start 23.749 -33.274)
		(end 23.749 -33.02)
		(width 0.127)
		(layer "In7.Cu")
		(net "FPGA_OUT_SMA2_LED_RED_N")
	)
	(segment
		(start 75.184 -52.07)
		(end 66.929 -52.07)
		(width 0.127)
		(layer "In7.Cu")
		(net "FPGA_OUT_SMA2_LED_RED_N")
	)
	(segment
		(start 79.278988 -51.2699)
		(end 78.872588 -50.8635)
		(width 0.127)
		(layer "In7.Cu")
		(net "FPGA_OUT_SMA2_LED_RED_N")
	)
	(segment
		(start 77.851 -50.8635)
		(end 77.2795 -51.435)
		(width 0.127)
		(layer "In7.Cu")
		(net "FPGA_OUT_SMA2_LED_RED_N")
	)
	(segment
		(start 51.4858 -39.5732)
		(end 24.5364 -39.5732)
		(width 0.127)
		(layer "In7.Cu")
		(net "FPGA_OUT_SMA2_LED_RED_N")
	)
	(segment
		(start 90.270076 -51.2699)
		(end 79.278988 -51.2699)
		(width 0.127)
		(layer "In7.Cu")
		(net "FPGA_OUT_SMA2_LED_RED_N")
	)
	(segment
		(start 21.0185 -38.717728)
		(end 21.0185 -36.0045)
		(width 0.127)
		(layer "In7.Cu")
		(net "FPGA_OUT_SMA2_LED_RED_N")
	)
	(segment
		(start 66.294 -51.435)
		(end 63.373 -51.435)
		(width 0.127)
		(layer "In7.Cu")
		(net "FPGA_OUT_SMA2_LED_RED_N")
	)
	(segment
		(start 22.559772 -40.259)
		(end 21.0185 -38.717728)
		(width 0.127)
		(layer "In7.Cu")
		(net "FPGA_OUT_SMA2_LED_RED_N")
	)
	(segment
		(start 100.84689 -47.82312)
		(end 100.347018 -48.322992)
		(width 0.11938)
		(layer "F.Cu")
		(net "FPGA_OUT_SMA2_LED_GREEN_N")
	)
	(segment
		(start 20.8534 -31.75)
		(end 21.971 -31.75)
		(width 0.11938)
		(layer "F.Cu")
		(net "FPGA_OUT_SMA2_LED_GREEN_N")
	)
	(segment
		(start 21.971 -31.75)
		(end 22.098 -31.877)
		(width 0.11938)
		(layer "F.Cu")
		(net "FPGA_OUT_SMA2_LED_GREEN_N")
	)
	(via
		(at 100.347018 -48.322992)
		(size 0.4572)
		(drill 0.2032)
		(layers "F.Cu" "B.Cu")
		(net "FPGA_OUT_SMA2_LED_GREEN_N")
	)
	(via
		(at 22.098 -31.877)
		(size 0.508)
		(drill 0.254)
		(layers "F.Cu" "B.Cu")
		(net "FPGA_OUT_SMA2_LED_GREEN_N")
	)
	(segment
		(start 91.060016 -53.1749)
		(end 91.656916 -52.578)
		(width 0.127)
		(layer "In7.Cu")
		(net "FPGA_OUT_SMA2_LED_GREEN_N")
	)
	(segment
		(start 100.109274 -48.322992)
		(end 100.347018 -48.322992)
		(width 0.127)
		(layer "In7.Cu")
		(net "FPGA_OUT_SMA2_LED_GREEN_N")
	)
	(segment
		(start 91.656916 -52.578)
		(end 94.05112 -52.578)
		(width 0.127)
		(layer "In7.Cu")
		(net "FPGA_OUT_SMA2_LED_GREEN_N")
	)
	(segment
		(start 20.066 -40.040814)
		(end 23.078186 -43.053)
		(width 0.127)
		(layer "In7.Cu")
		(net "FPGA_OUT_SMA2_LED_GREEN_N")
	)
	(segment
		(start 21.971 -31.877)
		(end 20.066 -33.782)
		(width 0.127)
		(layer "In7.Cu")
		(net "FPGA_OUT_SMA2_LED_GREEN_N")
	)
	(segment
		(start 97.88652 -48.7426)
		(end 99.689666 -48.7426)
		(width 0.127)
		(layer "In7.Cu")
		(net "FPGA_OUT_SMA2_LED_GREEN_N")
	)
	(segment
		(start 65.0875 -53.5305)
		(end 65.532 -53.975)
		(width 0.127)
		(layer "In7.Cu")
		(net "FPGA_OUT_SMA2_LED_GREEN_N")
	)
	(segment
		(start 51.7525 -43.053)
		(end 62.23 -53.5305)
		(width 0.127)
		(layer "In7.Cu")
		(net "FPGA_OUT_SMA2_LED_GREEN_N")
	)
	(segment
		(start 76.3905 -53.975)
		(end 76.835 -53.5305)
		(width 0.127)
		(layer "In7.Cu")
		(net "FPGA_OUT_SMA2_LED_GREEN_N")
	)
	(segment
		(start 99.689666 -48.7426)
		(end 100.109274 -48.322992)
		(width 0.127)
		(layer "In7.Cu")
		(net "FPGA_OUT_SMA2_LED_GREEN_N")
	)
	(segment
		(start 94.05112 -52.578)
		(end 97.88652 -48.7426)
		(width 0.127)
		(layer "In7.Cu")
		(net "FPGA_OUT_SMA2_LED_GREEN_N")
	)
	(segment
		(start 23.078186 -43.053)
		(end 51.7525 -43.053)
		(width 0.127)
		(layer "In7.Cu")
		(net "FPGA_OUT_SMA2_LED_GREEN_N")
	)
	(segment
		(start 82.142076 -53.1749)
		(end 91.060016 -53.1749)
		(width 0.127)
		(layer "In7.Cu")
		(net "FPGA_OUT_SMA2_LED_GREEN_N")
	)
	(segment
		(start 62.23 -53.5305)
		(end 65.0875 -53.5305)
		(width 0.127)
		(layer "In7.Cu")
		(net "FPGA_OUT_SMA2_LED_GREEN_N")
	)
	(segment
		(start 22.098 -31.877)
		(end 21.971 -31.877)
		(width 0.127)
		(layer "In7.Cu")
		(net "FPGA_OUT_SMA2_LED_GREEN_N")
	)
	(segment
		(start 20.066 -33.782)
		(end 20.066 -40.040814)
		(width 0.127)
		(layer "In7.Cu")
		(net "FPGA_OUT_SMA2_LED_GREEN_N")
	)
	(segment
		(start 81.786476 -53.5305)
		(end 82.142076 -53.1749)
		(width 0.127)
		(layer "In7.Cu")
		(net "FPGA_OUT_SMA2_LED_GREEN_N")
	)
	(segment
		(start 76.835 -53.5305)
		(end 81.786476 -53.5305)
		(width 0.127)
		(layer "In7.Cu")
		(net "FPGA_OUT_SMA2_LED_GREEN_N")
	)
	(segment
		(start 65.532 -53.975)
		(end 76.3905 -53.975)
		(width 0.127)
		(layer "In7.Cu")
		(net "FPGA_OUT_SMA2_LED_GREEN_N")
	)
	(segment
		(start 21.336 -27.94)
		(end 20.8534 -27.94)
		(width 0.11938)
		(layer "F.Cu")
		(net "FPGA_OUT_SMA2_LED_BLUE_N")
	)
	(segment
		(start 23.749 -31.75)
		(end 23.749 -30.353)
		(width 0.11938)
		(layer "F.Cu")
		(net "FPGA_OUT_SMA2_LED_BLUE_N")
	)
	(segment
		(start 23.749 -30.353)
		(end 21.336 -27.94)
		(width 0.11938)
		(layer "F.Cu")
		(net "FPGA_OUT_SMA2_LED_BLUE_N")
	)
	(segment
		(start 100.84689 -46.823122)
		(end 100.347018 -47.322994)
		(width 0.11938)
		(layer "F.Cu")
		(net "FPGA_OUT_SMA2_LED_BLUE_N")
	)
	(via
		(at 23.749 -31.75)
		(size 0.508)
		(drill 0.254)
		(layers "F.Cu" "B.Cu")
		(net "FPGA_OUT_SMA2_LED_BLUE_N")
	)
	(via
		(at 100.347018 -47.322994)
		(size 0.4572)
		(drill 0.2032)
		(layers "F.Cu" "B.Cu")
		(net "FPGA_OUT_SMA2_LED_BLUE_N")
	)
	(segment
		(start 51.576224 -40.7416)
		(end 63.222124 -52.3875)
		(width 0.127)
		(layer "In7.Cu")
		(net "FPGA_OUT_SMA2_LED_BLUE_N")
	)
	(segment
		(start 65.8495 -52.3875)
		(end 66.294 -52.832)
		(width 0.127)
		(layer "In7.Cu")
		(net "FPGA_OUT_SMA2_LED_BLUE_N")
	)
	(segment
		(start 99.52482 -47.74184)
		(end 99.943666 -47.322994)
		(width 0.1016)
		(layer "In7.Cu")
		(net "FPGA_OUT_SMA2_LED_BLUE_N")
	)
	(segment
		(start 24.598122 -41.148)
		(end 25.908 -41.148)
		(width 0.127)
		(layer "In7.Cu")
		(net "FPGA_OUT_SMA2_LED_BLUE_N")
	)
	(segment
		(start 20.574 -35.687)
		(end 20.574 -38.812216)
		(width 0.127)
		(layer "In7.Cu")
		(net "FPGA_OUT_SMA2_LED_BLUE_N")
	)
	(segment
		(start 76.1365 -52.3875)
		(end 81.2165 -52.3875)
		(width 0.127)
		(layer "In7.Cu")
		(net "FPGA_OUT_SMA2_LED_BLUE_N")
	)
	(segment
		(start 24.191722 -40.7416)
		(end 24.598122 -41.148)
		(width 0.127)
		(layer "In7.Cu")
		(net "FPGA_OUT_SMA2_LED_BLUE_N")
	)
	(segment
		(start 93.62567 -51.386486)
		(end 97.270316 -47.74184)
		(width 0.127)
		(layer "In7.Cu")
		(net "FPGA_OUT_SMA2_LED_BLUE_N")
	)
	(segment
		(start 97.270316 -47.74184)
		(end 98.015552 -47.74184)
		(width 0.127)
		(layer "In7.Cu")
		(net "FPGA_OUT_SMA2_LED_BLUE_N")
	)
	(segment
		(start 99.943666 -47.322994)
		(end 100.347018 -47.322994)
		(width 0.1016)
		(layer "In7.Cu")
		(net "FPGA_OUT_SMA2_LED_BLUE_N")
	)
	(segment
		(start 75.692 -52.832)
		(end 76.1365 -52.3875)
		(width 0.127)
		(layer "In7.Cu")
		(net "FPGA_OUT_SMA2_LED_BLUE_N")
	)
	(segment
		(start 25.908 -41.148)
		(end 26.3144 -40.7416)
		(width 0.127)
		(layer "In7.Cu")
		(net "FPGA_OUT_SMA2_LED_BLUE_N")
	)
	(segment
		(start 91.231466 -51.386486)
		(end 93.62567 -51.386486)
		(width 0.127)
		(layer "In7.Cu")
		(net "FPGA_OUT_SMA2_LED_BLUE_N")
	)
	(segment
		(start 22.503384 -40.7416)
		(end 24.191722 -40.7416)
		(width 0.127)
		(layer "In7.Cu")
		(net "FPGA_OUT_SMA2_LED_BLUE_N")
	)
	(segment
		(start 26.3144 -40.7416)
		(end 51.576224 -40.7416)
		(width 0.127)
		(layer "In7.Cu")
		(net "FPGA_OUT_SMA2_LED_BLUE_N")
	)
	(segment
		(start 66.294 -52.832)
		(end 75.692 -52.832)
		(width 0.127)
		(layer "In7.Cu")
		(net "FPGA_OUT_SMA2_LED_BLUE_N")
	)
	(segment
		(start 22.86 -33.401)
		(end 20.574 -35.687)
		(width 0.127)
		(layer "In7.Cu")
		(net "FPGA_OUT_SMA2_LED_BLUE_N")
	)
	(segment
		(start 90.586052 -52.0319)
		(end 91.231466 -51.386486)
		(width 0.127)
		(layer "In7.Cu")
		(net "FPGA_OUT_SMA2_LED_BLUE_N")
	)
	(segment
		(start 22.86 -32.639)
		(end 22.86 -33.401)
		(width 0.127)
		(layer "In7.Cu")
		(net "FPGA_OUT_SMA2_LED_BLUE_N")
	)
	(segment
		(start 20.574 -38.812216)
		(end 22.503384 -40.7416)
		(width 0.127)
		(layer "In7.Cu")
		(net "FPGA_OUT_SMA2_LED_BLUE_N")
	)
	(segment
		(start 81.5721 -52.0319)
		(end 90.586052 -52.0319)
		(width 0.127)
		(layer "In7.Cu")
		(net "FPGA_OUT_SMA2_LED_BLUE_N")
	)
	(segment
		(start 63.222124 -52.3875)
		(end 65.8495 -52.3875)
		(width 0.127)
		(layer "In7.Cu")
		(net "FPGA_OUT_SMA2_LED_BLUE_N")
	)
	(segment
		(start 98.015552 -47.74184)
		(end 99.52482 -47.74184)
		(width 0.1016)
		(layer "In7.Cu")
		(net "FPGA_OUT_SMA2_LED_BLUE_N")
	)
	(segment
		(start 81.2165 -52.3875)
		(end 81.5721 -52.0319)
		(width 0.127)
		(layer "In7.Cu")
		(net "FPGA_OUT_SMA2_LED_BLUE_N")
	)
	(segment
		(start 23.749 -31.75)
		(end 22.86 -32.639)
		(width 0.127)
		(layer "In7.Cu")
		(net "FPGA_OUT_SMA2_LED_BLUE_N")
	)
	(segment
		(start 103.847138 -48.823118)
		(end 103.347266 -49.32299)
		(width 0.11938)
		(layer "F.Cu")
		(net "FPGA_OUT_SMA1_LED_RED_N")
	)
	(segment
		(start 7.1374 -38.785292)
		(end 7.1374 -37.794692)
		(width 0.11938)
		(layer "F.Cu")
		(net "FPGA_OUT_SMA1_LED_RED_N")
	)
	(via
		(at 23.368 -43.942)
		(size 0.508)
		(drill 0.254)
		(layers "F.Cu" "B.Cu")
		(net "FPGA_OUT_SMA1_LED_RED_N")
	)
	(via
		(at 7.1374 -37.794692)
		(size 0.508)
		(drill 0.254)
		(layers "F.Cu" "B.Cu")
		(net "FPGA_OUT_SMA1_LED_RED_N")
	)
	(via
		(at 103.347266 -49.32299)
		(size 0.4572)
		(drill 0.2032)
		(layers "F.Cu" "B.Cu")
		(net "FPGA_OUT_SMA1_LED_RED_N")
	)
	(segment
		(start 12.3952 -34.52876)
		(end 13.644626 -34.52876)
		(width 0.11938)
		(layer "B.Cu")
		(net "FPGA_OUT_SMA1_LED_RED_N")
	)
	(segment
		(start 24.678386 -41.20769)
		(end 24.110696 -40.64)
		(width 0.11938)
		(layer "B.Cu")
		(net "FPGA_OUT_SMA1_LED_RED_N")
	)
	(segment
		(start 8.07847 -38.735762)
		(end 10.95629 -38.735762)
		(width 0.11938)
		(layer "B.Cu")
		(net "FPGA_OUT_SMA1_LED_RED_N")
	)
	(segment
		(start 10.922 -36.62553)
		(end 10.922 -35.306)
		(width 0.11938)
		(layer "B.Cu")
		(net "FPGA_OUT_SMA1_LED_RED_N")
	)
	(segment
		(start 10.922 -35.306)
		(end 11.43 -34.798)
		(width 0.11938)
		(layer "B.Cu")
		(net "FPGA_OUT_SMA1_LED_RED_N")
	)
	(segment
		(start 11.945366 -34.79038)
		(end 12.13358 -34.79038)
		(width 0.11938)
		(layer "B.Cu")
		(net "FPGA_OUT_SMA1_LED_RED_N")
	)
	(segment
		(start 19.605752 -34.28238)
		(end 24.884126 -34.28238)
		(width 0.11938)
		(layer "B.Cu")
		(net "FPGA_OUT_SMA1_LED_RED_N")
	)
	(segment
		(start 24.110696 -40.64)
		(end 23.749 -40.64)
		(width 0.11938)
		(layer "B.Cu")
		(net "FPGA_OUT_SMA1_LED_RED_N")
	)
	(segment
		(start 24.884126 -34.28238)
		(end 25.908 -35.306254)
		(width 0.11938)
		(layer "B.Cu")
		(net "FPGA_OUT_SMA1_LED_RED_N")
	)
	(segment
		(start 19.359372 -34.52876)
		(end 19.605752 -34.28238)
		(width 0.11938)
		(layer "B.Cu")
		(net "FPGA_OUT_SMA1_LED_RED_N")
	)
	(segment
		(start 11.937746 -34.798)
		(end 11.945366 -34.79038)
		(width 0.11938)
		(layer "B.Cu")
		(net "FPGA_OUT_SMA1_LED_RED_N")
	)
	(segment
		(start 13.756386 -34.417)
		(end 15.688564 -34.417)
		(width 0.11938)
		(layer "B.Cu")
		(net "FPGA_OUT_SMA1_LED_RED_N")
	)
	(segment
		(start 23.114 -43.688)
		(end 23.368 -43.942)
		(width 0.11938)
		(layer "B.Cu")
		(net "FPGA_OUT_SMA1_LED_RED_N")
	)
	(segment
		(start 12.13358 -34.79038)
		(end 12.3952 -34.52876)
		(width 0.11938)
		(layer "B.Cu")
		(net "FPGA_OUT_SMA1_LED_RED_N")
	)
	(segment
		(start 23.749 -40.64)
		(end 23.114 -41.275)
		(width 0.11938)
		(layer "B.Cu")
		(net "FPGA_OUT_SMA1_LED_RED_N")
	)
	(segment
		(start 7.1374 -37.794692)
		(end 8.07847 -38.735762)
		(width 0.11938)
		(layer "B.Cu")
		(net "FPGA_OUT_SMA1_LED_RED_N")
	)
	(segment
		(start 11.43 -34.798)
		(end 11.937746 -34.798)
		(width 0.11938)
		(layer "B.Cu")
		(net "FPGA_OUT_SMA1_LED_RED_N")
	)
	(segment
		(start 11.50747 -37.211)
		(end 10.922 -36.62553)
		(width 0.11938)
		(layer "B.Cu")
		(net "FPGA_OUT_SMA1_LED_RED_N")
	)
	(segment
		(start 23.114 -41.275)
		(end 23.114 -43.688)
		(width 0.11938)
		(layer "B.Cu")
		(net "FPGA_OUT_SMA1_LED_RED_N")
	)
	(segment
		(start 15.800324 -34.52876)
		(end 19.359372 -34.52876)
		(width 0.11938)
		(layer "B.Cu")
		(net "FPGA_OUT_SMA1_LED_RED_N")
	)
	(segment
		(start 13.644626 -34.52876)
		(end 13.756386 -34.417)
		(width 0.11938)
		(layer "B.Cu")
		(net "FPGA_OUT_SMA1_LED_RED_N")
	)
	(segment
		(start 25.467564 -41.20769)
		(end 24.678386 -41.20769)
		(width 0.11938)
		(layer "B.Cu")
		(net "FPGA_OUT_SMA1_LED_RED_N")
	)
	(segment
		(start 11.50747 -38.184582)
		(end 11.50747 -37.211)
		(width 0.11938)
		(layer "B.Cu")
		(net "FPGA_OUT_SMA1_LED_RED_N")
	)
	(segment
		(start 25.908 -35.306254)
		(end 25.908 -40.767254)
		(width 0.11938)
		(layer "B.Cu")
		(net "FPGA_OUT_SMA1_LED_RED_N")
	)
	(segment
		(start 25.908 -40.767254)
		(end 25.467564 -41.20769)
		(width 0.11938)
		(layer "B.Cu")
		(net "FPGA_OUT_SMA1_LED_RED_N")
	)
	(segment
		(start 15.688564 -34.417)
		(end 15.800324 -34.52876)
		(width 0.11938)
		(layer "B.Cu")
		(net "FPGA_OUT_SMA1_LED_RED_N")
	)
	(segment
		(start 10.95629 -38.735762)
		(end 11.50747 -38.184582)
		(width 0.11938)
		(layer "B.Cu")
		(net "FPGA_OUT_SMA1_LED_RED_N")
	)
	(segment
		(start 89.4461 -54.6989)
		(end 89.17432 -54.97068)
		(width 0.127)
		(layer "In7.Cu")
		(net "FPGA_OUT_SMA1_LED_RED_N")
	)
	(segment
		(start 99.266756 -49.70399)
		(end 98.0313 -50.939446)
		(width 0.127)
		(layer "In7.Cu")
		(net "FPGA_OUT_SMA1_LED_RED_N")
	)
	(segment
		(start 33.952688 -57.5437)
		(end 23.749 -47.340012)
		(width 0.127)
		(layer "In7.Cu")
		(net "FPGA_OUT_SMA1_LED_RED_N")
	)
	(segment
		(start 89.17432 -55.66029)
		(end 88.12911 -56.7055)
		(width 0.127)
		(layer "In7.Cu")
		(net "FPGA_OUT_SMA1_LED_RED_N")
	)
	(segment
		(start 84.525612 -56.7055)
		(end 83.319112 -55.499)
		(width 0.127)
		(layer "In7.Cu")
		(net "FPGA_OUT_SMA1_LED_RED_N")
	)
	(segment
		(start 78.8289 -56.2991)
		(end 77.5843 -57.5437)
		(width 0.127)
		(layer "In7.Cu")
		(net "FPGA_OUT_SMA1_LED_RED_N")
	)
	(segment
		(start 83.319112 -55.499)
		(end 80.929988 -55.499)
		(width 0.127)
		(layer "In7.Cu")
		(net "FPGA_OUT_SMA1_LED_RED_N")
	)
	(segment
		(start 97.155 -53.297836)
		(end 96.350836 -54.102)
		(width 0.127)
		(layer "In7.Cu")
		(net "FPGA_OUT_SMA1_LED_RED_N")
	)
	(segment
		(start 94.901512 -55.0545)
		(end 91.3765 -55.0545)
		(width 0.127)
		(layer "In7.Cu")
		(net "FPGA_OUT_SMA1_LED_RED_N")
	)
	(segment
		(start 23.749 -47.340012)
		(end 23.749 -45.719746)
		(width 0.127)
		(layer "In7.Cu")
		(net "FPGA_OUT_SMA1_LED_RED_N")
	)
	(segment
		(start 98.0313 -51.9557)
		(end 97.155 -52.832)
		(width 0.127)
		(layer "In7.Cu")
		(net "FPGA_OUT_SMA1_LED_RED_N")
	)
	(segment
		(start 80.129888 -56.2991)
		(end 78.8289 -56.2991)
		(width 0.127)
		(layer "In7.Cu")
		(net "FPGA_OUT_SMA1_LED_RED_N")
	)
	(segment
		(start 23.495 -44.323)
		(end 23.368 -44.196)
		(width 0.127)
		(layer "In7.Cu")
		(net "FPGA_OUT_SMA1_LED_RED_N")
	)
	(segment
		(start 103.347266 -49.32299)
		(end 102.966266 -49.70399)
		(width 0.1016)
		(layer "In7.Cu")
		(net "FPGA_OUT_SMA1_LED_RED_N")
	)
	(segment
		(start 96.350836 -54.102)
		(end 95.854012 -54.102)
		(width 0.127)
		(layer "In7.Cu")
		(net "FPGA_OUT_SMA1_LED_RED_N")
	)
	(segment
		(start 95.854012 -54.102)
		(end 94.901512 -55.0545)
		(width 0.127)
		(layer "In7.Cu")
		(net "FPGA_OUT_SMA1_LED_RED_N")
	)
	(segment
		(start 23.749 -45.719746)
		(end 23.495 -45.465746)
		(width 0.127)
		(layer "In7.Cu")
		(net "FPGA_OUT_SMA1_LED_RED_N")
	)
	(segment
		(start 91.0209 -54.6989)
		(end 89.4461 -54.6989)
		(width 0.127)
		(layer "In7.Cu")
		(net "FPGA_OUT_SMA1_LED_RED_N")
	)
	(segment
		(start 98.0313 -50.939446)
		(end 98.0313 -51.9557)
		(width 0.127)
		(layer "In7.Cu")
		(net "FPGA_OUT_SMA1_LED_RED_N")
	)
	(segment
		(start 102.966266 -49.70399)
		(end 99.266756 -49.70399)
		(width 0.1016)
		(layer "In7.Cu")
		(net "FPGA_OUT_SMA1_LED_RED_N")
	)
	(segment
		(start 77.5843 -57.5437)
		(end 33.952688 -57.5437)
		(width 0.127)
		(layer "In7.Cu")
		(net "FPGA_OUT_SMA1_LED_RED_N")
	)
	(segment
		(start 88.12911 -56.7055)
		(end 84.525612 -56.7055)
		(width 0.127)
		(layer "In7.Cu")
		(net "FPGA_OUT_SMA1_LED_RED_N")
	)
	(segment
		(start 97.155 -52.832)
		(end 97.155 -53.297836)
		(width 0.127)
		(layer "In7.Cu")
		(net "FPGA_OUT_SMA1_LED_RED_N")
	)
	(segment
		(start 89.17432 -54.97068)
		(end 89.17432 -55.66029)
		(width 0.127)
		(layer "In7.Cu")
		(net "FPGA_OUT_SMA1_LED_RED_N")
	)
	(segment
		(start 23.368 -44.196)
		(end 23.368 -43.942)
		(width 0.127)
		(layer "In7.Cu")
		(net "FPGA_OUT_SMA1_LED_RED_N")
	)
	(segment
		(start 23.495 -45.465746)
		(end 23.495 -44.323)
		(width 0.127)
		(layer "In7.Cu")
		(net "FPGA_OUT_SMA1_LED_RED_N")
	)
	(segment
		(start 80.929988 -55.499)
		(end 80.129888 -56.2991)
		(width 0.127)
		(layer "In7.Cu")
		(net "FPGA_OUT_SMA1_LED_RED_N")
	)
	(segment
		(start 91.3765 -55.0545)
		(end 91.0209 -54.6989)
		(width 0.127)
		(layer "In7.Cu")
		(net "FPGA_OUT_SMA1_LED_RED_N")
	)
	(segment
		(start 9.4234 -38.785292)
		(end 9.4234 -37.794692)
		(width 0.11938)
		(layer "F.Cu")
		(net "FPGA_OUT_SMA1_LED_GREEN_N")
	)
	(segment
		(start 103.847138 -46.823122)
		(end 103.347266 -47.322994)
		(width 0.11938)
		(layer "F.Cu")
		(net "FPGA_OUT_SMA1_LED_GREEN_N")
	)
	(via
		(at 9.4234 -37.794692)
		(size 0.508)
		(drill 0.254)
		(layers "F.Cu" "B.Cu")
		(net "FPGA_OUT_SMA1_LED_GREEN_N")
	)
	(via
		(at 25.019 -42.037)
		(size 0.508)
		(drill 0.254)
		(layers "F.Cu" "B.Cu")
		(net "FPGA_OUT_SMA1_LED_GREEN_N")
	)
	(via
		(at 103.347266 -47.322994)
		(size 0.4572)
		(drill 0.2032)
		(layers "F.Cu" "B.Cu")
		(net "FPGA_OUT_SMA1_LED_GREEN_N")
	)
	(segment
		(start 25.038812 -33.909)
		(end 19.451066 -33.909)
		(width 0.11938)
		(layer "B.Cu")
		(net "FPGA_OUT_SMA1_LED_GREEN_N")
	)
	(segment
		(start 15.70863 -33.909)
		(end 13.73632 -33.909)
		(width 0.11938)
		(layer "B.Cu")
		(net "FPGA_OUT_SMA1_LED_GREEN_N")
	)
	(segment
		(start 15.95501 -34.15538)
		(end 15.70863 -33.909)
		(width 0.11938)
		(layer "B.Cu")
		(net "FPGA_OUT_SMA1_LED_GREEN_N")
	)
	(segment
		(start 12.240514 -34.15538)
		(end 11.978894 -34.417)
		(width 0.11938)
		(layer "B.Cu")
		(net "FPGA_OUT_SMA1_LED_GREEN_N")
	)
	(segment
		(start 11.978894 -34.417)
		(end 11.049 -34.417)
		(width 0.11938)
		(layer "B.Cu")
		(net "FPGA_OUT_SMA1_LED_GREEN_N")
	)
	(segment
		(start 25.019 -42.037)
		(end 25.273 -42.037)
		(width 0.11938)
		(layer "B.Cu")
		(net "FPGA_OUT_SMA1_LED_GREEN_N")
	)
	(segment
		(start 13.48994 -34.15538)
		(end 12.240514 -34.15538)
		(width 0.11938)
		(layer "B.Cu")
		(net "FPGA_OUT_SMA1_LED_GREEN_N")
	)
	(segment
		(start 10.541 -36.830254)
		(end 11.13409 -37.423344)
		(width 0.11938)
		(layer "B.Cu")
		(net "FPGA_OUT_SMA1_LED_GREEN_N")
	)
	(segment
		(start 19.451066 -33.909)
		(end 19.204686 -34.15538)
		(width 0.11938)
		(layer "B.Cu")
		(net "FPGA_OUT_SMA1_LED_GREEN_N")
	)
	(segment
		(start 10.541 -34.925)
		(end 10.541 -36.830254)
		(width 0.11938)
		(layer "B.Cu")
		(net "FPGA_OUT_SMA1_LED_GREEN_N")
	)
	(segment
		(start 25.273 -42.037)
		(end 26.28138 -41.02862)
		(width 0.11938)
		(layer "B.Cu")
		(net "FPGA_OUT_SMA1_LED_GREEN_N")
	)
	(segment
		(start 26.28138 -35.151568)
		(end 25.038812 -33.909)
		(width 0.11938)
		(layer "B.Cu")
		(net "FPGA_OUT_SMA1_LED_GREEN_N")
	)
	(segment
		(start 26.28138 -41.02862)
		(end 26.28138 -35.151568)
		(width 0.11938)
		(layer "B.Cu")
		(net "FPGA_OUT_SMA1_LED_GREEN_N")
	)
	(segment
		(start 11.13409 -37.423344)
		(end 11.13409 -38.029896)
		(width 0.11938)
		(layer "B.Cu")
		(net "FPGA_OUT_SMA1_LED_GREEN_N")
	)
	(segment
		(start 19.204686 -34.15538)
		(end 15.95501 -34.15538)
		(width 0.11938)
		(layer "B.Cu")
		(net "FPGA_OUT_SMA1_LED_GREEN_N")
	)
	(segment
		(start 11.049 -34.417)
		(end 10.541 -34.925)
		(width 0.11938)
		(layer "B.Cu")
		(net "FPGA_OUT_SMA1_LED_GREEN_N")
	)
	(segment
		(start 9.99109 -38.362382)
		(end 9.4234 -37.794692)
		(width 0.11938)
		(layer "B.Cu")
		(net "FPGA_OUT_SMA1_LED_GREEN_N")
	)
	(segment
		(start 13.73632 -33.909)
		(end 13.48994 -34.15538)
		(width 0.11938)
		(layer "B.Cu")
		(net "FPGA_OUT_SMA1_LED_GREEN_N")
	)
	(segment
		(start 10.801604 -38.362382)
		(end 9.99109 -38.362382)
		(width 0.11938)
		(layer "B.Cu")
		(net "FPGA_OUT_SMA1_LED_GREEN_N")
	)
	(segment
		(start 11.13409 -38.029896)
		(end 10.801604 -38.362382)
		(width 0.11938)
		(layer "B.Cu")
		(net "FPGA_OUT_SMA1_LED_GREEN_N")
	)
	(segment
		(start 91.389454 -51.767486)
		(end 93.783658 -51.767486)
		(width 0.127)
		(layer "In7.Cu")
		(net "FPGA_OUT_SMA1_LED_GREEN_N")
	)
	(segment
		(start 99.920552 -47.729394)
		(end 102.940866 -47.729394)
		(width 0.1016)
		(layer "In7.Cu")
		(net "FPGA_OUT_SMA1_LED_GREEN_N")
	)
	(segment
		(start 81.8261 -52.4129)
		(end 90.74404 -52.4129)
		(width 0.127)
		(layer "In7.Cu")
		(net "FPGA_OUT_SMA1_LED_GREEN_N")
	)
	(segment
		(start 63.064136 -52.7685)
		(end 65.5955 -52.7685)
		(width 0.127)
		(layer "In7.Cu")
		(net "FPGA_OUT_SMA1_LED_GREEN_N")
	)
	(segment
		(start 25.019 -42.037)
		(end 25.654 -42.037)
		(width 0.127)
		(layer "In7.Cu")
		(net "FPGA_OUT_SMA1_LED_GREEN_N")
	)
	(segment
		(start 81.4705 -52.7685)
		(end 81.8261 -52.4129)
		(width 0.127)
		(layer "In7.Cu")
		(net "FPGA_OUT_SMA1_LED_GREEN_N")
	)
	(segment
		(start 76.454 -52.7685)
		(end 81.4705 -52.7685)
		(width 0.127)
		(layer "In7.Cu")
		(net "FPGA_OUT_SMA1_LED_GREEN_N")
	)
	(segment
		(start 98.171 -48.133)
		(end 99.516946 -48.133)
		(width 0.1016)
		(layer "In7.Cu")
		(net "FPGA_OUT_SMA1_LED_GREEN_N")
	)
	(segment
		(start 102.940866 -47.729394)
		(end 103.347266 -47.322994)
		(width 0.1016)
		(layer "In7.Cu")
		(net "FPGA_OUT_SMA1_LED_GREEN_N")
	)
	(segment
		(start 65.5955 -52.7685)
		(end 66.04 -53.213)
		(width 0.127)
		(layer "In7.Cu")
		(net "FPGA_OUT_SMA1_LED_GREEN_N")
	)
	(segment
		(start 90.74404 -52.4129)
		(end 91.389454 -51.767486)
		(width 0.127)
		(layer "In7.Cu")
		(net "FPGA_OUT_SMA1_LED_GREEN_N")
	)
	(segment
		(start 26.545032 -41.145968)
		(end 51.441604 -41.145968)
		(width 0.127)
		(layer "In7.Cu")
		(net "FPGA_OUT_SMA1_LED_GREEN_N")
	)
	(segment
		(start 51.441604 -41.145968)
		(end 63.064136 -52.7685)
		(width 0.127)
		(layer "In7.Cu")
		(net "FPGA_OUT_SMA1_LED_GREEN_N")
	)
	(segment
		(start 93.783658 -51.767486)
		(end 97.418144 -48.133)
		(width 0.127)
		(layer "In7.Cu")
		(net "FPGA_OUT_SMA1_LED_GREEN_N")
	)
	(segment
		(start 76.0095 -53.213)
		(end 76.454 -52.7685)
		(width 0.127)
		(layer "In7.Cu")
		(net "FPGA_OUT_SMA1_LED_GREEN_N")
	)
	(segment
		(start 97.418144 -48.133)
		(end 98.171 -48.133)
		(width 0.127)
		(layer "In7.Cu")
		(net "FPGA_OUT_SMA1_LED_GREEN_N")
	)
	(segment
		(start 99.516946 -48.133)
		(end 99.920552 -47.729394)
		(width 0.1016)
		(layer "In7.Cu")
		(net "FPGA_OUT_SMA1_LED_GREEN_N")
	)
	(segment
		(start 66.04 -53.213)
		(end 76.0095 -53.213)
		(width 0.127)
		(layer "In7.Cu")
		(net "FPGA_OUT_SMA1_LED_GREEN_N")
	)
	(segment
		(start 25.654 -42.037)
		(end 26.545032 -41.145968)
		(width 0.127)
		(layer "In7.Cu")
		(net "FPGA_OUT_SMA1_LED_GREEN_N")
	)
	(segment
		(start 5.9944 -38.785292)
		(end 5.9944 -37.794692)
		(width 0.11938)
		(layer "F.Cu")
		(net "FPGA_OUT_SMA1_LED_BLUE_N")
	)
	(segment
		(start 103.347266 -46.322996)
		(end 103.847138 -45.823124)
		(width 0.11938)
		(layer "F.Cu")
		(net "FPGA_OUT_SMA1_LED_BLUE_N")
	)
	(via
		(at 103.347266 -46.322996)
		(size 0.4572)
		(drill 0.2032)
		(layers "F.Cu" "B.Cu")
		(net "FPGA_OUT_SMA1_LED_BLUE_N")
	)
	(via
		(at 25.019 -40.386)
		(size 0.508)
		(drill 0.254)
		(layers "F.Cu" "B.Cu")
		(net "FPGA_OUT_SMA1_LED_BLUE_N")
	)
	(via
		(at 5.9944 -37.794692)
		(size 0.508)
		(drill 0.254)
		(layers "F.Cu" "B.Cu")
		(net "FPGA_OUT_SMA1_LED_BLUE_N")
	)
	(segment
		(start 12.573 -37.719)
		(end 10.668 -39.624)
		(width 0.11938)
		(layer "B.Cu")
		(net "FPGA_OUT_SMA1_LED_BLUE_N")
	)
	(segment
		(start 13.863574 -34.876232)
		(end 12.88669 -35.844734)
		(width 0.11938)
		(layer "B.Cu")
		(net "FPGA_OUT_SMA1_LED_BLUE_N")
	)
	(segment
		(start 12.573 -36.341304)
		(end 12.573 -37.719)
		(width 0.11938)
		(layer "B.Cu")
		(net "FPGA_OUT_SMA1_LED_BLUE_N")
	)
	(segment
		(start 24.746204 -34.99231)
		(end 22.091396 -34.99231)
		(width 0.11938)
		(layer "B.Cu")
		(net "FPGA_OUT_SMA1_LED_BLUE_N")
	)
	(segment
		(start 25.019 -40.386)
		(end 25.527 -39.878)
		(width 0.11938)
		(layer "B.Cu")
		(net "FPGA_OUT_SMA1_LED_BLUE_N")
	)
	(segment
		(start 15.064232 -34.876232)
		(end 13.863574 -34.876232)
		(width 0.11938)
		(layer "B.Cu")
		(net "FPGA_OUT_SMA1_LED_BLUE_N")
	)
	(segment
		(start 25.527 -35.773106)
		(end 24.746204 -34.99231)
		(width 0.11938)
		(layer "B.Cu")
		(net "FPGA_OUT_SMA1_LED_BLUE_N")
	)
	(segment
		(start 25.527 -39.878)
		(end 25.527 -35.773106)
		(width 0.11938)
		(layer "B.Cu")
		(net "FPGA_OUT_SMA1_LED_BLUE_N")
	)
	(segment
		(start 20.373086 -36.71062)
		(end 16.89862 -36.71062)
		(width 0.11938)
		(layer "B.Cu")
		(net "FPGA_OUT_SMA1_LED_BLUE_N")
	)
	(segment
		(start 12.88669 -35.844734)
		(end 12.88669 -36.027614)
		(width 0.11938)
		(layer "B.Cu")
		(net "FPGA_OUT_SMA1_LED_BLUE_N")
	)
	(segment
		(start 10.668 -39.624)
		(end 7.823708 -39.624)
		(width 0.11938)
		(layer "B.Cu")
		(net "FPGA_OUT_SMA1_LED_BLUE_N")
	)
	(segment
		(start 22.091396 -34.99231)
		(end 20.373086 -36.71062)
		(width 0.11938)
		(layer "B.Cu")
		(net "FPGA_OUT_SMA1_LED_BLUE_N")
	)
	(segment
		(start 7.823708 -39.624)
		(end 5.9944 -37.794692)
		(width 0.11938)
		(layer "B.Cu")
		(net "FPGA_OUT_SMA1_LED_BLUE_N")
	)
	(segment
		(start 16.89862 -36.71062)
		(end 15.064232 -34.876232)
		(width 0.11938)
		(layer "B.Cu")
		(net "FPGA_OUT_SMA1_LED_BLUE_N")
	)
	(segment
		(start 12.88669 -36.027614)
		(end 12.573 -36.341304)
		(width 0.11938)
		(layer "B.Cu")
		(net "FPGA_OUT_SMA1_LED_BLUE_N")
	)
	(segment
		(start 66.548 -52.451)
		(end 65.913 -51.816)
		(width 0.127)
		(layer "In7.Cu")
		(net "FPGA_OUT_SMA1_LED_BLUE_N")
	)
	(segment
		(start 97.79 -47.117)
		(end 97.409 -47.117)
		(width 0.1016)
		(layer "In7.Cu")
		(net "FPGA_OUT_SMA1_LED_BLUE_N")
	)
	(segment
		(start 90.428064 -51.6509)
		(end 79.121 -51.6509)
		(width 0.127)
		(layer "In7.Cu")
		(net "FPGA_OUT_SMA1_LED_BLUE_N")
	)
	(segment
		(start 65.913 -51.816)
		(end 63.189612 -51.816)
		(width 0.127)
		(layer "In7.Cu")
		(net "FPGA_OUT_SMA1_LED_BLUE_N")
	)
	(segment
		(start 75.438 -52.451)
		(end 66.548 -52.451)
		(width 0.127)
		(layer "In7.Cu")
		(net "FPGA_OUT_SMA1_LED_BLUE_N")
	)
	(segment
		(start 78.0415 -51.2445)
		(end 77.47 -51.816)
		(width 0.127)
		(layer "In7.Cu")
		(net "FPGA_OUT_SMA1_LED_BLUE_N")
	)
	(segment
		(start 77.47 -51.816)
		(end 76.073 -51.816)
		(width 0.127)
		(layer "In7.Cu")
		(net "FPGA_OUT_SMA1_LED_BLUE_N")
	)
	(segment
		(start 51.531012 -40.1574)
		(end 25.2476 -40.1574)
		(width 0.127)
		(layer "In7.Cu")
		(net "FPGA_OUT_SMA1_LED_BLUE_N")
	)
	(segment
		(start 78.7146 -51.2445)
		(end 78.0415 -51.2445)
		(width 0.127)
		(layer "In7.Cu")
		(net "FPGA_OUT_SMA1_LED_BLUE_N")
	)
	(segment
		(start 97.355914 -47.117)
		(end 93.467428 -51.005486)
		(width 0.127)
		(layer "In7.Cu")
		(net "FPGA_OUT_SMA1_LED_BLUE_N")
	)
	(segment
		(start 103.347266 -46.322996)
		(end 102.763066 -46.907196)
		(width 0.1016)
		(layer "In7.Cu")
		(net "FPGA_OUT_SMA1_LED_BLUE_N")
	)
	(segment
		(start 97.409 -47.117)
		(end 97.355914 -47.117)
		(width 0.127)
		(layer "In7.Cu")
		(net "FPGA_OUT_SMA1_LED_BLUE_N")
	)
	(segment
		(start 102.763066 -46.907196)
		(end 97.999804 -46.907196)
		(width 0.1016)
		(layer "In7.Cu")
		(net "FPGA_OUT_SMA1_LED_BLUE_N")
	)
	(segment
		(start 25.2476 -40.1574)
		(end 25.019 -40.386)
		(width 0.127)
		(layer "In7.Cu")
		(net "FPGA_OUT_SMA1_LED_BLUE_N")
	)
	(segment
		(start 76.073 -51.816)
		(end 75.438 -52.451)
		(width 0.127)
		(layer "In7.Cu")
		(net "FPGA_OUT_SMA1_LED_BLUE_N")
	)
	(segment
		(start 63.189612 -51.816)
		(end 51.531012 -40.1574)
		(width 0.127)
		(layer "In7.Cu")
		(net "FPGA_OUT_SMA1_LED_BLUE_N")
	)
	(segment
		(start 79.121 -51.6509)
		(end 78.7146 -51.2445)
		(width 0.127)
		(layer "In7.Cu")
		(net "FPGA_OUT_SMA1_LED_BLUE_N")
	)
	(segment
		(start 97.999804 -46.907196)
		(end 97.79 -47.117)
		(width 0.1016)
		(layer "In7.Cu")
		(net "FPGA_OUT_SMA1_LED_BLUE_N")
	)
	(segment
		(start 93.467428 -51.005486)
		(end 91.073478 -51.005486)
		(width 0.127)
		(layer "In7.Cu")
		(net "FPGA_OUT_SMA1_LED_BLUE_N")
	)
	(segment
		(start 91.073478 -51.005486)
		(end 90.428064 -51.6509)
		(width 0.127)
		(layer "In7.Cu")
		(net "FPGA_OUT_SMA1_LED_BLUE_N")
	)
	(segment
		(start 7.112 -80.137)
		(end 8.763 -78.486)
		(width 0.11938)
		(layer "F.Cu")
		(net "FPGA_OUT_GPS_LED_RED_N")
	)
	(segment
		(start 7.112 -81.0006)
		(end 7.112 -80.137)
		(width 0.11938)
		(layer "F.Cu")
		(net "FPGA_OUT_GPS_LED_RED_N")
	)
	(segment
		(start 98.846894 -50.823114)
		(end 97.559114 -50.823114)
		(width 0.11938)
		(layer "F.Cu")
		(net "FPGA_OUT_GPS_LED_RED_N")
	)
	(via
		(at 25.146 -47.879)
		(size 0.508)
		(drill 0.254)
		(layers "F.Cu" "B.Cu")
		(net "FPGA_OUT_GPS_LED_RED_N")
	)
	(via
		(at 97.559114 -50.823114)
		(size 0.508)
		(drill 0.254)
		(layers "F.Cu" "B.Cu")
		(net "FPGA_OUT_GPS_LED_RED_N")
	)
	(via
		(at 8.763 -78.486)
		(size 0.508)
		(drill 0.254)
		(layers "F.Cu" "B.Cu")
		(net "FPGA_OUT_GPS_LED_RED_N")
	)
	(segment
		(start 25.781 -51.435)
		(end 25.781 -48.514)
		(width 0.127)
		(layer "In2.Cu")
		(net "FPGA_OUT_GPS_LED_RED_N")
	)
	(segment
		(start 22.271482 -51.816)
		(end 25.4 -51.816)
		(width 0.127)
		(layer "In2.Cu")
		(net "FPGA_OUT_GPS_LED_RED_N")
	)
	(segment
		(start 17.78 -52.07)
		(end 22.017482 -52.07)
		(width 0.127)
		(layer "In2.Cu")
		(net "FPGA_OUT_GPS_LED_RED_N")
	)
	(segment
		(start 14.351 -54.864)
		(end 15.113 -54.864)
		(width 0.127)
		(layer "In2.Cu")
		(net "FPGA_OUT_GPS_LED_RED_N")
	)
	(segment
		(start 14.45768 -68.85432)
		(end 14.45768 -66.06032)
		(width 0.127)
		(layer "In2.Cu")
		(net "FPGA_OUT_GPS_LED_RED_N")
	)
	(segment
		(start 14.732 -65.786)
		(end 14.732 -64.291718)
		(width 0.127)
		(layer "In2.Cu")
		(net "FPGA_OUT_GPS_LED_RED_N")
	)
	(segment
		(start 13.2715 -70.0405)
		(end 14.45768 -68.85432)
		(width 0.127)
		(layer "In2.Cu")
		(net "FPGA_OUT_GPS_LED_RED_N")
	)
	(segment
		(start 14.478 -59.69)
		(end 13.843 -59.055)
		(width 0.127)
		(layer "In2.Cu")
		(net "FPGA_OUT_GPS_LED_RED_N")
	)
	(segment
		(start 25.4 -51.816)
		(end 25.781 -51.435)
		(width 0.127)
		(layer "In2.Cu")
		(net "FPGA_OUT_GPS_LED_RED_N")
	)
	(segment
		(start 15.367 -54.61)
		(end 15.367 -51.943)
		(width 0.127)
		(layer "In2.Cu")
		(net "FPGA_OUT_GPS_LED_RED_N")
	)
	(segment
		(start 15.367 -51.943)
		(end 15.875 -51.435)
		(width 0.127)
		(layer "In2.Cu")
		(net "FPGA_OUT_GPS_LED_RED_N")
	)
	(segment
		(start 13.843 -55.372)
		(end 14.351 -54.864)
		(width 0.127)
		(layer "In2.Cu")
		(net "FPGA_OUT_GPS_LED_RED_N")
	)
	(segment
		(start 25.781 -48.514)
		(end 25.146 -47.879)
		(width 0.127)
		(layer "In2.Cu")
		(net "FPGA_OUT_GPS_LED_RED_N")
	)
	(segment
		(start 13.098018 -70.0405)
		(end 13.2715 -70.0405)
		(width 0.127)
		(layer "In2.Cu")
		(net "FPGA_OUT_GPS_LED_RED_N")
	)
	(segment
		(start 14.45768 -66.06032)
		(end 14.732 -65.786)
		(width 0.127)
		(layer "In2.Cu")
		(net "FPGA_OUT_GPS_LED_RED_N")
	)
	(segment
		(start 17.145 -51.435)
		(end 17.78 -52.07)
		(width 0.127)
		(layer "In2.Cu")
		(net "FPGA_OUT_GPS_LED_RED_N")
	)
	(segment
		(start 11.176 -71.962518)
		(end 13.098018 -70.0405)
		(width 0.127)
		(layer "In2.Cu")
		(net "FPGA_OUT_GPS_LED_RED_N")
	)
	(segment
		(start 22.017482 -52.07)
		(end 22.271482 -51.816)
		(width 0.127)
		(layer "In2.Cu")
		(net "FPGA_OUT_GPS_LED_RED_N")
	)
	(segment
		(start 13.843 -59.055)
		(end 13.843 -55.372)
		(width 0.127)
		(layer "In2.Cu")
		(net "FPGA_OUT_GPS_LED_RED_N")
	)
	(segment
		(start 14.732 -64.291718)
		(end 14.478 -64.037718)
		(width 0.127)
		(layer "In2.Cu")
		(net "FPGA_OUT_GPS_LED_RED_N")
	)
	(segment
		(start 11.176 -76.073)
		(end 11.176 -71.962518)
		(width 0.127)
		(layer "In2.Cu")
		(net "FPGA_OUT_GPS_LED_RED_N")
	)
	(segment
		(start 15.875 -51.435)
		(end 17.145 -51.435)
		(width 0.127)
		(layer "In2.Cu")
		(net "FPGA_OUT_GPS_LED_RED_N")
	)
	(segment
		(start 15.113 -54.864)
		(end 15.367 -54.61)
		(width 0.127)
		(layer "In2.Cu")
		(net "FPGA_OUT_GPS_LED_RED_N")
	)
	(segment
		(start 8.763 -78.486)
		(end 11.176 -76.073)
		(width 0.127)
		(layer "In2.Cu")
		(net "FPGA_OUT_GPS_LED_RED_N")
	)
	(segment
		(start 14.478 -64.037718)
		(end 14.478 -59.69)
		(width 0.127)
		(layer "In2.Cu")
		(net "FPGA_OUT_GPS_LED_RED_N")
	)
	(segment
		(start 88.79332 -55.502302)
		(end 88.79332 -54.747668)
		(width 0.127)
		(layer "In7.Cu")
		(net "FPGA_OUT_GPS_LED_RED_N")
	)
	(segment
		(start 97.559114 -51.70805)
		(end 97.559114 -50.823114)
		(width 0.127)
		(layer "In7.Cu")
		(net "FPGA_OUT_GPS_LED_RED_N")
	)
	(segment
		(start 83.3501 -54.991)
		(end 84.6836 -56.3245)
		(width 0.127)
		(layer "In7.Cu")
		(net "FPGA_OUT_GPS_LED_RED_N")
	)
	(segment
		(start 87.971122 -56.3245)
		(end 88.79332 -55.502302)
		(width 0.127)
		(layer "In7.Cu")
		(net "FPGA_OUT_GPS_LED_RED_N")
	)
	(segment
		(start 80.899 -54.991)
		(end 83.3501 -54.991)
		(width 0.127)
		(layer "In7.Cu")
		(net "FPGA_OUT_GPS_LED_RED_N")
	)
	(segment
		(start 25.146 -47.879)
		(end 33.3375 -56.0705)
		(width 0.127)
		(layer "In7.Cu")
		(net "FPGA_OUT_GPS_LED_RED_N")
	)
	(segment
		(start 79.9719 -55.9181)
		(end 80.899 -54.991)
		(width 0.127)
		(layer "In7.Cu")
		(net "FPGA_OUT_GPS_LED_RED_N")
	)
	(segment
		(start 95.758 -53.509164)
		(end 97.559114 -51.70805)
		(width 0.127)
		(layer "In7.Cu")
		(net "FPGA_OUT_GPS_LED_RED_N")
	)
	(segment
		(start 91.178888 -54.3179)
		(end 91.534488 -54.6735)
		(width 0.127)
		(layer "In7.Cu")
		(net "FPGA_OUT_GPS_LED_RED_N")
	)
	(segment
		(start 95.758 -53.659024)
		(end 95.758 -53.509164)
		(width 0.127)
		(layer "In7.Cu")
		(net "FPGA_OUT_GPS_LED_RED_N")
	)
	(segment
		(start 84.6836 -56.3245)
		(end 87.971122 -56.3245)
		(width 0.127)
		(layer "In7.Cu")
		(net "FPGA_OUT_GPS_LED_RED_N")
	)
	(segment
		(start 88.79332 -54.747668)
		(end 89.223088 -54.3179)
		(width 0.127)
		(layer "In7.Cu")
		(net "FPGA_OUT_GPS_LED_RED_N")
	)
	(segment
		(start 77.7875 -56.0705)
		(end 77.9399 -55.9181)
		(width 0.127)
		(layer "In7.Cu")
		(net "FPGA_OUT_GPS_LED_RED_N")
	)
	(segment
		(start 94.743524 -54.6735)
		(end 95.758 -53.659024)
		(width 0.127)
		(layer "In7.Cu")
		(net "FPGA_OUT_GPS_LED_RED_N")
	)
	(segment
		(start 91.534488 -54.6735)
		(end 94.743524 -54.6735)
		(width 0.127)
		(layer "In7.Cu")
		(net "FPGA_OUT_GPS_LED_RED_N")
	)
	(segment
		(start 77.9399 -55.9181)
		(end 79.9719 -55.9181)
		(width 0.127)
		(layer "In7.Cu")
		(net "FPGA_OUT_GPS_LED_RED_N")
	)
	(segment
		(start 33.3375 -56.0705)
		(end 77.7875 -56.0705)
		(width 0.127)
		(layer "In7.Cu")
		(net "FPGA_OUT_GPS_LED_RED_N")
	)
	(segment
		(start 89.223088 -54.3179)
		(end 91.178888 -54.3179)
		(width 0.127)
		(layer "In7.Cu")
		(net "FPGA_OUT_GPS_LED_RED_N")
	)
	(segment
		(start 10.033 -78.486)
		(end 10.033 -79.120746)
		(width 0.11938)
		(layer "F.Cu")
		(net "FPGA_OUT_GPS_LED_GREEN_N")
	)
	(segment
		(start 9.652 -79.501746)
		(end 9.652 -81.0006)
		(width 0.11938)
		(layer "F.Cu")
		(net "FPGA_OUT_GPS_LED_GREEN_N")
	)
	(segment
		(start 10.033 -79.120746)
		(end 9.652 -79.501746)
		(width 0.11938)
		(layer "F.Cu")
		(net "FPGA_OUT_GPS_LED_GREEN_N")
	)
	(segment
		(start 98.846894 -52.82311)
		(end 98.347022 -53.322982)
		(width 0.11938)
		(layer "F.Cu")
		(net "FPGA_OUT_GPS_LED_GREEN_N")
	)
	(via
		(at 25.146 -52.451)
		(size 0.508)
		(drill 0.254)
		(layers "F.Cu" "B.Cu")
		(net "FPGA_OUT_GPS_LED_GREEN_N")
	)
	(via
		(at 10.033 -78.486)
		(size 0.508)
		(drill 0.254)
		(layers "F.Cu" "B.Cu")
		(net "FPGA_OUT_GPS_LED_GREEN_N")
	)
	(via
		(at 98.347022 -53.322982)
		(size 0.4572)
		(drill 0.2032)
		(layers "F.Cu" "B.Cu")
		(net "FPGA_OUT_GPS_LED_GREEN_N")
	)
	(segment
		(start 16.592042 -53.892958)
		(end 16.592042 -55.036212)
		(width 0.127)
		(layer "In2.Cu")
		(net "FPGA_OUT_GPS_LED_GREEN_N")
	)
	(segment
		(start 15.6845 -57.978548)
		(end 14.859 -58.804048)
		(width 0.127)
		(layer "In2.Cu")
		(net "FPGA_OUT_GPS_LED_GREEN_N")
	)
	(segment
		(start 15.6845 -55.943754)
		(end 15.6845 -57.978548)
		(width 0.127)
		(layer "In2.Cu")
		(net "FPGA_OUT_GPS_LED_GREEN_N")
	)
	(segment
		(start 14.859 -58.804048)
		(end 14.859 -63.87973)
		(width 0.127)
		(layer "In2.Cu")
		(net "FPGA_OUT_GPS_LED_GREEN_N")
	)
	(segment
		(start 15.113 -64.13373)
		(end 15.113 -66.14033)
		(width 0.127)
		(layer "In2.Cu")
		(net "FPGA_OUT_GPS_LED_GREEN_N")
	)
	(segment
		(start 14.859 -63.87973)
		(end 15.113 -64.13373)
		(width 0.127)
		(layer "In2.Cu")
		(net "FPGA_OUT_GPS_LED_GREEN_N")
	)
	(segment
		(start 18.034 -52.451)
		(end 16.592042 -53.892958)
		(width 0.127)
		(layer "In2.Cu")
		(net "FPGA_OUT_GPS_LED_GREEN_N")
	)
	(segment
		(start 11.938 -76.581)
		(end 10.033 -78.486)
		(width 0.127)
		(layer "In2.Cu")
		(net "FPGA_OUT_GPS_LED_GREEN_N")
	)
	(segment
		(start 14.95298 -69.88302)
		(end 11.938 -72.898)
		(width 0.127)
		(layer "In2.Cu")
		(net "FPGA_OUT_GPS_LED_GREEN_N")
	)
	(segment
		(start 16.592042 -55.036212)
		(end 15.6845 -55.943754)
		(width 0.127)
		(layer "In2.Cu")
		(net "FPGA_OUT_GPS_LED_GREEN_N")
	)
	(segment
		(start 11.938 -72.898)
		(end 11.938 -76.581)
		(width 0.127)
		(layer "In2.Cu")
		(net "FPGA_OUT_GPS_LED_GREEN_N")
	)
	(segment
		(start 15.113 -66.14033)
		(end 14.95298 -66.30035)
		(width 0.127)
		(layer "In2.Cu")
		(net "FPGA_OUT_GPS_LED_GREEN_N")
	)
	(segment
		(start 14.95298 -66.30035)
		(end 14.95298 -69.88302)
		(width 0.127)
		(layer "In2.Cu")
		(net "FPGA_OUT_GPS_LED_GREEN_N")
	)
	(segment
		(start 25.146 -52.451)
		(end 18.034 -52.451)
		(width 0.127)
		(layer "In2.Cu")
		(net "FPGA_OUT_GPS_LED_GREEN_N")
	)
	(segment
		(start 98.347022 -53.925978)
		(end 96.901 -55.372)
		(width 0.127)
		(layer "In7.Cu")
		(net "FPGA_OUT_GPS_LED_GREEN_N")
	)
	(segment
		(start 88.5825 -60.198)
		(end 87.122 -58.7375)
		(width 0.127)
		(layer "In7.Cu")
		(net "FPGA_OUT_GPS_LED_GREEN_N")
	)
	(segment
		(start 81.00822 -60.1091)
		(end 77.108812 -60.1091)
		(width 0.127)
		(layer "In7.Cu")
		(net "FPGA_OUT_GPS_LED_GREEN_N")
	)
	(segment
		(start 84.518246 -58.7375)
		(end 83.692746 -59.563)
		(width 0.127)
		(layer "In7.Cu")
		(net "FPGA_OUT_GPS_LED_GREEN_N")
	)
	(segment
		(start 98.347022 -53.322982)
		(end 98.347022 -53.925978)
		(width 0.127)
		(layer "In7.Cu")
		(net "FPGA_OUT_GPS_LED_GREEN_N")
	)
	(segment
		(start 88.917018 -60.7695)
		(end 88.5825 -60.434982)
		(width 0.127)
		(layer "In7.Cu")
		(net "FPGA_OUT_GPS_LED_GREEN_N")
	)
	(segment
		(start 77.108812 -60.1091)
		(end 75.686412 -58.6867)
		(width 0.127)
		(layer "In7.Cu")
		(net "FPGA_OUT_GPS_LED_GREEN_N")
	)
	(segment
		(start 96.901 -55.372)
		(end 96.901 -58.073036)
		(width 0.127)
		(layer "In7.Cu")
		(net "FPGA_OUT_GPS_LED_GREEN_N")
	)
	(segment
		(start 90.279982 -59.8805)
		(end 89.390982 -60.7695)
		(width 0.127)
		(layer "In7.Cu")
		(net "FPGA_OUT_GPS_LED_GREEN_N")
	)
	(segment
		(start 96.901 -58.073036)
		(end 95.412814 -59.561222)
		(width 0.127)
		(layer "In7.Cu")
		(net "FPGA_OUT_GPS_LED_GREEN_N")
	)
	(segment
		(start 90.953844 -59.8805)
		(end 90.279982 -59.8805)
		(width 0.127)
		(layer "In7.Cu")
		(net "FPGA_OUT_GPS_LED_GREEN_N")
	)
	(segment
		(start 95.412814 -59.561222)
		(end 91.273122 -59.561222)
		(width 0.127)
		(layer "In7.Cu")
		(net "FPGA_OUT_GPS_LED_GREEN_N")
	)
	(segment
		(start 75.686412 -58.6867)
		(end 31.3817 -58.6867)
		(width 0.127)
		(layer "In7.Cu")
		(net "FPGA_OUT_GPS_LED_GREEN_N")
	)
	(segment
		(start 89.390982 -60.7695)
		(end 88.917018 -60.7695)
		(width 0.127)
		(layer "In7.Cu")
		(net "FPGA_OUT_GPS_LED_GREEN_N")
	)
	(segment
		(start 88.5825 -60.434982)
		(end 88.5825 -60.198)
		(width 0.127)
		(layer "In7.Cu")
		(net "FPGA_OUT_GPS_LED_GREEN_N")
	)
	(segment
		(start 87.122 -58.7375)
		(end 84.518246 -58.7375)
		(width 0.127)
		(layer "In7.Cu")
		(net "FPGA_OUT_GPS_LED_GREEN_N")
	)
	(segment
		(start 83.692746 -59.563)
		(end 82.920586 -59.563)
		(width 0.127)
		(layer "In7.Cu")
		(net "FPGA_OUT_GPS_LED_GREEN_N")
	)
	(segment
		(start 82.666586 -59.309)
		(end 81.80832 -59.309)
		(width 0.127)
		(layer "In7.Cu")
		(net "FPGA_OUT_GPS_LED_GREEN_N")
	)
	(segment
		(start 91.273122 -59.561222)
		(end 90.953844 -59.8805)
		(width 0.127)
		(layer "In7.Cu")
		(net "FPGA_OUT_GPS_LED_GREEN_N")
	)
	(segment
		(start 82.920586 -59.563)
		(end 82.666586 -59.309)
		(width 0.127)
		(layer "In7.Cu")
		(net "FPGA_OUT_GPS_LED_GREEN_N")
	)
	(segment
		(start 31.3817 -58.6867)
		(end 25.146 -52.451)
		(width 0.127)
		(layer "In7.Cu")
		(net "FPGA_OUT_GPS_LED_GREEN_N")
	)
	(segment
		(start 81.80832 -59.309)
		(end 81.00822 -60.1091)
		(width 0.127)
		(layer "In7.Cu")
		(net "FPGA_OUT_GPS_LED_GREEN_N")
	)
	(segment
		(start 11.303 -78.486)
		(end 10.73531 -77.91831)
		(width 0.11938)
		(layer "F.Cu")
		(net "FPGA_OUT_GPS_LED_BLUE_N")
	)
	(segment
		(start 5.842 -80.264)
		(end 5.842 -81.0006)
		(width 0.11938)
		(layer "F.Cu")
		(net "FPGA_OUT_GPS_LED_BLUE_N")
	)
	(segment
		(start 10.73531 -77.91831)
		(end 8.18769 -77.91831)
		(width 0.11938)
		(layer "F.Cu")
		(net "FPGA_OUT_GPS_LED_BLUE_N")
	)
	(segment
		(start 8.18769 -77.91831)
		(end 5.842 -80.264)
		(width 0.11938)
		(layer "F.Cu")
		(net "FPGA_OUT_GPS_LED_BLUE_N")
	)
	(segment
		(start 99.846892 -52.82311)
		(end 99.34702 -53.322982)
		(width 0.11938)
		(layer "F.Cu")
		(net "FPGA_OUT_GPS_LED_BLUE_N")
	)
	(via
		(at 24.765 -54.356)
		(size 0.508)
		(drill 0.254)
		(layers "F.Cu" "B.Cu")
		(net "FPGA_OUT_GPS_LED_BLUE_N")
	)
	(via
		(at 11.303 -78.486)
		(size 0.508)
		(drill 0.254)
		(layers "F.Cu" "B.Cu")
		(net "FPGA_OUT_GPS_LED_BLUE_N")
	)
	(via
		(at 99.34702 -53.322982)
		(size 0.4572)
		(drill 0.2032)
		(layers "F.Cu" "B.Cu")
		(net "FPGA_OUT_GPS_LED_BLUE_N")
	)
	(segment
		(start 15.494 -59.944)
		(end 15.875 -59.563)
		(width 0.127)
		(layer "In2.Cu")
		(net "FPGA_OUT_GPS_LED_BLUE_N")
	)
	(segment
		(start 11.303 -78.486)
		(end 12.573 -77.216)
		(width 0.127)
		(layer "In2.Cu")
		(net "FPGA_OUT_GPS_LED_BLUE_N")
	)
	(segment
		(start 12.573 -77.216)
		(end 12.573 -73.025)
		(width 0.127)
		(layer "In2.Cu")
		(net "FPGA_OUT_GPS_LED_BLUE_N")
	)
	(segment
		(start 15.33398 -66.458338)
		(end 15.494 -66.298318)
		(width 0.127)
		(layer "In2.Cu")
		(net "FPGA_OUT_GPS_LED_BLUE_N")
	)
	(segment
		(start 16.0655 -56.101742)
		(end 17.811242 -54.356)
		(width 0.127)
		(layer "In2.Cu")
		(net "FPGA_OUT_GPS_LED_BLUE_N")
	)
	(segment
		(start 15.875 -59.563)
		(end 15.875 -58.327036)
		(width 0.127)
		(layer "In2.Cu")
		(net "FPGA_OUT_GPS_LED_BLUE_N")
	)
	(segment
		(start 15.33398 -70.26402)
		(end 15.33398 -66.458338)
		(width 0.127)
		(layer "In2.Cu")
		(net "FPGA_OUT_GPS_LED_BLUE_N")
	)
	(segment
		(start 16.0655 -58.136536)
		(end 16.0655 -56.101742)
		(width 0.127)
		(layer "In2.Cu")
		(net "FPGA_OUT_GPS_LED_BLUE_N")
	)
	(segment
		(start 15.875 -58.327036)
		(end 16.0655 -58.136536)
		(width 0.127)
		(layer "In2.Cu")
		(net "FPGA_OUT_GPS_LED_BLUE_N")
	)
	(segment
		(start 15.494 -66.298318)
		(end 15.494 -59.944)
		(width 0.127)
		(layer "In2.Cu")
		(net "FPGA_OUT_GPS_LED_BLUE_N")
	)
	(segment
		(start 17.811242 -54.356)
		(end 24.765 -54.356)
		(width 0.127)
		(layer "In2.Cu")
		(net "FPGA_OUT_GPS_LED_BLUE_N")
	)
	(segment
		(start 12.573 -73.025)
		(end 15.33398 -70.26402)
		(width 0.127)
		(layer "In2.Cu")
		(net "FPGA_OUT_GPS_LED_BLUE_N")
	)
	(segment
		(start 94.615 -60.833)
		(end 94.105222 -60.323222)
		(width 0.127)
		(layer "In7.Cu")
		(net "FPGA_OUT_GPS_LED_BLUE_N")
	)
	(segment
		(start 25.4635 -54.356)
		(end 24.765 -54.356)
		(width 0.127)
		(layer "In7.Cu")
		(net "FPGA_OUT_GPS_LED_BLUE_N")
	)
	(segment
		(start 75.370436 -59.4487)
		(end 30.5562 -59.4487)
		(width 0.127)
		(layer "In7.Cu")
		(net "FPGA_OUT_GPS_LED_BLUE_N")
	)
	(segment
		(start 91.868498 -61.1505)
		(end 91.330272 -61.1505)
		(width 0.127)
		(layer "In7.Cu")
		(net "FPGA_OUT_GPS_LED_BLUE_N")
	)
	(segment
		(start 80.7593 -61.3283)
		(end 80.3021 -60.8711)
		(width 0.127)
		(layer "In7.Cu")
		(net "FPGA_OUT_GPS_LED_BLUE_N")
	)
	(segment
		(start 90.7415 -61.831982)
		(end 90.406982 -62.1665)
		(width 0.127)
		(layer "In7.Cu")
		(net "FPGA_OUT_GPS_LED_BLUE_N")
	)
	(segment
		(start 97.663 -60.325)
		(end 97.155 -60.833)
		(width 0.127)
		(layer "In7.Cu")
		(net "FPGA_OUT_GPS_LED_BLUE_N")
	)
	(segment
		(start 90.7415 -61.739272)
		(end 90.7415 -61.831982)
		(width 0.127)
		(layer "In7.Cu")
		(net "FPGA_OUT_GPS_LED_BLUE_N")
	)
	(segment
		(start 99.34702 -55.071772)
		(end 98.171 -56.247792)
		(width 0.127)
		(layer "In7.Cu")
		(net "FPGA_OUT_GPS_LED_BLUE_N")
	)
	(segment
		(start 94.105222 -60.323222)
		(end 92.695776 -60.323222)
		(width 0.127)
		(layer "In7.Cu")
		(net "FPGA_OUT_GPS_LED_BLUE_N")
	)
	(segment
		(start 76.792836 -60.8711)
		(end 75.370436 -59.4487)
		(width 0.127)
		(layer "In7.Cu")
		(net "FPGA_OUT_GPS_LED_BLUE_N")
	)
	(segment
		(start 98.171 -59.055)
		(end 97.663 -59.563)
		(width 0.127)
		(layer "In7.Cu")
		(net "FPGA_OUT_GPS_LED_BLUE_N")
	)
	(segment
		(start 90.406982 -62.1665)
		(end 88.130888 -62.1665)
		(width 0.127)
		(layer "In7.Cu")
		(net "FPGA_OUT_GPS_LED_BLUE_N")
	)
	(segment
		(start 98.171 -56.247792)
		(end 98.171 -59.055)
		(width 0.127)
		(layer "In7.Cu")
		(net "FPGA_OUT_GPS_LED_BLUE_N")
	)
	(segment
		(start 30.5562 -59.4487)
		(end 25.4635 -54.356)
		(width 0.127)
		(layer "In7.Cu")
		(net "FPGA_OUT_GPS_LED_BLUE_N")
	)
	(segment
		(start 97.155 -60.833)
		(end 94.615 -60.833)
		(width 0.127)
		(layer "In7.Cu")
		(net "FPGA_OUT_GPS_LED_BLUE_N")
	)
	(segment
		(start 87.292688 -61.3283)
		(end 80.7593 -61.3283)
		(width 0.127)
		(layer "In7.Cu")
		(net "FPGA_OUT_GPS_LED_BLUE_N")
	)
	(segment
		(start 97.663 -59.563)
		(end 97.663 -60.325)
		(width 0.127)
		(layer "In7.Cu")
		(net "FPGA_OUT_GPS_LED_BLUE_N")
	)
	(segment
		(start 91.330272 -61.1505)
		(end 90.7415 -61.739272)
		(width 0.127)
		(layer "In7.Cu")
		(net "FPGA_OUT_GPS_LED_BLUE_N")
	)
	(segment
		(start 92.695776 -60.323222)
		(end 91.868498 -61.1505)
		(width 0.127)
		(layer "In7.Cu")
		(net "FPGA_OUT_GPS_LED_BLUE_N")
	)
	(segment
		(start 99.34702 -53.322982)
		(end 99.34702 -55.071772)
		(width 0.127)
		(layer "In7.Cu")
		(net "FPGA_OUT_GPS_LED_BLUE_N")
	)
	(segment
		(start 80.3021 -60.8711)
		(end 76.792836 -60.8711)
		(width 0.127)
		(layer "In7.Cu")
		(net "FPGA_OUT_GPS_LED_BLUE_N")
	)
	(segment
		(start 88.130888 -62.1665)
		(end 87.292688 -61.3283)
		(width 0.127)
		(layer "In7.Cu")
		(net "FPGA_OUT_GPS_LED_BLUE_N")
	)
	(segment
		(start 14.149832 -50.239168)
		(end 13.462 -50.927)
		(width 0.11938)
		(layer "F.Cu")
		(net "UNNAMED_12_74HCT2G125DPTSSOP8_9")
	)
	(segment
		(start 13.462 -50.927)
		(end 13.462 -52.0446)
		(width 0.11938)
		(layer "F.Cu")
		(net "UNNAMED_12_74HCT2G125DPTSSOP8_9")
	)
	(segment
		(start 14.149832 -48.790098)
		(end 14.149832 -50.239168)
		(width 0.11938)
		(layer "F.Cu")
		(net "UNNAMED_12_74HCT2G125DPTSSOP8_9")
	)
	(via
		(at 13.462 -50.927)
		(size 0.508)
		(drill 0.254)
		(layers "F.Cu" "B.Cu")
		(net "UNNAMED_12_74HCT2G125DPTSSOP8_9")
	)
	(segment
		(start 13.462 -52.0446)
		(end 13.462 -50.927)
		(width 0.11938)
		(layer "B.Cu")
		(net "UNNAMED_12_74HCT2G125DPTSSOP8_9")
	)
	(segment
		(start 13.462 -65.6336)
		(end 13.462 -64.9478)
		(width 0.11938)
		(layer "F.Cu")
		(net "UNNAMED_12_74HCT2G125DPTSSOP8_6")
	)
	(segment
		(start 14.149832 -64.14262)
		(end 14.149832 -63.290196)
		(width 0.11938)
		(layer "F.Cu")
		(net "UNNAMED_12_74HCT2G125DPTSSOP8_6")
	)
	(segment
		(start 14.0208 -64.271652)
		(end 14.149832 -64.14262)
		(width 0.11938)
		(layer "F.Cu")
		(net "UNNAMED_12_74HCT2G125DPTSSOP8_6")
	)
	(segment
		(start 14.0208 -64.389)
		(end 14.0208 -64.271652)
		(width 0.11938)
		(layer "F.Cu")
		(net "UNNAMED_12_74HCT2G125DPTSSOP8_6")
	)
	(segment
		(start 13.462 -64.9478)
		(end 14.0208 -64.389)
		(width 0.11938)
		(layer "F.Cu")
		(net "UNNAMED_12_74HCT2G125DPTSSOP8_6")
	)
	(via
		(at 14.0208 -64.389)
		(size 0.508)
		(drill 0.254)
		(layers "F.Cu" "B.Cu")
		(net "UNNAMED_12_74HCT2G125DPTSSOP8_6")
	)
	(segment
		(start 14.0208 -64.389)
		(end 13.462 -64.9478)
		(width 0.11938)
		(layer "B.Cu")
		(net "UNNAMED_12_74HCT2G125DPTSSOP8_6")
	)
	(segment
		(start 13.462 -64.9478)
		(end 13.462 -65.6336)
		(width 0.11938)
		(layer "B.Cu")
		(net "UNNAMED_12_74HCT2G125DPTSSOP8_6")
	)
	(segment
		(start 6.9215 -53.0225)
		(end 6.9215 -53.2511)
		(width 0.11938)
		(layer "F.Cu")
		(net "SMA2_SIG_IO_CONN")
	)
	(segment
		(start 11.557 -46.355)
		(end 9.017 -48.895)
		(width 0.11938)
		(layer "F.Cu")
		(net "SMA2_SIG_IO_CONN")
	)
	(segment
		(start 9.017 -48.895)
		(end 9.017 -52.705)
		(width 0.11938)
		(layer "F.Cu")
		(net "SMA2_SIG_IO_CONN")
	)
	(segment
		(start 4.073906 -50.174906)
		(end 6.9215 -53.0225)
		(width 0.11938)
		(layer "F.Cu")
		(net "SMA2_SIG_IO_CONN")
	)
	(segment
		(start 4.073906 -47.099982)
		(end 4.073906 -50.174906)
		(width 0.11938)
		(layer "F.Cu")
		(net "SMA2_SIG_IO_CONN")
	)
	(segment
		(start 11.557 -45.2374)
		(end 11.557 -46.355)
		(width 0.11938)
		(layer "F.Cu")
		(net "SMA2_SIG_IO_CONN")
	)
	(segment
		(start 9.017 -52.705)
		(end 8.4709 -53.2511)
		(width 0.11938)
		(layer "F.Cu")
		(net "SMA2_SIG_IO_CONN")
	)
	(segment
		(start 8.4709 -53.2511)
		(end 6.9215 -53.2511)
		(width 0.11938)
		(layer "F.Cu")
		(net "SMA2_SIG_IO_CONN")
	)
	(via
		(at 11.557 -46.355)
		(size 0.508)
		(drill 0.254)
		(layers "F.Cu" "B.Cu")
		(net "SMA2_SIG_IO_CONN")
	)
	(segment
		(start 11.3919 -55.4609)
		(end 11.684 -55.753)
		(width 0.11938)
		(layer "F.Cu")
		(net "SMA1_SIG_IO_CONN")
	)
	(segment
		(start 11.684 -55.753)
		(end 11.798808 -55.867808)
		(width 0.11938)
		(layer "F.Cu")
		(net "SMA1_SIG_IO_CONN")
	)
	(segment
		(start 6.9215 -55.6895)
		(end 6.9215 -55.4609)
		(width 0.11938)
		(layer "F.Cu")
		(net "SMA1_SIG_IO_CONN")
	)
	(segment
		(start 4.073906 -58.537094)
		(end 6.9215 -55.6895)
		(width 0.11938)
		(layer "F.Cu")
		(net "SMA1_SIG_IO_CONN")
	)
	(segment
		(start 11.798808 -55.867808)
		(end 11.798808 -56.7182)
		(width 0.11938)
		(layer "F.Cu")
		(net "SMA1_SIG_IO_CONN")
	)
	(segment
		(start 4.073906 -61.60008)
		(end 4.073906 -58.537094)
		(width 0.11938)
		(layer "F.Cu")
		(net "SMA1_SIG_IO_CONN")
	)
	(segment
		(start 6.9215 -55.4609)
		(end 11.3919 -55.4609)
		(width 0.11938)
		(layer "F.Cu")
		(net "SMA1_SIG_IO_CONN")
	)
	(via
		(at 11.684 -55.753)
		(size 0.508)
		(drill 0.254)
		(layers "F.Cu" "B.Cu")
		(net "SMA1_SIG_IO_CONN")
	)
	(segment
		(start 10.16 -19.812)
		(end 10.16 -21.844)
		(width 0.11938)
		(layer "F.Cu")
		(net "SMA4_SIG_IO_CONN")
	)
	(segment
		(start 4.073906 -18.10004)
		(end 4.073906 -20.837906)
		(width 0.11938)
		(layer "F.Cu")
		(net "SMA4_SIG_IO_CONN")
	)
	(segment
		(start 10.16 -21.844)
		(end 7.7089 -24.2951)
		(width 0.11938)
		(layer "F.Cu")
		(net "SMA4_SIG_IO_CONN")
	)
	(segment
		(start 6.9215 -23.6855)
		(end 6.9215 -24.2951)
		(width 0.11938)
		(layer "F.Cu")
		(net "SMA4_SIG_IO_CONN")
	)
	(segment
		(start 4.073906 -20.837906)
		(end 6.9215 -23.6855)
		(width 0.11938)
		(layer "F.Cu")
		(net "SMA4_SIG_IO_CONN")
	)
	(segment
		(start 7.7089 -24.2951)
		(end 6.9215 -24.2951)
		(width 0.11938)
		(layer "F.Cu")
		(net "SMA4_SIG_IO_CONN")
	)
	(segment
		(start 11.303 -18.669)
		(end 10.16 -19.812)
		(width 0.11938)
		(layer "F.Cu")
		(net "SMA4_SIG_IO_CONN")
	)
	(via
		(at 11.303 -18.669)
		(size 0.508)
		(drill 0.254)
		(layers "F.Cu" "B.Cu")
		(net "SMA4_SIG_IO_CONN")
	)
	(segment
		(start 11.303 -18.669)
		(end 12.065 -18.669)
		(width 0.11938)
		(layer "B.Cu")
		(net "SMA4_SIG_IO_CONN")
	)
	(segment
		(start 12.065 -18.669)
		(end 13.0302 -17.7038)
		(width 0.11938)
		(layer "B.Cu")
		(net "SMA4_SIG_IO_CONN")
	)
	(segment
		(start 13.0302 -17.7038)
		(end 13.462 -17.7038)
		(width 0.11938)
		(layer "B.Cu")
		(net "SMA4_SIG_IO_CONN")
	)
	(segment
		(start 6.9215 -26.8605)
		(end 6.9215 -26.5049)
		(width 0.11938)
		(layer "F.Cu")
		(net "SMA3_SIG_IO_CONN")
	)
	(segment
		(start 11.557 -27.53106)
		(end 11.557 -26.51506)
		(width 0.11938)
		(layer "F.Cu")
		(net "SMA3_SIG_IO_CONN")
	)
	(segment
		(start 11.557 -26.51506)
		(end 11.54684 -26.5049)
		(width 0.11938)
		(layer "F.Cu")
		(net "SMA3_SIG_IO_CONN")
	)
	(segment
		(start 11.54684 -26.5049)
		(end 6.9215 -26.5049)
		(width 0.11938)
		(layer "F.Cu")
		(net "SMA3_SIG_IO_CONN")
	)
	(segment
		(start 4.073906 -32.599884)
		(end 4.073906 -29.708094)
		(width 0.11938)
		(layer "F.Cu")
		(net "SMA3_SIG_IO_CONN")
	)
	(segment
		(start 4.073906 -29.708094)
		(end 6.9215 -26.8605)
		(width 0.11938)
		(layer "F.Cu")
		(net "SMA3_SIG_IO_CONN")
	)
	(via
		(at 11.557 -26.51506)
		(size 0.508)
		(drill 0.254)
		(layers "F.Cu" "B.Cu")
		(net "SMA3_SIG_IO_CONN")
	)
	(segment
		(start 13.589 -46.609)
		(end 13.64996 -46.54804)
		(width 0.11938)
		(layer "F.Cu")
		(net "BF_SMA2_SIG_IO_CONN")
	)
	(segment
		(start 13.335 -46.609)
		(end 13.150088 -46.424088)
		(width 0.11938)
		(layer "F.Cu")
		(net "BF_SMA2_SIG_IO_CONN")
	)
	(segment
		(start 13.150088 -45.409866)
		(end 13.150088 -44.569888)
		(width 0.11938)
		(layer "F.Cu")
		(net "BF_SMA2_SIG_IO_CONN")
	)
	(segment
		(start 13.150088 -46.424088)
		(end 13.150088 -45.409866)
		(width 0.11938)
		(layer "F.Cu")
		(net "BF_SMA2_SIG_IO_CONN")
	)
	(segment
		(start 13.589 -46.609)
		(end 13.335 -46.609)
		(width 0.11938)
		(layer "F.Cu")
		(net "BF_SMA2_SIG_IO_CONN")
	)
	(segment
		(start 12.7508 -44.1706)
		(end 11.557 -44.1706)
		(width 0.11938)
		(layer "F.Cu")
		(net "BF_SMA2_SIG_IO_CONN")
	)
	(segment
		(start 13.150088 -44.569888)
		(end 12.7508 -44.1706)
		(width 0.11938)
		(layer "F.Cu")
		(net "BF_SMA2_SIG_IO_CONN")
	)
	(segment
		(start 13.64996 -46.54804)
		(end 13.64996 -45.409866)
		(width 0.11938)
		(layer "F.Cu")
		(net "BF_SMA2_SIG_IO_CONN")
	)
	(segment
		(start 11.557 -44.1706)
		(end 11.557 -42.8244)
		(width 0.11938)
		(layer "F.Cu")
		(net "BF_SMA2_SIG_IO_CONN")
	)
	(via
		(at 13.589 -46.609)
		(size 0.508)
		(drill 0.254)
		(layers "F.Cu" "B.Cu")
		(net "BF_SMA2_SIG_IO_CONN")
	)
	(segment
		(start 13.5128 -61.007498)
		(end 13.2588 -61.007498)
		(width 0.11938)
		(layer "F.Cu")
		(net "BF_SMA1_SIG_IO_CONN")
	)
	(segment
		(start 11.4808 -59.0804)
		(end 11.4808 -58.103008)
		(width 0.11938)
		(layer "F.Cu")
		(net "BF_SMA1_SIG_IO_CONN")
	)
	(segment
		(start 13.2588 -61.007498)
		(end 13.150088 -60.898786)
		(width 0.11938)
		(layer "F.Cu")
		(net "BF_SMA1_SIG_IO_CONN")
	)
	(segment
		(start 13.64996 -60.870338)
		(end 13.5128 -61.007498)
		(width 0.11938)
		(layer "F.Cu")
		(net "BF_SMA1_SIG_IO_CONN")
	)
	(segment
		(start 13.150088 -59.276488)
		(end 12.954 -59.0804)
		(width 0.11938)
		(layer "F.Cu")
		(net "BF_SMA1_SIG_IO_CONN")
	)
	(segment
		(start 11.4808 -58.103008)
		(end 11.798808 -57.785)
		(width 0.11938)
		(layer "F.Cu")
		(net "BF_SMA1_SIG_IO_CONN")
	)
	(segment
		(start 13.64996 -59.909964)
		(end 13.64996 -60.870338)
		(width 0.11938)
		(layer "F.Cu")
		(net "BF_SMA1_SIG_IO_CONN")
	)
	(segment
		(start 13.150088 -60.898786)
		(end 13.150088 -59.909964)
		(width 0.11938)
		(layer "F.Cu")
		(net "BF_SMA1_SIG_IO_CONN")
	)
	(segment
		(start 13.150088 -59.909964)
		(end 13.150088 -59.276488)
		(width 0.11938)
		(layer "F.Cu")
		(net "BF_SMA1_SIG_IO_CONN")
	)
	(segment
		(start 12.954 -59.0804)
		(end 11.4808 -59.0804)
		(width 0.11938)
		(layer "F.Cu")
		(net "BF_SMA1_SIG_IO_CONN")
	)
	(via
		(at 13.5128 -61.007498)
		(size 0.508)
		(drill 0.254)
		(layers "F.Cu" "B.Cu")
		(net "BF_SMA1_SIG_IO_CONN")
	)
	(segment
		(start 13.56233 -17.42567)
		(end 13.23467 -17.42567)
		(width 0.11938)
		(layer "F.Cu")
		(net "BF_SMA4_SIG_IO_CONN")
	)
	(segment
		(start 13.64996 -16.409924)
		(end 13.64996 -17.33804)
		(width 0.11938)
		(layer "F.Cu")
		(net "BF_SMA4_SIG_IO_CONN")
	)
	(segment
		(start 11.2522 -16.0274)
		(end 11.981688 -15.297912)
		(width 0.11938)
		(layer "F.Cu")
		(net "BF_SMA4_SIG_IO_CONN")
	)
	(segment
		(start 13.64996 -17.33804)
		(end 13.56233 -17.42567)
		(width 0.11938)
		(layer "F.Cu")
		(net "BF_SMA4_SIG_IO_CONN")
	)
	(segment
		(start 11.981688 -15.297912)
		(end 12.827 -15.297912)
		(width 0.11938)
		(layer "F.Cu")
		(net "BF_SMA4_SIG_IO_CONN")
	)
	(segment
		(start 13.150088 -15.621)
		(end 13.150088 -16.409924)
		(width 0.11938)
		(layer "F.Cu")
		(net "BF_SMA4_SIG_IO_CONN")
	)
	(segment
		(start 13.150088 -17.341088)
		(end 13.150088 -16.409924)
		(width 0.11938)
		(layer "F.Cu")
		(net "BF_SMA4_SIG_IO_CONN")
	)
	(segment
		(start 11.2522 -16.4338)
		(end 11.2522 -16.0274)
		(width 0.11938)
		(layer "F.Cu")
		(net "BF_SMA4_SIG_IO_CONN")
	)
	(segment
		(start 13.23467 -17.42567)
		(end 13.150088 -17.341088)
		(width 0.11938)
		(layer "F.Cu")
		(net "BF_SMA4_SIG_IO_CONN")
	)
	(segment
		(start 12.827 -15.297912)
		(end 13.150088 -15.621)
		(width 0.11938)
		(layer "F.Cu")
		(net "BF_SMA4_SIG_IO_CONN")
	)
	(via
		(at 12.827 -15.297912)
		(size 0.508)
		(drill 0.254)
		(layers "F.Cu" "B.Cu")
		(net "BF_SMA4_SIG_IO_CONN")
	)
	(segment
		(start 12.827 -15.297912)
		(end 13.150088 -15.297912)
		(width 0.11938)
		(layer "B.Cu")
		(net "BF_SMA4_SIG_IO_CONN")
	)
	(segment
		(start 13.150088 -15.297912)
		(end 13.462 -15.609824)
		(width 0.11938)
		(layer "B.Cu")
		(net "BF_SMA4_SIG_IO_CONN")
	)
	(segment
		(start 13.462 -15.609824)
		(end 13.462 -16.637)
		(width 0.11938)
		(layer "B.Cu")
		(net "BF_SMA4_SIG_IO_CONN")
	)
	(segment
		(start 13.150088 -30.091888)
		(end 13.150088 -30.909768)
		(width 0.11938)
		(layer "F.Cu")
		(net "BF_SMA3_SIG_IO_CONN")
	)
	(segment
		(start 13.64996 -32.004)
		(end 13.64996 -30.909768)
		(width 0.11938)
		(layer "F.Cu")
		(net "BF_SMA3_SIG_IO_CONN")
	)
	(segment
		(start 12.9794 -29.9212)
		(end 13.150088 -30.091888)
		(width 0.11938)
		(layer "F.Cu")
		(net "BF_SMA3_SIG_IO_CONN")
	)
	(segment
		(start 13.269468 -32.004)
		(end 13.64996 -32.004)
		(width 0.11938)
		(layer "F.Cu")
		(net "BF_SMA3_SIG_IO_CONN")
	)
	(segment
		(start 11.557 -29.9212)
		(end 11.557 -28.59786)
		(width 0.11938)
		(layer "F.Cu")
		(net "BF_SMA3_SIG_IO_CONN")
	)
	(segment
		(start 11.557 -29.9212)
		(end 12.9794 -29.9212)
		(width 0.11938)
		(layer "F.Cu")
		(net "BF_SMA3_SIG_IO_CONN")
	)
	(segment
		(start 13.150088 -30.909768)
		(end 13.150088 -31.88462)
		(width 0.11938)
		(layer "F.Cu")
		(net "BF_SMA3_SIG_IO_CONN")
	)
	(segment
		(start 13.150088 -31.88462)
		(end 13.269468 -32.004)
		(width 0.11938)
		(layer "F.Cu")
		(net "BF_SMA3_SIG_IO_CONN")
	)
	(via
		(at 13.64996 -32.004)
		(size 0.508)
		(drill 0.254)
		(layers "F.Cu" "B.Cu")
		(net "BF_SMA3_SIG_IO_CONN")
	)
	(segment
		(start 13.64996 -49.67224)
		(end 12.3952 -50.927)
		(width 0.11938)
		(layer "F.Cu")
		(net "BF_ANT2_IN")
	)
	(segment
		(start 13.64996 -48.790098)
		(end 13.64996 -49.67224)
		(width 0.11938)
		(layer "F.Cu")
		(net "BF_ANT2_IN")
	)
	(segment
		(start 12.3952 -50.927)
		(end 12.192 -50.927)
		(width 0.11938)
		(layer "F.Cu")
		(net "BF_ANT2_IN")
	)
	(segment
		(start 12.192 -50.927)
		(end 12.192 -52.0446)
		(width 0.11938)
		(layer "F.Cu")
		(net "BF_ANT2_IN")
	)
	(via
		(at 12.192 -50.927)
		(size 0.508)
		(drill 0.254)
		(layers "F.Cu" "B.Cu")
		(net "BF_ANT2_IN")
	)
	(segment
		(start 13.64996 -63.88862)
		(end 13.53058 -64.008)
		(width 0.11938)
		(layer "F.Cu")
		(net "BF_ANT1_IN")
	)
	(segment
		(start 13.64996 -63.290196)
		(end 13.64996 -63.88862)
		(width 0.11938)
		(layer "F.Cu")
		(net "BF_ANT1_IN")
	)
	(segment
		(start 12.1412 -64.3128)
		(end 12.1412 -65.2526)
		(width 0.11938)
		(layer "F.Cu")
		(net "BF_ANT1_IN")
	)
	(segment
		(start 12.446 -64.008)
		(end 12.319 -64.135)
		(width 0.11938)
		(layer "F.Cu")
		(net "BF_ANT1_IN")
	)
	(segment
		(start 13.53058 -64.008)
		(end 12.446 -64.008)
		(width 0.11938)
		(layer "F.Cu")
		(net "BF_ANT1_IN")
	)
	(segment
		(start 12.319 -64.135)
		(end 12.1412 -64.3128)
		(width 0.11938)
		(layer "F.Cu")
		(net "BF_ANT1_IN")
	)
	(via
		(at 12.319 -64.135)
		(size 0.508)
		(drill 0.254)
		(layers "F.Cu" "B.Cu")
		(net "BF_ANT1_IN")
	)
	(segment
		(start 13.64996 -20.64004)
		(end 13.081 -21.209)
		(width 0.11938)
		(layer "F.Cu")
		(net "BF_ANT4_IN")
	)
	(segment
		(start 12.319 -21.971)
		(end 12.319 -22.4536)
		(width 0.11938)
		(layer "F.Cu")
		(net "BF_ANT4_IN")
	)
	(segment
		(start 13.64996 -19.790156)
		(end 13.64996 -20.64004)
		(width 0.11938)
		(layer "F.Cu")
		(net "BF_ANT4_IN")
	)
	(segment
		(start 13.081 -21.209)
		(end 12.319 -21.971)
		(width 0.11938)
		(layer "F.Cu")
		(net "BF_ANT4_IN")
	)
	(via
		(at 13.081 -21.209)
		(size 0.508)
		(drill 0.254)
		(layers "F.Cu" "B.Cu")
		(net "BF_ANT4_IN")
	)
	(segment
		(start 13.64996 -34.975546)
		(end 13.64996 -34.29)
		(width 0.11938)
		(layer "F.Cu")
		(net "BF_ANT3_IN")
	)
	(segment
		(start 12.065 -36.5506)
		(end 12.192 -36.6776)
		(width 0.11938)
		(layer "F.Cu")
		(net "BF_ANT3_IN")
	)
	(segment
		(start 12.938506 -35.687)
		(end 13.64996 -34.975546)
		(width 0.11938)
		(layer "F.Cu")
		(net "BF_ANT3_IN")
	)
	(segment
		(start 12.065 -35.687)
		(end 12.065 -36.5506)
		(width 0.11938)
		(layer "F.Cu")
		(net "BF_ANT3_IN")
	)
	(segment
		(start 12.065 -35.687)
		(end 12.938506 -35.687)
		(width 0.11938)
		(layer "F.Cu")
		(net "BF_ANT3_IN")
	)
	(via
		(at 12.065 -35.687)
		(size 0.508)
		(drill 0.254)
		(layers "F.Cu" "B.Cu")
		(net "BF_ANT3_IN")
	)
	(segment
		(start 160.909 -24.511)
		(end 162.0266 -24.511)
		(width 0.11938)
		(layer "F.Cu")
		(net "UNNAMED_6_LM75BDPTSSOP8_I81_A2")
	)
	(segment
		(start 159.1437 -25.56764)
		(end 159.72536 -25.56764)
		(width 0.11938)
		(layer "F.Cu")
		(net "UNNAMED_6_LM75BDPTSSOP8_I81_A2")
	)
	(segment
		(start 159.72536 -25.56764)
		(end 160.782 -24.511)
		(width 0.11938)
		(layer "F.Cu")
		(net "UNNAMED_6_LM75BDPTSSOP8_I81_A2")
	)
	(segment
		(start 160.782 -24.511)
		(end 160.909 -24.511)
		(width 0.11938)
		(layer "F.Cu")
		(net "UNNAMED_6_LM75BDPTSSOP8_I81_A2")
	)
	(via
		(at 160.909 -24.511)
		(size 0.508)
		(drill 0.254)
		(layers "F.Cu" "B.Cu")
		(net "UNNAMED_6_LM75BDPTSSOP8_I81_A2")
	)
	(segment
		(start 162.0266 -24.511)
		(end 160.909 -24.511)
		(width 0.11938)
		(layer "B.Cu")
		(net "UNNAMED_6_LM75BDPTSSOP8_I81_A2")
	)
	(segment
		(start 160.59912 -26.21788)
		(end 160.909 -25.908)
		(width 0.11938)
		(layer "F.Cu")
		(net "UNNAMED_6_LM75BDPTSSOP8_I81_A1")
	)
	(segment
		(start 160.909 -25.908)
		(end 162.0266 -25.908)
		(width 0.11938)
		(layer "F.Cu")
		(net "UNNAMED_6_LM75BDPTSSOP8_I81_A1")
	)
	(segment
		(start 159.1437 -26.21788)
		(end 160.59912 -26.21788)
		(width 0.11938)
		(layer "F.Cu")
		(net "UNNAMED_6_LM75BDPTSSOP8_I81_A1")
	)
	(via
		(at 160.909 -25.908)
		(size 0.508)
		(drill 0.254)
		(layers "F.Cu" "B.Cu")
		(net "UNNAMED_6_LM75BDPTSSOP8_I81_A1")
	)
	(segment
		(start 162.0266 -25.908)
		(end 160.909 -25.908)
		(width 0.11938)
		(layer "B.Cu")
		(net "UNNAMED_6_LM75BDPTSSOP8_I81_A1")
	)
	(segment
		(start 160.909 -27.432)
		(end 162.0266 -27.432)
		(width 0.11938)
		(layer "F.Cu")
		(net "UNNAMED_6_LM75BDPTSSOP8_I81_A0")
	)
	(segment
		(start 160.34512 -26.86812)
		(end 160.909 -27.432)
		(width 0.11938)
		(layer "F.Cu")
		(net "UNNAMED_6_LM75BDPTSSOP8_I81_A0")
	)
	(segment
		(start 159.1437 -26.86812)
		(end 160.34512 -26.86812)
		(width 0.11938)
		(layer "F.Cu")
		(net "UNNAMED_6_LM75BDPTSSOP8_I81_A0")
	)
	(via
		(at 160.909 -27.432)
		(size 0.508)
		(drill 0.254)
		(layers "F.Cu" "B.Cu")
		(net "UNNAMED_6_LM75BDPTSSOP8_I81_A0")
	)
	(segment
		(start 162.0266 -27.432)
		(end 160.909 -27.432)
		(width 0.11938)
		(layer "B.Cu")
		(net "UNNAMED_6_LM75BDPTSSOP8_I81_A0")
	)
	(segment
		(start 53.25364 -76.92644)
		(end 52.959 -76.6318)
		(width 0.11938)
		(layer "F.Cu")
		(net "UNNAMED_6_LM75BDPTSSOP8_I59_A2")
	)
	(segment
		(start 53.25364 -78.3463)
		(end 53.25364 -76.92644)
		(width 0.11938)
		(layer "F.Cu")
		(net "UNNAMED_6_LM75BDPTSSOP8_I59_A2")
	)
	(segment
		(start 52.9082 -76.581)
		(end 52.9082 -75.5142)
		(width 0.11938)
		(layer "F.Cu")
		(net "UNNAMED_6_LM75BDPTSSOP8_I59_A2")
	)
	(segment
		(start 52.959 -76.6318)
		(end 52.9082 -76.581)
		(width 0.11938)
		(layer "F.Cu")
		(net "UNNAMED_6_LM75BDPTSSOP8_I59_A2")
	)
	(via
		(at 52.959 -76.6318)
		(size 0.4572)
		(drill 0.2032)
		(layers "F.Cu" "B.Cu")
		(net "UNNAMED_6_LM75BDPTSSOP8_I59_A2")
	)
	(segment
		(start 52.9082 -76.581)
		(end 52.9082 -75.5142)
		(width 0.11938)
		(layer "B.Cu")
		(net "UNNAMED_6_LM75BDPTSSOP8_I59_A2")
	)
	(segment
		(start 52.959 -76.6318)
		(end 52.9082 -76.581)
		(width 0.11938)
		(layer "B.Cu")
		(net "UNNAMED_6_LM75BDPTSSOP8_I59_A2")
	)
	(segment
		(start 53.90388 -78.3463)
		(end 53.90388 -77.28712)
		(width 0.11938)
		(layer "F.Cu")
		(net "UNNAMED_6_LM75BDPTSSOP8_I59_A1")
	)
	(segment
		(start 53.90388 -77.28712)
		(end 54.229 -76.962)
		(width 0.11938)
		(layer "F.Cu")
		(net "UNNAMED_6_LM75BDPTSSOP8_I59_A1")
	)
	(segment
		(start 54.0512 -76.454)
		(end 54.0512 -75.5142)
		(width 0.11938)
		(layer "F.Cu")
		(net "UNNAMED_6_LM75BDPTSSOP8_I59_A1")
	)
	(segment
		(start 54.229 -76.6318)
		(end 54.0512 -76.454)
		(width 0.11938)
		(layer "F.Cu")
		(net "UNNAMED_6_LM75BDPTSSOP8_I59_A1")
	)
	(segment
		(start 54.229 -76.962)
		(end 54.229 -76.6318)
		(width 0.11938)
		(layer "F.Cu")
		(net "UNNAMED_6_LM75BDPTSSOP8_I59_A1")
	)
	(via
		(at 54.229 -76.6318)
		(size 0.4572)
		(drill 0.2032)
		(layers "F.Cu" "B.Cu")
		(net "UNNAMED_6_LM75BDPTSSOP8_I59_A1")
	)
	(segment
		(start 54.0512 -75.5142)
		(end 54.0512 -76.454)
		(width 0.11938)
		(layer "B.Cu")
		(net "UNNAMED_6_LM75BDPTSSOP8_I59_A1")
	)
	(segment
		(start 54.0512 -76.454)
		(end 54.229 -76.6318)
		(width 0.11938)
		(layer "B.Cu")
		(net "UNNAMED_6_LM75BDPTSSOP8_I59_A1")
	)
	(segment
		(start 54.55412 -78.3463)
		(end 54.55412 -77.42428)
		(width 0.11938)
		(layer "F.Cu")
		(net "UNNAMED_6_LM75BDPTSSOP8_I59_A0")
	)
	(segment
		(start 55.1942 -76.327)
		(end 55.499 -76.6318)
		(width 0.11938)
		(layer "F.Cu")
		(net "UNNAMED_6_LM75BDPTSSOP8_I59_A0")
	)
	(segment
		(start 54.55412 -77.42428)
		(end 54.9402 -77.0382)
		(width 0.11938)
		(layer "F.Cu")
		(net "UNNAMED_6_LM75BDPTSSOP8_I59_A0")
	)
	(segment
		(start 55.1942 -75.5142)
		(end 55.1942 -76.327)
		(width 0.11938)
		(layer "F.Cu")
		(net "UNNAMED_6_LM75BDPTSSOP8_I59_A0")
	)
	(segment
		(start 54.9402 -77.0382)
		(end 55.0926 -77.0382)
		(width 0.11938)
		(layer "F.Cu")
		(net "UNNAMED_6_LM75BDPTSSOP8_I59_A0")
	)
	(segment
		(start 55.0926 -77.0382)
		(end 55.499 -76.6318)
		(width 0.11938)
		(layer "F.Cu")
		(net "UNNAMED_6_LM75BDPTSSOP8_I59_A0")
	)
	(via
		(at 55.499 -76.6318)
		(size 0.4572)
		(drill 0.2032)
		(layers "F.Cu" "B.Cu")
		(net "UNNAMED_6_LM75BDPTSSOP8_I59_A0")
	)
	(segment
		(start 55.1942 -76.327)
		(end 55.499 -76.6318)
		(width 0.11938)
		(layer "B.Cu")
		(net "UNNAMED_6_LM75BDPTSSOP8_I59_A0")
	)
	(segment
		(start 55.1942 -75.5142)
		(end 55.1942 -76.327)
		(width 0.11938)
		(layer "B.Cu")
		(net "UNNAMED_6_LM75BDPTSSOP8_I59_A0")
	)
	(via
		(at 74.295 -56.6039)
		(size 0.762)
		(drill 0.381)
		(layers "F.Cu" "B.Cu")
		(net "UNNAMED_527_POWERMOS3PNCHV1_I23")
	)
	(segment
		(start 75.057 -55.372)
		(end 74.295 -56.134)
		(width 0.11938)
		(layer "B.Cu")
		(net "UNNAMED_527_POWERMOS3PNCHV1_I23")
	)
	(segment
		(start 75.4761 -57.1881)
		(end 75.184 -56.896)
		(width 0.11938)
		(layer "B.Cu")
		(net "UNNAMED_527_POWERMOS3PNCHV1_I23")
	)
	(segment
		(start 74.4474 -57.8612)
		(end 75.4761 -57.8612)
		(width 0.11938)
		(layer "B.Cu")
		(net "UNNAMED_527_POWERMOS3PNCHV1_I23")
	)
	(segment
		(start 75.4761 -57.8612)
		(end 75.4761 -57.1881)
		(width 0.11938)
		(layer "B.Cu")
		(net "UNNAMED_527_POWERMOS3PNCHV1_I23")
	)
	(segment
		(start 73.914 -58.3946)
		(end 74.4474 -57.8612)
		(width 0.11938)
		(layer "B.Cu")
		(net "UNNAMED_527_POWERMOS3PNCHV1_I23")
	)
	(segment
		(start 75.3491 -55.372)
		(end 75.057 -55.372)
		(width 0.11938)
		(layer "B.Cu")
		(net "UNNAMED_527_POWERMOS3PNCHV1_I23")
	)
	(segment
		(start 74.5871 -56.896)
		(end 74.295 -56.6039)
		(width 0.11938)
		(layer "B.Cu")
		(net "UNNAMED_527_POWERMOS3PNCHV1_I23")
	)
	(segment
		(start 75.184 -56.896)
		(end 74.5871 -56.896)
		(width 0.11938)
		(layer "B.Cu")
		(net "UNNAMED_527_POWERMOS3PNCHV1_I23")
	)
	(segment
		(start 74.295 -56.134)
		(end 74.295 -56.6039)
		(width 0.11938)
		(layer "B.Cu")
		(net "UNNAMED_527_POWERMOS3PNCHV1_I23")
	)
	(via
		(at 74.93 -54.102)
		(size 0.762)
		(drill 0.381)
		(layers "F.Cu" "B.Cu")
		(net "UNNAMED_527_FUSE_I244_1")
	)
	(segment
		(start 77.6859 -58.801)
		(end 76.835 -58.801)
		(width 0.11938)
		(layer "B.Cu")
		(net "UNNAMED_527_FUSE_I244_1")
	)
	(segment
		(start 73.533 -55.499)
		(end 73.533 -56.14162)
		(width 0.11938)
		(layer "B.Cu")
		(net "UNNAMED_527_FUSE_I244_1")
	)
	(segment
		(start 75.311 -54.483)
		(end 74.93 -54.102)
		(width 0.11938)
		(layer "B.Cu")
		(net "UNNAMED_527_FUSE_I244_1")
	)
	(segment
		(start 76.097638 -54.483)
		(end 75.311 -54.483)
		(width 0.11938)
		(layer "B.Cu")
		(net "UNNAMED_527_FUSE_I244_1")
	)
	(segment
		(start 73.23582 -56.4388)
		(end 72.263 -56.4388)
		(width 0.11938)
		(layer "B.Cu")
		(net "UNNAMED_527_FUSE_I244_1")
	)
	(segment
		(start 76.54671 -54.932072)
		(end 76.097638 -54.483)
		(width 0.11938)
		(layer "B.Cu")
		(net "UNNAMED_527_FUSE_I244_1")
	)
	(segment
		(start 73.533 -56.14162)
		(end 73.23582 -56.4388)
		(width 0.11938)
		(layer "B.Cu")
		(net "UNNAMED_527_FUSE_I244_1")
	)
	(segment
		(start 74.93 -54.102)
		(end 73.533 -55.499)
		(width 0.11938)
		(layer "B.Cu")
		(net "UNNAMED_527_FUSE_I244_1")
	)
	(segment
		(start 72.263 -57.7088)
		(end 72.39 -57.8358)
		(width 0.11938)
		(layer "B.Cu")
		(net "UNNAMED_527_FUSE_I244_1")
	)
	(segment
		(start 72.263 -56.4388)
		(end 72.263 -57.7088)
		(width 0.11938)
		(layer "B.Cu")
		(net "UNNAMED_527_FUSE_I244_1")
	)
	(segment
		(start 76.835 -58.801)
		(end 76.54671 -58.51271)
		(width 0.11938)
		(layer "B.Cu")
		(net "UNNAMED_527_FUSE_I244_1")
	)
	(segment
		(start 76.54671 -58.51271)
		(end 76.54671 -54.932072)
		(width 0.11938)
		(layer "B.Cu")
		(net "UNNAMED_527_FUSE_I244_1")
	)
	(segment
		(start 154.5463 -27.51836)
		(end 153.63444 -27.51836)
		(width 0.11938)
		(layer "F.Cu")
		(net "R_LM75B_3_I2C_SDA")
	)
	(segment
		(start 151.2824 -27.432)
		(end 151.511 -27.432)
		(width 0.11938)
		(layer "F.Cu")
		(net "R_LM75B_3_I2C_SDA")
	)
	(segment
		(start 153.63444 -27.51836)
		(end 152.6159 -28.5369)
		(width 0.11938)
		(layer "F.Cu")
		(net "R_LM75B_3_I2C_SDA")
	)
	(segment
		(start 151.511 -27.432)
		(end 152.6159 -28.5369)
		(width 0.11938)
		(layer "F.Cu")
		(net "R_LM75B_3_I2C_SDA")
	)
	(via
		(at 152.6159 -28.5369)
		(size 0.508)
		(drill 0.254)
		(layers "F.Cu" "B.Cu")
		(net "R_LM75B_3_I2C_SDA")
	)
	(segment
		(start 56.388 -83.82)
		(end 56.9214 -83.82)
		(width 0.11938)
		(layer "F.Cu")
		(net "R_LM75B_2_I2C_SDA")
	)
	(segment
		(start 55.20436 -83.90636)
		(end 55.372 -84.074)
		(width 0.11938)
		(layer "F.Cu")
		(net "R_LM75B_2_I2C_SDA")
	)
	(segment
		(start 57.2516 -83.4898)
		(end 57.47512 -83.4898)
		(width 0.11938)
		(layer "F.Cu")
		(net "R_LM75B_2_I2C_SDA")
	)
	(segment
		(start 56.9214 -83.82)
		(end 57.2516 -83.4898)
		(width 0.11938)
		(layer "F.Cu")
		(net "R_LM75B_2_I2C_SDA")
	)
	(segment
		(start 55.20436 -82.9437)
		(end 55.20436 -83.90636)
		(width 0.11938)
		(layer "F.Cu")
		(net "R_LM75B_2_I2C_SDA")
	)
	(segment
		(start 56.134 -84.074)
		(end 56.388 -83.82)
		(width 0.11938)
		(layer "F.Cu")
		(net "R_LM75B_2_I2C_SDA")
	)
	(segment
		(start 55.372 -84.074)
		(end 56.134 -84.074)
		(width 0.11938)
		(layer "F.Cu")
		(net "R_LM75B_2_I2C_SDA")
	)
	(via
		(at 56.388 -83.82)
		(size 0.4572)
		(drill 0.2032)
		(layers "F.Cu" "B.Cu")
		(net "R_LM75B_2_I2C_SDA")
	)
	(segment
		(start 147.32 -26.6192)
		(end 147.32 -25.654)
		(width 0.11938)
		(layer "F.Cu")
		(net "FPGA_IN_LM75B_INT3_N")
	)
	(segment
		(start 151.2824 -23.7744)
		(end 151.2824 -24.511)
		(width 0.11938)
		(layer "F.Cu")
		(net "FPGA_IN_LM75B_INT3_N")
	)
	(segment
		(start 152.98928 -26.21788)
		(end 151.2824 -24.511)
		(width 0.11938)
		(layer "F.Cu")
		(net "FPGA_IN_LM75B_INT3_N")
	)
	(segment
		(start 151.13 -23.622)
		(end 151.2824 -23.7744)
		(width 0.11938)
		(layer "F.Cu")
		(net "FPGA_IN_LM75B_INT3_N")
	)
	(segment
		(start 154.5463 -26.21788)
		(end 152.98928 -26.21788)
		(width 0.11938)
		(layer "F.Cu")
		(net "FPGA_IN_LM75B_INT3_N")
	)
	(segment
		(start 149.352 -23.622)
		(end 151.13 -23.622)
		(width 0.11938)
		(layer "F.Cu")
		(net "FPGA_IN_LM75B_INT3_N")
	)
	(segment
		(start 109.847126 -50.823114)
		(end 110.346998 -51.322986)
		(width 0.11938)
		(layer "F.Cu")
		(net "FPGA_IN_LM75B_INT3_N")
	)
	(segment
		(start 147.32 -25.654)
		(end 149.352 -23.622)
		(width 0.11938)
		(layer "F.Cu")
		(net "FPGA_IN_LM75B_INT3_N")
	)
	(via
		(at 110.346998 -51.322986)
		(size 0.4572)
		(drill 0.2032)
		(layers "F.Cu" "B.Cu")
		(net "FPGA_IN_LM75B_INT3_N")
	)
	(via
		(at 134.239 -75.946)
		(size 0.4572)
		(drill 0.2032)
		(layers "F.Cu" "B.Cu")
		(net "FPGA_IN_LM75B_INT3_N")
	)
	(segment
		(start 113.157 -79.375)
		(end 113.665 -79.883)
		(width 0.127)
		(layer "In2.Cu")
		(net "FPGA_IN_LM75B_INT3_N")
	)
	(segment
		(start 110.84814 -55.978806)
		(end 112.014 -57.144666)
		(width 0.127)
		(layer "In2.Cu")
		(net "FPGA_IN_LM75B_INT3_N")
	)
	(segment
		(start 127 -87.503)
		(end 127 -86.102952)
		(width 0.127)
		(layer "In2.Cu")
		(net "FPGA_IN_LM75B_INT3_N")
	)
	(segment
		(start 114.808 -79.883)
		(end 115.951 -81.026)
		(width 0.127)
		(layer "In2.Cu")
		(net "FPGA_IN_LM75B_INT3_N")
	)
	(segment
		(start 121.111518 -89.281)
		(end 125.222 -89.281)
		(width 0.127)
		(layer "In2.Cu")
		(net "FPGA_IN_LM75B_INT3_N")
	)
	(segment
		(start 112.6109 -70.358)
		(end 112.6109 -75.262486)
		(width 0.127)
		(layer "In2.Cu")
		(net "FPGA_IN_LM75B_INT3_N")
	)
	(segment
		(start 128.651 -82.677)
		(end 134.239 -77.089)
		(width 0.127)
		(layer "In2.Cu")
		(net "FPGA_IN_LM75B_INT3_N")
	)
	(segment
		(start 115.951 -81.026)
		(end 116.926868 -81.026)
		(width 0.127)
		(layer "In2.Cu")
		(net "FPGA_IN_LM75B_INT3_N")
	)
	(segment
		(start 112.6109 -75.262486)
		(end 113.157 -75.808586)
		(width 0.127)
		(layer "In2.Cu")
		(net "FPGA_IN_LM75B_INT3_N")
	)
	(segment
		(start 125.222 -89.281)
		(end 127 -87.503)
		(width 0.127)
		(layer "In2.Cu")
		(net "FPGA_IN_LM75B_INT3_N")
	)
	(segment
		(start 111.252 -61.849)
		(end 109.855 -61.849)
		(width 0.127)
		(layer "In2.Cu")
		(net "FPGA_IN_LM75B_INT3_N")
	)
	(segment
		(start 112.014 -61.087)
		(end 111.252 -61.849)
		(width 0.127)
		(layer "In2.Cu")
		(net "FPGA_IN_LM75B_INT3_N")
	)
	(segment
		(start 117.2845 -84.980018)
		(end 120.2055 -87.901018)
		(width 0.127)
		(layer "In2.Cu")
		(net "FPGA_IN_LM75B_INT3_N")
	)
	(segment
		(start 109.347 -62.357)
		(end 109.347 -67.0941)
		(width 0.127)
		(layer "In2.Cu")
		(net "FPGA_IN_LM75B_INT3_N")
	)
	(segment
		(start 109.855 -61.849)
		(end 109.347 -62.357)
		(width 0.127)
		(layer "In2.Cu")
		(net "FPGA_IN_LM75B_INT3_N")
	)
	(segment
		(start 127 -86.102952)
		(end 128.651 -84.451952)
		(width 0.127)
		(layer "In2.Cu")
		(net "FPGA_IN_LM75B_INT3_N")
	)
	(segment
		(start 112.014 -57.144666)
		(end 112.014 -61.087)
		(width 0.127)
		(layer "In2.Cu")
		(net "FPGA_IN_LM75B_INT3_N")
	)
	(segment
		(start 113.665 -79.883)
		(end 114.808 -79.883)
		(width 0.127)
		(layer "In2.Cu")
		(net "FPGA_IN_LM75B_INT3_N")
	)
	(segment
		(start 120.2055 -88.374982)
		(end 121.111518 -89.281)
		(width 0.127)
		(layer "In2.Cu")
		(net "FPGA_IN_LM75B_INT3_N")
	)
	(segment
		(start 116.926868 -81.026)
		(end 117.2845 -81.383632)
		(width 0.127)
		(layer "In2.Cu")
		(net "FPGA_IN_LM75B_INT3_N")
	)
	(segment
		(start 134.239 -77.089)
		(end 134.239 -75.946)
		(width 0.127)
		(layer "In2.Cu")
		(net "FPGA_IN_LM75B_INT3_N")
	)
	(segment
		(start 110.346998 -51.322986)
		(end 110.84814 -51.824128)
		(width 0.127)
		(layer "In2.Cu")
		(net "FPGA_IN_LM75B_INT3_N")
	)
	(segment
		(start 113.157 -75.808586)
		(end 113.157 -79.375)
		(width 0.127)
		(layer "In2.Cu")
		(net "FPGA_IN_LM75B_INT3_N")
	)
	(segment
		(start 120.2055 -87.901018)
		(end 120.2055 -88.374982)
		(width 0.127)
		(layer "In2.Cu")
		(net "FPGA_IN_LM75B_INT3_N")
	)
	(segment
		(start 128.651 -84.451952)
		(end 128.651 -82.677)
		(width 0.127)
		(layer "In2.Cu")
		(net "FPGA_IN_LM75B_INT3_N")
	)
	(segment
		(start 109.347 -67.0941)
		(end 112.6109 -70.358)
		(width 0.127)
		(layer "In2.Cu")
		(net "FPGA_IN_LM75B_INT3_N")
	)
	(segment
		(start 117.2845 -81.383632)
		(end 117.2845 -84.980018)
		(width 0.127)
		(layer "In2.Cu")
		(net "FPGA_IN_LM75B_INT3_N")
	)
	(segment
		(start 110.84814 -51.824128)
		(end 110.84814 -55.978806)
		(width 0.127)
		(layer "In2.Cu")
		(net "FPGA_IN_LM75B_INT3_N")
	)
	(segment
		(start 130.048 -55.9562)
		(end 135.8138 -61.722)
		(width 0.127)
		(layer "In7.Cu")
		(net "FPGA_IN_LM75B_INT3_N")
	)
	(segment
		(start 143.3068 -63.373)
		(end 144.7038 -64.77)
		(width 0.127)
		(layer "In7.Cu")
		(net "FPGA_IN_LM75B_INT3_N")
	)
	(segment
		(start 128.524 -53.169566)
		(end 128.524 -55.564786)
		(width 0.127)
		(layer "In7.Cu")
		(net "FPGA_IN_LM75B_INT3_N")
	)
	(segment
		(start 132.334 -33.147)
		(end 132.334 -40.005)
		(width 0.127)
		(layer "In7.Cu")
		(net "FPGA_IN_LM75B_INT3_N")
	)
	(segment
		(start 128.397 -49.504854)
		(end 128.397 -53.042566)
		(width 0.127)
		(layer "In7.Cu")
		(net "FPGA_IN_LM75B_INT3_N")
	)
	(segment
		(start 147.32 -26.6192)
		(end 147.193 -26.4922)
		(width 0.127)
		(layer "In7.Cu")
		(net "FPGA_IN_LM75B_INT3_N")
	)
	(segment
		(start 144.7038 -64.77)
		(end 144.7038 -66.8782)
		(width 0.127)
		(layer "In7.Cu")
		(net "FPGA_IN_LM75B_INT3_N")
	)
	(segment
		(start 138.303 -63.373)
		(end 143.3068 -63.373)
		(width 0.127)
		(layer "In7.Cu")
		(net "FPGA_IN_LM75B_INT3_N")
	)
	(segment
		(start 135.8138 -61.722)
		(end 136.652 -61.722)
		(width 0.127)
		(layer "In7.Cu")
		(net "FPGA_IN_LM75B_INT3_N")
	)
	(segment
		(start 139.573 -74.676)
		(end 138.303 -75.946)
		(width 0.127)
		(layer "In7.Cu")
		(net "FPGA_IN_LM75B_INT3_N")
	)
	(segment
		(start 138.303 -75.946)
		(end 134.239 -75.946)
		(width 0.127)
		(layer "In7.Cu")
		(net "FPGA_IN_LM75B_INT3_N")
	)
	(segment
		(start 144.7038 -66.8782)
		(end 139.573 -72.009)
		(width 0.127)
		(layer "In7.Cu")
		(net "FPGA_IN_LM75B_INT3_N")
	)
	(segment
		(start 128.0795 -49.187354)
		(end 128.397 -49.504854)
		(width 0.127)
		(layer "In7.Cu")
		(net "FPGA_IN_LM75B_INT3_N")
	)
	(segment
		(start 128.0795 -44.2595)
		(end 128.0795 -49.187354)
		(width 0.127)
		(layer "In7.Cu")
		(net "FPGA_IN_LM75B_INT3_N")
	)
	(segment
		(start 128.915414 -55.9562)
		(end 130.048 -55.9562)
		(width 0.127)
		(layer "In7.Cu")
		(net "FPGA_IN_LM75B_INT3_N")
	)
	(segment
		(start 132.334 -40.005)
		(end 128.0795 -44.2595)
		(width 0.127)
		(layer "In7.Cu")
		(net "FPGA_IN_LM75B_INT3_N")
	)
	(segment
		(start 128.524 -55.564786)
		(end 128.915414 -55.9562)
		(width 0.127)
		(layer "In7.Cu")
		(net "FPGA_IN_LM75B_INT3_N")
	)
	(segment
		(start 128.397 -53.042566)
		(end 128.524 -53.169566)
		(width 0.127)
		(layer "In7.Cu")
		(net "FPGA_IN_LM75B_INT3_N")
	)
	(segment
		(start 136.652 -61.722)
		(end 138.303 -63.373)
		(width 0.127)
		(layer "In7.Cu")
		(net "FPGA_IN_LM75B_INT3_N")
	)
	(segment
		(start 147.193 -26.4922)
		(end 138.9888 -26.4922)
		(width 0.127)
		(layer "In7.Cu")
		(net "FPGA_IN_LM75B_INT3_N")
	)
	(segment
		(start 139.573 -72.009)
		(end 139.573 -74.676)
		(width 0.127)
		(layer "In7.Cu")
		(net "FPGA_IN_LM75B_INT3_N")
	)
	(segment
		(start 138.9888 -26.4922)
		(end 132.334 -33.147)
		(width 0.127)
		(layer "In7.Cu")
		(net "FPGA_IN_LM75B_INT3_N")
	)
	(segment
		(start 109.847126 -54.823106)
		(end 110.346998 -55.322978)
		(width 0.11938)
		(layer "F.Cu")
		(net "FPGA_IN_LM75B_INT2_N")
	)
	(segment
		(start 51.2318 -83.8708)
		(end 52.451 -85.09)
		(width 0.11938)
		(layer "F.Cu")
		(net "FPGA_IN_LM75B_INT2_N")
	)
	(segment
		(start 53.467 -85.09)
		(end 53.90388 -84.65312)
		(width 0.11938)
		(layer "F.Cu")
		(net "FPGA_IN_LM75B_INT2_N")
	)
	(segment
		(start 53.90388 -84.65312)
		(end 53.90388 -82.9437)
		(width 0.11938)
		(layer "F.Cu")
		(net "FPGA_IN_LM75B_INT2_N")
	)
	(segment
		(start 51.2318 -83.2866)
		(end 51.2318 -83.8708)
		(width 0.11938)
		(layer "F.Cu")
		(net "FPGA_IN_LM75B_INT2_N")
	)
	(segment
		(start 49.7586 -82.4738)
		(end 50.419 -82.4738)
		(width 0.11938)
		(layer "F.Cu")
		(net "FPGA_IN_LM75B_INT2_N")
	)
	(segment
		(start 52.451 -85.09)
		(end 53.467 -85.09)
		(width 0.11938)
		(layer "F.Cu")
		(net "FPGA_IN_LM75B_INT2_N")
	)
	(segment
		(start 50.419 -82.4738)
		(end 51.2318 -83.2866)
		(width 0.11938)
		(layer "F.Cu")
		(net "FPGA_IN_LM75B_INT2_N")
	)
	(via
		(at 79.375 -78.105)
		(size 0.508)
		(drill 0.254)
		(layers "F.Cu" "B.Cu")
		(net "FPGA_IN_LM75B_INT2_N")
	)
	(via
		(at 110.346998 -55.322978)
		(size 0.4572)
		(drill 0.2032)
		(layers "F.Cu" "B.Cu")
		(net "FPGA_IN_LM75B_INT2_N")
	)
	(segment
		(start 53.4416 -83.2866)
		(end 51.2318 -83.2866)
		(width 0.127)
		(layer "In2.Cu")
		(net "FPGA_IN_LM75B_INT2_N")
	)
	(segment
		(start 57.912 -83.566)
		(end 57.023 -84.455)
		(width 0.127)
		(layer "In2.Cu")
		(net "FPGA_IN_LM75B_INT2_N")
	)
	(segment
		(start 57.023 -84.455)
		(end 54.61 -84.455)
		(width 0.127)
		(layer "In2.Cu")
		(net "FPGA_IN_LM75B_INT2_N")
	)
	(segment
		(start 54.61 -84.455)
		(end 53.4416 -83.2866)
		(width 0.127)
		(layer "In2.Cu")
		(net "FPGA_IN_LM75B_INT2_N")
	)
	(segment
		(start 78.359 -77.089)
		(end 73.533 -77.089)
		(width 0.127)
		(layer "In2.Cu")
		(net "FPGA_IN_LM75B_INT2_N")
	)
	(segment
		(start 73.533 -77.089)
		(end 67.056 -83.566)
		(width 0.127)
		(layer "In2.Cu")
		(net "FPGA_IN_LM75B_INT2_N")
	)
	(segment
		(start 67.056 -83.566)
		(end 57.912 -83.566)
		(width 0.127)
		(layer "In2.Cu")
		(net "FPGA_IN_LM75B_INT2_N")
	)
	(segment
		(start 79.375 -78.105)
		(end 78.359 -77.089)
		(width 0.127)
		(layer "In2.Cu")
		(net "FPGA_IN_LM75B_INT2_N")
	)
	(segment
		(start 104.3305 -77.7367)
		(end 104.3305 -76.090018)
		(width 0.127)
		(layer "In7.Cu")
		(net "FPGA_IN_LM75B_INT2_N")
	)
	(segment
		(start 103.8352 -78.232)
		(end 104.3305 -77.7367)
		(width 0.127)
		(layer "In7.Cu")
		(net "FPGA_IN_LM75B_INT2_N")
	)
	(segment
		(start 104.5718 -71.247)
		(end 109.2454 -66.5734)
		(width 0.127)
		(layer "In7.Cu")
		(net "FPGA_IN_LM75B_INT2_N")
	)
	(segment
		(start 80.137 -78.867)
		(end 86.740746 -78.867)
		(width 0.127)
		(layer "In7.Cu")
		(net "FPGA_IN_LM75B_INT2_N")
	)
	(segment
		(start 104.3305 -76.090018)
		(end 104.5718 -75.848718)
		(width 0.127)
		(layer "In7.Cu")
		(net "FPGA_IN_LM75B_INT2_N")
	)
	(segment
		(start 103.331518 -78.232)
		(end 103.8352 -78.232)
		(width 0.127)
		(layer "In7.Cu")
		(net "FPGA_IN_LM75B_INT2_N")
	)
	(segment
		(start 101.375718 -80.1878)
		(end 103.331518 -78.232)
		(width 0.127)
		(layer "In7.Cu")
		(net "FPGA_IN_LM75B_INT2_N")
	)
	(segment
		(start 110.346998 -61.324998)
		(end 110.346998 -55.322978)
		(width 0.127)
		(layer "In7.Cu")
		(net "FPGA_IN_LM75B_INT2_N")
	)
	(segment
		(start 104.5718 -75.848718)
		(end 104.5718 -71.247)
		(width 0.127)
		(layer "In7.Cu")
		(net "FPGA_IN_LM75B_INT2_N")
	)
	(segment
		(start 98.7298 -80.1878)
		(end 101.375718 -80.1878)
		(width 0.127)
		(layer "In7.Cu")
		(net "FPGA_IN_LM75B_INT2_N")
	)
	(segment
		(start 86.740746 -78.867)
		(end 88.899746 -81.026)
		(width 0.127)
		(layer "In7.Cu")
		(net "FPGA_IN_LM75B_INT2_N")
	)
	(segment
		(start 88.899746 -81.026)
		(end 97.8916 -81.026)
		(width 0.127)
		(layer "In7.Cu")
		(net "FPGA_IN_LM75B_INT2_N")
	)
	(segment
		(start 109.2454 -66.5734)
		(end 109.2454 -62.426596)
		(width 0.127)
		(layer "In7.Cu")
		(net "FPGA_IN_LM75B_INT2_N")
	)
	(segment
		(start 97.8916 -81.026)
		(end 98.7298 -80.1878)
		(width 0.127)
		(layer "In7.Cu")
		(net "FPGA_IN_LM75B_INT2_N")
	)
	(segment
		(start 79.375 -78.105)
		(end 80.137 -78.867)
		(width 0.127)
		(layer "In7.Cu")
		(net "FPGA_IN_LM75B_INT2_N")
	)
	(segment
		(start 109.2454 -62.426596)
		(end 110.346998 -61.324998)
		(width 0.127)
		(layer "In7.Cu")
		(net "FPGA_IN_LM75B_INT2_N")
	)
	(segment
		(start 110.847124 -54.823106)
		(end 111.346996 -55.322978)
		(width 0.11938)
		(layer "F.Cu")
		(net "FPGA_IN_LM75B_INT1_N")
	)
	(via
		(at 111.346996 -55.322978)
		(size 0.4572)
		(drill 0.2032)
		(layers "F.Cu" "B.Cu")
		(net "FPGA_IN_LM75B_INT1_N")
	)
	(via
		(at 75.438 -78.867)
		(size 0.508)
		(drill 0.254)
		(layers "F.Cu" "B.Cu")
		(net "FPGA_IN_LM75B_INT1_N")
	)
	(segment
		(start 61.122306 -84.5947)
		(end 58.97626 -82.448654)
		(width 0.11938)
		(layer "B.Cu")
		(net "FPGA_IN_LM75B_INT1_N")
	)
	(segment
		(start 67.449192 -84.5947)
		(end 61.122306 -84.5947)
		(width 0.11938)
		(layer "B.Cu")
		(net "FPGA_IN_LM75B_INT1_N")
	)
	(segment
		(start 41.769538 -70.993)
		(end 40.568118 -72.19442)
		(width 0.11938)
		(layer "B.Cu")
		(net "FPGA_IN_LM75B_INT1_N")
	)
	(segment
		(start 24.62911 -73.14311)
		(end 23.37689 -73.14311)
		(width 0.11938)
		(layer "B.Cu")
		(net "FPGA_IN_LM75B_INT1_N")
	)
	(segment
		(start 13.9827 -75.62088)
		(end 14.937486 -75.62088)
		(width 0.11938)
		(layer "B.Cu")
		(net "FPGA_IN_LM75B_INT1_N")
	)
	(segment
		(start 17.87398 -73.406)
		(end 17.7546 -73.52538)
		(width 0.11938)
		(layer "B.Cu")
		(net "FPGA_IN_LM75B_INT1_N")
	)
	(segment
		(start 32.45358 -72.19442)
		(end 30.226 -74.422)
		(width 0.11938)
		(layer "B.Cu")
		(net "FPGA_IN_LM75B_INT1_N")
	)
	(segment
		(start 73.176892 -78.867)
		(end 67.449192 -84.5947)
		(width 0.11938)
		(layer "B.Cu")
		(net "FPGA_IN_LM75B_INT1_N")
	)
	(segment
		(start 25.908 -74.422)
		(end 24.62911 -73.14311)
		(width 0.11938)
		(layer "B.Cu")
		(net "FPGA_IN_LM75B_INT1_N")
	)
	(segment
		(start 22.352 -74.168)
		(end 20.828 -74.168)
		(width 0.11938)
		(layer "B.Cu")
		(net "FPGA_IN_LM75B_INT1_N")
	)
	(segment
		(start 30.226 -74.422)
		(end 25.908 -74.422)
		(width 0.11938)
		(layer "B.Cu")
		(net "FPGA_IN_LM75B_INT1_N")
	)
	(segment
		(start 40.568118 -72.19442)
		(end 32.45358 -72.19442)
		(width 0.11938)
		(layer "B.Cu")
		(net "FPGA_IN_LM75B_INT1_N")
	)
	(segment
		(start 57.404254 -70.993)
		(end 41.769538 -70.993)
		(width 0.11938)
		(layer "B.Cu")
		(net "FPGA_IN_LM75B_INT1_N")
	)
	(segment
		(start 16.1544 -74.403966)
		(end 16.1544 -74.041)
		(width 0.11938)
		(layer "B.Cu")
		(net "FPGA_IN_LM75B_INT1_N")
	)
	(segment
		(start 23.37689 -73.14311)
		(end 22.352 -74.168)
		(width 0.11938)
		(layer "B.Cu")
		(net "FPGA_IN_LM75B_INT1_N")
	)
	(segment
		(start 14.937486 -75.62088)
		(end 16.1544 -74.403966)
		(width 0.11938)
		(layer "B.Cu")
		(net "FPGA_IN_LM75B_INT1_N")
	)
	(segment
		(start 16.1544 -74.041)
		(end 17.7546 -74.041)
		(width 0.11938)
		(layer "B.Cu")
		(net "FPGA_IN_LM75B_INT1_N")
	)
	(segment
		(start 17.7546 -73.52538)
		(end 17.7546 -74.041)
		(width 0.11938)
		(layer "B.Cu")
		(net "FPGA_IN_LM75B_INT1_N")
	)
	(segment
		(start 58.97626 -72.565006)
		(end 57.404254 -70.993)
		(width 0.11938)
		(layer "B.Cu")
		(net "FPGA_IN_LM75B_INT1_N")
	)
	(segment
		(start 58.97626 -82.448654)
		(end 58.97626 -72.565006)
		(width 0.11938)
		(layer "B.Cu")
		(net "FPGA_IN_LM75B_INT1_N")
	)
	(segment
		(start 75.438 -78.867)
		(end 73.176892 -78.867)
		(width 0.11938)
		(layer "B.Cu")
		(net "FPGA_IN_LM75B_INT1_N")
	)
	(segment
		(start 20.828 -74.168)
		(end 20.066 -73.406)
		(width 0.11938)
		(layer "B.Cu")
		(net "FPGA_IN_LM75B_INT1_N")
	)
	(segment
		(start 20.066 -73.406)
		(end 17.87398 -73.406)
		(width 0.11938)
		(layer "B.Cu")
		(net "FPGA_IN_LM75B_INT1_N")
	)
	(segment
		(start 111.346996 -55.797196)
		(end 111.506 -55.9562)
		(width 0.127)
		(layer "In7.Cu")
		(net "FPGA_IN_LM75B_INT1_N")
	)
	(segment
		(start 102.9716 -79.756)
		(end 102.0318 -80.6958)
		(width 0.127)
		(layer "In7.Cu")
		(net "FPGA_IN_LM75B_INT1_N")
	)
	(segment
		(start 79.121 -79.375)
		(end 78.359 -78.613)
		(width 0.127)
		(layer "In7.Cu")
		(net "FPGA_IN_LM75B_INT1_N")
	)
	(segment
		(start 88.7095 -81.5975)
		(end 86.487 -79.375)
		(width 0.127)
		(layer "In7.Cu")
		(net "FPGA_IN_LM75B_INT1_N")
	)
	(segment
		(start 104.0384 -79.756)
		(end 102.9716 -79.756)
		(width 0.127)
		(layer "In7.Cu")
		(net "FPGA_IN_LM75B_INT1_N")
	)
	(segment
		(start 86.487 -79.375)
		(end 79.121 -79.375)
		(width 0.127)
		(layer "In7.Cu")
		(net "FPGA_IN_LM75B_INT1_N")
	)
	(segment
		(start 102.0318 -80.6958)
		(end 99.4664 -80.6958)
		(width 0.127)
		(layer "In7.Cu")
		(net "FPGA_IN_LM75B_INT1_N")
	)
	(segment
		(start 98.5647 -81.5975)
		(end 88.7095 -81.5975)
		(width 0.127)
		(layer "In7.Cu")
		(net "FPGA_IN_LM75B_INT1_N")
	)
	(segment
		(start 111.346996 -55.322978)
		(end 111.346996 -55.797196)
		(width 0.127)
		(layer "In7.Cu")
		(net "FPGA_IN_LM75B_INT1_N")
	)
	(segment
		(start 99.4664 -80.6958)
		(end 98.5647 -81.5975)
		(width 0.127)
		(layer "In7.Cu")
		(net "FPGA_IN_LM75B_INT1_N")
	)
	(segment
		(start 78.359 -78.613)
		(end 75.692 -78.613)
		(width 0.127)
		(layer "In7.Cu")
		(net "FPGA_IN_LM75B_INT1_N")
	)
	(segment
		(start 75.692 -78.613)
		(end 75.438 -78.867)
		(width 0.127)
		(layer "In7.Cu")
		(net "FPGA_IN_LM75B_INT1_N")
	)
	(segment
		(start 111.506 -61.0616)
		(end 109.9185 -62.6491)
		(width 0.127)
		(layer "In7.Cu")
		(net "FPGA_IN_LM75B_INT1_N")
	)
	(segment
		(start 105.8672 -70.670166)
		(end 105.8672 -77.9272)
		(width 0.127)
		(layer "In7.Cu")
		(net "FPGA_IN_LM75B_INT1_N")
	)
	(segment
		(start 105.8672 -77.9272)
		(end 104.0384 -79.756)
		(width 0.127)
		(layer "In7.Cu")
		(net "FPGA_IN_LM75B_INT1_N")
	)
	(segment
		(start 109.9185 -62.6491)
		(end 109.9185 -66.618866)
		(width 0.127)
		(layer "In7.Cu")
		(net "FPGA_IN_LM75B_INT1_N")
	)
	(segment
		(start 111.506 -55.9562)
		(end 111.506 -61.0616)
		(width 0.127)
		(layer "In7.Cu")
		(net "FPGA_IN_LM75B_INT1_N")
	)
	(segment
		(start 109.9185 -66.618866)
		(end 105.8672 -70.670166)
		(width 0.127)
		(layer "In7.Cu")
		(net "FPGA_IN_LM75B_INT1_N")
	)
	(segment
		(start 150.114 -70.993)
		(end 150.622 -71.501)
		(width 0.11938)
		(layer "F.Cu")
		(net "DBG_UART_MAC_TX")
	)
	(segment
		(start 150.114 -70.739)
		(end 150.114 -70.993)
		(width 0.11938)
		(layer "F.Cu")
		(net "DBG_UART_MAC_TX")
	)
	(segment
		(start 150.622 -71.501)
		(end 152.868376 -71.501)
		(width 0.11938)
		(layer "F.Cu")
		(net "DBG_UART_MAC_TX")
	)
	(via
		(at 150.114 -70.739)
		(size 0.508)
		(drill 0.254)
		(layers "F.Cu" "B.Cu")
		(net "DBG_UART_MAC_TX")
	)
	(segment
		(start 150.114 -70.739)
		(end 150.241 -70.866)
		(width 0.11938)
		(layer "B.Cu")
		(net "DBG_UART_MAC_TX")
	)
	(segment
		(start 150.241 -70.866)
		(end 152.2476 -70.866)
		(width 0.11938)
		(layer "B.Cu")
		(net "DBG_UART_MAC_TX")
	)
	(segment
		(start 152.868376 -66.421)
		(end 150.114 -66.421)
		(width 0.11938)
		(layer "F.Cu")
		(net "DBG_UART_MAC_RX")
	)
	(via
		(at 150.114 -66.421)
		(size 0.4572)
		(drill 0.2032)
		(layers "F.Cu" "B.Cu")
		(net "DBG_UART_MAC_RX")
	)
	(segment
		(start 151.342598 -65.65392)
		(end 150.953978 -65.65392)
		(width 0.11938)
		(layer "B.Cu")
		(net "DBG_UART_MAC_RX")
	)
	(segment
		(start 150.834598 -66.30162)
		(end 150.715218 -66.421)
		(width 0.11938)
		(layer "B.Cu")
		(net "DBG_UART_MAC_RX")
	)
	(segment
		(start 151.461978 -65.7733)
		(end 151.342598 -65.65392)
		(width 0.11938)
		(layer "B.Cu")
		(net "DBG_UART_MAC_RX")
	)
	(segment
		(start 152.2476 -66.421)
		(end 151.581358 -66.421)
		(width 0.11938)
		(layer "B.Cu")
		(net "DBG_UART_MAC_RX")
	)
	(segment
		(start 150.834598 -65.7733)
		(end 150.834598 -66.30162)
		(width 0.11938)
		(layer "B.Cu")
		(net "DBG_UART_MAC_RX")
	)
	(segment
		(start 150.953978 -65.65392)
		(end 150.834598 -65.7733)
		(width 0.11938)
		(layer "B.Cu")
		(net "DBG_UART_MAC_RX")
	)
	(segment
		(start 150.715218 -66.421)
		(end 150.114 -66.421)
		(width 0.11938)
		(layer "B.Cu")
		(net "DBG_UART_MAC_RX")
	)
	(segment
		(start 151.461978 -66.30162)
		(end 151.461978 -65.7733)
		(width 0.11938)
		(layer "B.Cu")
		(net "DBG_UART_MAC_RX")
	)
	(segment
		(start 151.581358 -66.421)
		(end 151.461978 -66.30162)
		(width 0.11938)
		(layer "B.Cu")
		(net "DBG_UART_MAC_RX")
	)
	(segment
		(start 131.343654 -83.032346)
		(end 131.174998 -83.032346)
		(width 0.11938)
		(layer "F.Cu")
		(net "DBG_UART_GPS_TXD")
	)
	(segment
		(start 130.456178 -83.919822)
		(end 130.287522 -83.919822)
		(width 0.11938)
		(layer "F.Cu")
		(net "DBG_UART_GPS_TXD")
	)
	(segment
		(start 128.299464 -84.425536)
		(end 128.299464 -84.594192)
		(width 0.11938)
		(layer "F.Cu")
		(net "DBG_UART_GPS_TXD")
	)
	(segment
		(start 130.074416 -82.81924)
		(end 130.73126 -83.476084)
		(width 0.11938)
		(layer "F.Cu")
		(net "DBG_UART_GPS_TXD")
	)
	(segment
		(start 149.098 -78.486)
		(end 148.082 -79.502)
		(width 0.11938)
		(layer "F.Cu")
		(net "DBG_UART_GPS_TXD")
	)
	(segment
		(start 127.254 -88.3666)
		(end 126.619 -89.0016)
		(width 0.11938)
		(layer "F.Cu")
		(net "DBG_UART_GPS_TXD")
	)
	(segment
		(start 131.174998 -83.032346)
		(end 130.518154 -82.375502)
		(width 0.11938)
		(layer "F.Cu")
		(net "DBG_UART_GPS_TXD")
	)
	(segment
		(start 129.843784 -84.532216)
		(end 129.568702 -84.807298)
		(width 0.11938)
		(layer "F.Cu")
		(net "DBG_UART_GPS_TXD")
	)
	(segment
		(start 129.462022 -83.262978)
		(end 129.18694 -83.53806)
		(width 0.11938)
		(layer "F.Cu")
		(net "DBG_UART_GPS_TXD")
	)
	(segment
		(start 130.518154 -82.375502)
		(end 130.349498 -82.375502)
		(width 0.11938)
		(layer "F.Cu")
		(net "DBG_UART_GPS_TXD")
	)
	(segment
		(start 129.18694 -83.706716)
		(end 129.843784 -84.36356)
		(width 0.11938)
		(layer "F.Cu")
		(net "DBG_UART_GPS_TXD")
	)
	(segment
		(start 130.074416 -82.650584)
		(end 130.074416 -82.81924)
		(width 0.11938)
		(layer "F.Cu")
		(net "DBG_UART_GPS_TXD")
	)
	(segment
		(start 128.516126 -85.529674)
		(end 128.34747 -85.529674)
		(width 0.11938)
		(layer "F.Cu")
		(net "DBG_UART_GPS_TXD")
	)
	(segment
		(start 128.34747 -85.529674)
		(end 127.855726 -85.03793)
		(width 0.11938)
		(layer "F.Cu")
		(net "DBG_UART_GPS_TXD")
	)
	(segment
		(start 131.618736 -82.588608)
		(end 131.618736 -82.757264)
		(width 0.11938)
		(layer "F.Cu")
		(net "DBG_UART_GPS_TXD")
	)
	(segment
		(start 150.114 -74.041)
		(end 150.114 -75.311)
		(width 0.11938)
		(layer "F.Cu")
		(net "DBG_UART_GPS_TXD")
	)
	(segment
		(start 130.73126 -83.476084)
		(end 130.73126 -83.64474)
		(width 0.11938)
		(layer "F.Cu")
		(net "DBG_UART_GPS_TXD")
	)
	(segment
		(start 128.299464 -84.594192)
		(end 128.791208 -85.085936)
		(width 0.11938)
		(layer "F.Cu")
		(net "DBG_UART_GPS_TXD")
	)
	(segment
		(start 127.254 -85.471)
		(end 127.254 -88.3666)
		(width 0.11938)
		(layer "F.Cu")
		(net "DBG_UART_GPS_TXD")
	)
	(segment
		(start 152.868376 -74.041)
		(end 150.114 -74.041)
		(width 0.11938)
		(layer "F.Cu")
		(net "DBG_UART_GPS_TXD")
	)
	(segment
		(start 129.630678 -83.262978)
		(end 129.462022 -83.262978)
		(width 0.11938)
		(layer "F.Cu")
		(net "DBG_UART_GPS_TXD")
	)
	(segment
		(start 150.114 -75.311)
		(end 149.098 -76.327)
		(width 0.11938)
		(layer "F.Cu")
		(net "DBG_UART_GPS_TXD")
	)
	(segment
		(start 130.961892 -81.931764)
		(end 131.618736 -82.588608)
		(width 0.11938)
		(layer "F.Cu")
		(net "DBG_UART_GPS_TXD")
	)
	(segment
		(start 131.618736 -82.757264)
		(end 131.343654 -83.032346)
		(width 0.11938)
		(layer "F.Cu")
		(net "DBG_UART_GPS_TXD")
	)
	(segment
		(start 128.791208 -85.254592)
		(end 128.516126 -85.529674)
		(width 0.11938)
		(layer "F.Cu")
		(net "DBG_UART_GPS_TXD")
	)
	(segment
		(start 127.68707 -85.03793)
		(end 127.254 -85.471)
		(width 0.11938)
		(layer "F.Cu")
		(net "DBG_UART_GPS_TXD")
	)
	(segment
		(start 133.223 -79.502)
		(end 130.961892 -81.763108)
		(width 0.11938)
		(layer "F.Cu")
		(net "DBG_UART_GPS_TXD")
	)
	(segment
		(start 129.18694 -83.53806)
		(end 129.18694 -83.706716)
		(width 0.11938)
		(layer "F.Cu")
		(net "DBG_UART_GPS_TXD")
	)
	(segment
		(start 128.791208 -85.085936)
		(end 128.791208 -85.254592)
		(width 0.11938)
		(layer "F.Cu")
		(net "DBG_UART_GPS_TXD")
	)
	(segment
		(start 129.843784 -84.36356)
		(end 129.843784 -84.532216)
		(width 0.11938)
		(layer "F.Cu")
		(net "DBG_UART_GPS_TXD")
	)
	(segment
		(start 130.349498 -82.375502)
		(end 130.074416 -82.650584)
		(width 0.11938)
		(layer "F.Cu")
		(net "DBG_UART_GPS_TXD")
	)
	(segment
		(start 127.855726 -85.03793)
		(end 127.68707 -85.03793)
		(width 0.11938)
		(layer "F.Cu")
		(net "DBG_UART_GPS_TXD")
	)
	(segment
		(start 130.287522 -83.919822)
		(end 129.630678 -83.262978)
		(width 0.11938)
		(layer "F.Cu")
		(net "DBG_UART_GPS_TXD")
	)
	(segment
		(start 130.961892 -81.763108)
		(end 130.961892 -81.931764)
		(width 0.11938)
		(layer "F.Cu")
		(net "DBG_UART_GPS_TXD")
	)
	(segment
		(start 148.082 -79.502)
		(end 133.223 -79.502)
		(width 0.11938)
		(layer "F.Cu")
		(net "DBG_UART_GPS_TXD")
	)
	(segment
		(start 149.098 -76.327)
		(end 149.098 -78.486)
		(width 0.11938)
		(layer "F.Cu")
		(net "DBG_UART_GPS_TXD")
	)
	(segment
		(start 128.743202 -84.150454)
		(end 128.574546 -84.150454)
		(width 0.11938)
		(layer "F.Cu")
		(net "DBG_UART_GPS_TXD")
	)
	(segment
		(start 130.73126 -83.64474)
		(end 130.456178 -83.919822)
		(width 0.11938)
		(layer "F.Cu")
		(net "DBG_UART_GPS_TXD")
	)
	(segment
		(start 128.574546 -84.150454)
		(end 128.299464 -84.425536)
		(width 0.11938)
		(layer "F.Cu")
		(net "DBG_UART_GPS_TXD")
	)
	(segment
		(start 129.400046 -84.807298)
		(end 128.743202 -84.150454)
		(width 0.11938)
		(layer "F.Cu")
		(net "DBG_UART_GPS_TXD")
	)
	(segment
		(start 129.568702 -84.807298)
		(end 129.400046 -84.807298)
		(width 0.11938)
		(layer "F.Cu")
		(net "DBG_UART_GPS_TXD")
	)
	(via
		(at 150.114 -74.041)
		(size 0.508)
		(drill 0.254)
		(layers "F.Cu" "B.Cu")
		(net "DBG_UART_GPS_TXD")
	)
	(segment
		(start 148.784056 -75.75169)
		(end 148.784056 -70.290944)
		(width 0.11938)
		(layer "F.Cu")
		(net "DBG_UART_GPS_RXD")
	)
	(segment
		(start 148.463 -76.072746)
		(end 148.784056 -75.75169)
		(width 0.11938)
		(layer "F.Cu")
		(net "DBG_UART_GPS_RXD")
	)
	(segment
		(start 148.784056 -70.290944)
		(end 150.114 -68.961)
		(width 0.11938)
		(layer "F.Cu")
		(net "DBG_UART_GPS_RXD")
	)
	(segment
		(start 124.714 -88.3666)
		(end 124.714 -87.122)
		(width 0.11938)
		(layer "F.Cu")
		(net "DBG_UART_GPS_RXD")
	)
	(segment
		(start 152.868376 -68.961)
		(end 150.114 -68.961)
		(width 0.11938)
		(layer "F.Cu")
		(net "DBG_UART_GPS_RXD")
	)
	(segment
		(start 132.842 -78.994)
		(end 147.828 -78.994)
		(width 0.11938)
		(layer "F.Cu")
		(net "DBG_UART_GPS_RXD")
	)
	(segment
		(start 147.828 -78.994)
		(end 148.463 -78.359)
		(width 0.11938)
		(layer "F.Cu")
		(net "DBG_UART_GPS_RXD")
	)
	(segment
		(start 124.714 -87.122)
		(end 132.842 -78.994)
		(width 0.11938)
		(layer "F.Cu")
		(net "DBG_UART_GPS_RXD")
	)
	(segment
		(start 124.079 -89.0016)
		(end 124.714 -88.3666)
		(width 0.11938)
		(layer "F.Cu")
		(net "DBG_UART_GPS_RXD")
	)
	(segment
		(start 148.463 -78.359)
		(end 148.463 -76.072746)
		(width 0.11938)
		(layer "F.Cu")
		(net "DBG_UART_GPS_RXD")
	)
	(via
		(at 150.114 -68.961)
		(size 0.508)
		(drill 0.254)
		(layers "F.Cu" "B.Cu")
		(net "DBG_UART_GPS_RXD")
	)
	(segment
		(start 13.462 -54.0258)
		(end 13.462 -53.1114)
		(width 0.11938)
		(layer "F.Cu")
		(net "ANT2_OUT")
	)
	(segment
		(start 13.6652 -54.229)
		(end 13.462 -54.0258)
		(width 0.11938)
		(layer "F.Cu")
		(net "ANT2_OUT")
	)
	(segment
		(start 116.847112 -42.82313)
		(end 117.346984 -42.323258)
		(width 0.11938)
		(layer "F.Cu")
		(net "ANT2_OUT")
	)
	(segment
		(start 13.716 -54.229)
		(end 13.6652 -54.229)
		(width 0.11938)
		(layer "F.Cu")
		(net "ANT2_OUT")
	)
	(via
		(at 13.716 -54.229)
		(size 0.508)
		(drill 0.254)
		(layers "F.Cu" "B.Cu")
		(net "ANT2_OUT")
	)
	(via
		(at 17.018 -27.686)
		(size 0.508)
		(drill 0.254)
		(layers "F.Cu" "B.Cu")
		(net "ANT2_OUT")
	)
	(via
		(at 117.346984 -42.323258)
		(size 0.4572)
		(drill 0.2032)
		(layers "F.Cu" "B.Cu")
		(net "ANT2_OUT")
	)
	(segment
		(start 17.399 -27.813)
		(end 17.272 -27.686)
		(width 0.127)
		(layer "In2.Cu")
		(net "ANT2_OUT")
	)
	(segment
		(start 117.927882 -41.149524)
		(end 118.183406 -40.894)
		(width 0.127)
		(layer "In2.Cu")
		(net "ANT2_OUT")
	)
	(segment
		(start 105.0544 -26.2128)
		(end 104.53878 -26.72842)
		(width 0.127)
		(layer "In2.Cu")
		(net "ANT2_OUT")
	)
	(segment
		(start 123.8377 -30.801818)
		(end 123.8377 -27.516074)
		(width 0.127)
		(layer "In2.Cu")
		(net "ANT2_OUT")
	)
	(segment
		(start 93.726 -24.257)
		(end 85.38464 -24.257)
		(width 0.127)
		(layer "In2.Cu")
		(net "ANT2_OUT")
	)
	(segment
		(start 125.76048 -35.61588)
		(end 125.76048 -33.47212)
		(width 0.127)
		(layer "In2.Cu")
		(net "ANT2_OUT")
	)
	(segment
		(start 94.637352 -25.168352)
		(end 93.726 -24.257)
		(width 0.127)
		(layer "In2.Cu")
		(net "ANT2_OUT")
	)
	(segment
		(start 94.637352 -25.905968)
		(end 94.637352 -25.168352)
		(width 0.127)
		(layer "In2.Cu")
		(net "ANT2_OUT")
	)
	(segment
		(start 118.183406 -40.894)
		(end 118.491 -40.894)
		(width 0.127)
		(layer "In2.Cu")
		(net "ANT2_OUT")
	)
	(segment
		(start 118.6942 -26.2128)
		(end 105.0544 -26.2128)
		(width 0.127)
		(layer "In2.Cu")
		(net "ANT2_OUT")
	)
	(segment
		(start 123.8377 -27.516074)
		(end 123.131326 -26.8097)
		(width 0.127)
		(layer "In2.Cu")
		(net "ANT2_OUT")
	)
	(segment
		(start 118.491 -40.894)
		(end 119.0625 -40.3225)
		(width 0.127)
		(layer "In2.Cu")
		(net "ANT2_OUT")
	)
	(segment
		(start 124.8791 -32.59074)
		(end 124.8791 -31.843218)
		(width 0.127)
		(layer "In2.Cu")
		(net "ANT2_OUT")
	)
	(segment
		(start 119.0625 -40.3225)
		(end 120.659652 -40.3225)
		(width 0.127)
		(layer "In2.Cu")
		(net "ANT2_OUT")
	)
	(segment
		(start 124.8791 -31.843218)
		(end 123.8377 -30.801818)
		(width 0.127)
		(layer "In2.Cu")
		(net "ANT2_OUT")
	)
	(segment
		(start 121.53138 -38.46576)
		(end 123.76404 -36.2331)
		(width 0.127)
		(layer "In2.Cu")
		(net "ANT2_OUT")
	)
	(segment
		(start 123.76404 -36.2331)
		(end 125.14326 -36.2331)
		(width 0.127)
		(layer "In2.Cu")
		(net "ANT2_OUT")
	)
	(segment
		(start 119.2911 -26.8097)
		(end 118.6942 -26.2128)
		(width 0.127)
		(layer "In2.Cu")
		(net "ANT2_OUT")
	)
	(segment
		(start 30.269434 -34.036)
		(end 25.443434 -29.21)
		(width 0.127)
		(layer "In2.Cu")
		(net "ANT2_OUT")
	)
	(segment
		(start 85.38464 -24.257)
		(end 75.60564 -34.036)
		(width 0.127)
		(layer "In2.Cu")
		(net "ANT2_OUT")
	)
	(segment
		(start 17.272 -27.686)
		(end 17.018 -27.686)
		(width 0.127)
		(layer "In2.Cu")
		(net "ANT2_OUT")
	)
	(segment
		(start 125.14326 -36.2331)
		(end 125.76048 -35.61588)
		(width 0.127)
		(layer "In2.Cu")
		(net "ANT2_OUT")
	)
	(segment
		(start 95.459804 -26.72842)
		(end 94.637352 -25.905968)
		(width 0.127)
		(layer "In2.Cu")
		(net "ANT2_OUT")
	)
	(segment
		(start 21.209 -29.21)
		(end 19.812 -27.813)
		(width 0.127)
		(layer "In2.Cu")
		(net "ANT2_OUT")
	)
	(segment
		(start 117.346984 -42.323258)
		(end 117.927882 -41.74236)
		(width 0.127)
		(layer "In2.Cu")
		(net "ANT2_OUT")
	)
	(segment
		(start 117.927882 -41.74236)
		(end 117.927882 -41.149524)
		(width 0.127)
		(layer "In2.Cu")
		(net "ANT2_OUT")
	)
	(segment
		(start 104.53878 -26.72842)
		(end 95.459804 -26.72842)
		(width 0.127)
		(layer "In2.Cu")
		(net "ANT2_OUT")
	)
	(segment
		(start 120.659652 -40.3225)
		(end 121.53138 -39.450772)
		(width 0.127)
		(layer "In2.Cu")
		(net "ANT2_OUT")
	)
	(segment
		(start 125.76048 -33.47212)
		(end 124.8791 -32.59074)
		(width 0.127)
		(layer "In2.Cu")
		(net "ANT2_OUT")
	)
	(segment
		(start 121.53138 -39.450772)
		(end 121.53138 -38.46576)
		(width 0.127)
		(layer "In2.Cu")
		(net "ANT2_OUT")
	)
	(segment
		(start 75.60564 -34.036)
		(end 30.269434 -34.036)
		(width 0.127)
		(layer "In2.Cu")
		(net "ANT2_OUT")
	)
	(segment
		(start 19.812 -27.813)
		(end 17.399 -27.813)
		(width 0.127)
		(layer "In2.Cu")
		(net "ANT2_OUT")
	)
	(segment
		(start 25.443434 -29.21)
		(end 21.209 -29.21)
		(width 0.127)
		(layer "In2.Cu")
		(net "ANT2_OUT")
	)
	(segment
		(start 123.131326 -26.8097)
		(end 119.2911 -26.8097)
		(width 0.127)
		(layer "In2.Cu")
		(net "ANT2_OUT")
	)
	(segment
		(start 16.256 -38.3032)
		(end 14.986 -37.0332)
		(width 0.127)
		(layer "In7.Cu")
		(net "ANT2_OUT")
	)
	(segment
		(start 14.986 -37.0332)
		(end 14.986 -31.877)
		(width 0.127)
		(layer "In7.Cu")
		(net "ANT2_OUT")
	)
	(segment
		(start 15.494 -44.196)
		(end 15.494 -42.978578)
		(width 0.127)
		(layer "In7.Cu")
		(net "ANT2_OUT")
	)
	(segment
		(start 15.494 -42.978578)
		(end 16.256 -42.216578)
		(width 0.127)
		(layer "In7.Cu")
		(net "ANT2_OUT")
	)
	(segment
		(start 16.5735 -30.2895)
		(end 16.5735 -28.1305)
		(width 0.127)
		(layer "In7.Cu")
		(net "ANT2_OUT")
	)
	(segment
		(start 14.3256 -45.3644)
		(end 15.494 -44.196)
		(width 0.127)
		(layer "In7.Cu")
		(net "ANT2_OUT")
	)
	(segment
		(start 16.5735 -28.1305)
		(end 17.018 -27.686)
		(width 0.127)
		(layer "In7.Cu")
		(net "ANT2_OUT")
	)
	(segment
		(start 13.716 -54.229)
		(end 13.716 -54.102)
		(width 0.127)
		(layer "In7.Cu")
		(net "ANT2_OUT")
	)
	(segment
		(start 13.716 -54.102)
		(end 13.6144 -54.0004)
		(width 0.127)
		(layer "In7.Cu")
		(net "ANT2_OUT")
	)
	(segment
		(start 14.3256 -51.3334)
		(end 14.3256 -45.3644)
		(width 0.127)
		(layer "In7.Cu")
		(net "ANT2_OUT")
	)
	(segment
		(start 13.6144 -54.0004)
		(end 13.6144 -52.0446)
		(width 0.127)
		(layer "In7.Cu")
		(net "ANT2_OUT")
	)
	(segment
		(start 13.6144 -52.0446)
		(end 14.3256 -51.3334)
		(width 0.127)
		(layer "In7.Cu")
		(net "ANT2_OUT")
	)
	(segment
		(start 14.986 -31.877)
		(end 16.5735 -30.2895)
		(width 0.127)
		(layer "In7.Cu")
		(net "ANT2_OUT")
	)
	(segment
		(start 16.256 -42.216578)
		(end 16.256 -38.3032)
		(width 0.127)
		(layer "In7.Cu")
		(net "ANT2_OUT")
	)
	(segment
		(start 118.847108 -52.82311)
		(end 119.34698 -53.322982)
		(width 0.11938)
		(layer "F.Cu")
		(net "ANT2_IN")
	)
	(segment
		(start 11.74877 -54.102)
		(end 12.192 -53.65877)
		(width 0.11938)
		(layer "F.Cu")
		(net "ANT2_IN")
	)
	(segment
		(start 12.192 -53.65877)
		(end 12.192 -53.1114)
		(width 0.11938)
		(layer "F.Cu")
		(net "ANT2_IN")
	)
	(segment
		(start 11.43 -54.102)
		(end 11.74877 -54.102)
		(width 0.11938)
		(layer "F.Cu")
		(net "ANT2_IN")
	)
	(via
		(at 119.34698 -53.322982)
		(size 0.4572)
		(drill 0.2032)
		(layers "F.Cu" "B.Cu")
		(net "ANT2_IN")
	)
	(via
		(at 24.511 -59.817)
		(size 0.508)
		(drill 0.254)
		(layers "F.Cu" "B.Cu")
		(net "ANT2_IN")
	)
	(via
		(at 11.43 -54.102)
		(size 0.508)
		(drill 0.254)
		(layers "F.Cu" "B.Cu")
		(net "ANT2_IN")
	)
	(segment
		(start 24.511 -59.817)
		(end 25.12949 -59.19851)
		(width 0.11938)
		(layer "B.Cu")
		(net "ANT2_IN")
	)
	(segment
		(start 13.842746 -55.118)
		(end 12.336526 -55.118)
		(width 0.11938)
		(layer "B.Cu")
		(net "ANT2_IN")
	)
	(segment
		(start 24.257 -56.388)
		(end 20.574 -56.388)
		(width 0.11938)
		(layer "B.Cu")
		(net "ANT2_IN")
	)
	(segment
		(start 15.24 -54.864)
		(end 14.096746 -54.864)
		(width 0.11938)
		(layer "B.Cu")
		(net "ANT2_IN")
	)
	(segment
		(start 20.574 -56.388)
		(end 19.431 -55.245)
		(width 0.11938)
		(layer "B.Cu")
		(net "ANT2_IN")
	)
	(segment
		(start 118.847108 -52.82311)
		(end 119.34698 -53.322982)
		(width 0.11938)
		(layer "B.Cu")
		(net "ANT2_IN")
	)
	(segment
		(start 12.336526 -55.118)
		(end 11.43 -54.211474)
		(width 0.11938)
		(layer "B.Cu")
		(net "ANT2_IN")
	)
	(segment
		(start 25.12949 -59.19851)
		(end 25.12949 -57.26049)
		(width 0.11938)
		(layer "B.Cu")
		(net "ANT2_IN")
	)
	(segment
		(start 14.096746 -54.864)
		(end 13.842746 -55.118)
		(width 0.11938)
		(layer "B.Cu")
		(net "ANT2_IN")
	)
	(segment
		(start 15.621 -55.245)
		(end 15.24 -54.864)
		(width 0.11938)
		(layer "B.Cu")
		(net "ANT2_IN")
	)
	(segment
		(start 19.431 -55.245)
		(end 15.621 -55.245)
		(width 0.11938)
		(layer "B.Cu")
		(net "ANT2_IN")
	)
	(segment
		(start 25.12949 -57.26049)
		(end 24.257 -56.388)
		(width 0.11938)
		(layer "B.Cu")
		(net "ANT2_IN")
	)
	(segment
		(start 11.43 -54.211474)
		(end 11.43 -54.102)
		(width 0.11938)
		(layer "B.Cu")
		(net "ANT2_IN")
	)
	(segment
		(start 123.5329 -69.7611)
		(end 123.5329 -59.834526)
		(width 0.127)
		(layer "In7.Cu")
		(net "ANT2_IN")
	)
	(segment
		(start 64.071754 -86.5505)
		(end 85.9155 -86.5505)
		(width 0.127)
		(layer "In7.Cu")
		(net "ANT2_IN")
	)
	(segment
		(start 123.5329 -59.834526)
		(end 121.412 -57.713626)
		(width 0.127)
		(layer "In7.Cu")
		(net "ANT2_IN")
	)
	(segment
		(start 116.586 -84.709)
		(end 118.237 -83.058)
		(width 0.127)
		(layer "In7.Cu")
		(net "ANT2_IN")
	)
	(segment
		(start 118.237 -81.015332)
		(end 120.1166 -79.135732)
		(width 0.127)
		(layer "In7.Cu")
		(net "ANT2_IN")
	)
	(segment
		(start 107.649518 -87.503)
		(end 107.840018 -87.3125)
		(width 0.127)
		(layer "In7.Cu")
		(net "ANT2_IN")
	)
	(segment
		(start 24.511 -59.817)
		(end 29.0576 -64.3636)
		(width 0.127)
		(layer "In7.Cu")
		(net "ANT2_IN")
	)
	(segment
		(start 97.028 -90.424)
		(end 99.949 -87.503)
		(width 0.127)
		(layer "In7.Cu")
		(net "ANT2_IN")
	)
	(segment
		(start 115.57 -84.709)
		(end 116.586 -84.709)
		(width 0.127)
		(layer "In7.Cu")
		(net "ANT2_IN")
	)
	(segment
		(start 57.658 -71.388986)
		(end 57.658 -80.136746)
		(width 0.127)
		(layer "In7.Cu")
		(net "ANT2_IN")
	)
	(segment
		(start 119.8118 -53.787802)
		(end 119.34698 -53.322982)
		(width 0.127)
		(layer "In7.Cu")
		(net "ANT2_IN")
	)
	(segment
		(start 120.1166 -79.135732)
		(end 120.1166 -73.1774)
		(width 0.127)
		(layer "In7.Cu")
		(net "ANT2_IN")
	)
	(segment
		(start 121.412 -57.023)
		(end 119.8118 -55.4228)
		(width 0.127)
		(layer "In7.Cu")
		(net "ANT2_IN")
	)
	(segment
		(start 89.8525 -87.8205)
		(end 92.456 -90.424)
		(width 0.127)
		(layer "In7.Cu")
		(net "ANT2_IN")
	)
	(segment
		(start 109.707934 -87.3125)
		(end 110.533434 -88.138)
		(width 0.127)
		(layer "In7.Cu")
		(net "ANT2_IN")
	)
	(segment
		(start 87.1855 -87.8205)
		(end 89.8525 -87.8205)
		(width 0.127)
		(layer "In7.Cu")
		(net "ANT2_IN")
	)
	(segment
		(start 50.632614 -64.3636)
		(end 57.658 -71.388986)
		(width 0.127)
		(layer "In7.Cu")
		(net "ANT2_IN")
	)
	(segment
		(start 57.658 -80.136746)
		(end 64.071754 -86.5505)
		(width 0.127)
		(layer "In7.Cu")
		(net "ANT2_IN")
	)
	(segment
		(start 110.533434 -88.138)
		(end 112.141 -88.138)
		(width 0.127)
		(layer "In7.Cu")
		(net "ANT2_IN")
	)
	(segment
		(start 107.840018 -87.3125)
		(end 109.707934 -87.3125)
		(width 0.127)
		(layer "In7.Cu")
		(net "ANT2_IN")
	)
	(segment
		(start 29.0576 -64.3636)
		(end 50.632614 -64.3636)
		(width 0.127)
		(layer "In7.Cu")
		(net "ANT2_IN")
	)
	(segment
		(start 92.456 -90.424)
		(end 97.028 -90.424)
		(width 0.127)
		(layer "In7.Cu")
		(net "ANT2_IN")
	)
	(segment
		(start 119.8118 -55.4228)
		(end 119.8118 -53.787802)
		(width 0.127)
		(layer "In7.Cu")
		(net "ANT2_IN")
	)
	(segment
		(start 121.412 -57.713626)
		(end 121.412 -57.023)
		(width 0.127)
		(layer "In7.Cu")
		(net "ANT2_IN")
	)
	(segment
		(start 85.9155 -86.5505)
		(end 87.1855 -87.8205)
		(width 0.127)
		(layer "In7.Cu")
		(net "ANT2_IN")
	)
	(segment
		(start 99.949 -87.503)
		(end 107.649518 -87.503)
		(width 0.127)
		(layer "In7.Cu")
		(net "ANT2_IN")
	)
	(segment
		(start 112.141 -88.138)
		(end 115.57 -84.709)
		(width 0.127)
		(layer "In7.Cu")
		(net "ANT2_IN")
	)
	(segment
		(start 120.1166 -73.1774)
		(end 123.5329 -69.7611)
		(width 0.127)
		(layer "In7.Cu")
		(net "ANT2_IN")
	)
	(segment
		(start 118.237 -83.058)
		(end 118.237 -81.015332)
		(width 0.127)
		(layer "In7.Cu")
		(net "ANT2_IN")
	)
	(segment
		(start 12.250928 -67.19062)
		(end 12.258548 -67.183)
		(width 0.11938)
		(layer "F.Cu")
		(net "ANT1_OUT")
	)
	(segment
		(start 12.258548 -67.183)
		(end 12.5476 -67.183)
		(width 0.11938)
		(layer "F.Cu")
		(net "ANT1_OUT")
	)
	(segment
		(start 115.847114 -42.82313)
		(end 116.34724 -43.323256)
		(width 0.11938)
		(layer "F.Cu")
		(net "ANT1_OUT")
	)
	(segment
		(start 12.5476 -67.183)
		(end 13.0302 -66.7004)
		(width 0.11938)
		(layer "F.Cu")
		(net "ANT1_OUT")
	)
	(segment
		(start 13.0302 -66.7004)
		(end 13.462 -66.7004)
		(width 0.11938)
		(layer "F.Cu")
		(net "ANT1_OUT")
	)
	(via
		(at 116.34724 -43.323256)
		(size 0.4572)
		(drill 0.2032)
		(layers "F.Cu" "B.Cu")
		(net "ANT1_OUT")
	)
	(via
		(at 12.250928 -67.19062)
		(size 0.508)
		(drill 0.254)
		(layers "F.Cu" "B.Cu")
		(net "ANT1_OUT")
	)
	(via
		(at 18.669 -28.575)
		(size 0.508)
		(drill 0.254)
		(layers "F.Cu" "B.Cu")
		(net "ANT1_OUT")
	)
	(segment
		(start 125.25248 -35.405314)
		(end 125.25248 -33.682686)
		(width 0.127)
		(layer "In2.Cu")
		(net "ANT1_OUT")
	)
	(segment
		(start 123.3297 -27.72664)
		(end 122.92076 -27.3177)
		(width 0.127)
		(layer "In2.Cu")
		(net "ANT1_OUT")
	)
	(segment
		(start 93.198188 -26.015188)
		(end 91.9607 -24.7777)
		(width 0.127)
		(layer "In2.Cu")
		(net "ANT1_OUT")
	)
	(segment
		(start 117.740684 -40.486584)
		(end 117.740684 -40.27805)
		(width 0.127)
		(layer "In2.Cu")
		(net "ANT1_OUT")
	)
	(segment
		(start 121.09704 -39.166292)
		(end 121.09704 -38.18128)
		(width 0.127)
		(layer "In2.Cu")
		(net "ANT1_OUT")
	)
	(segment
		(start 119.08028 -27.3177)
		(end 118.48338 -26.7208)
		(width 0.127)
		(layer "In2.Cu")
		(net "ANT1_OUT")
	)
	(segment
		(start 117.510306 -40.716962)
		(end 117.740684 -40.486584)
		(width 0.127)
		(layer "In2.Cu")
		(net "ANT1_OUT")
	)
	(segment
		(start 118.204234 -39.8145)
		(end 120.448832 -39.8145)
		(width 0.127)
		(layer "In2.Cu")
		(net "ANT1_OUT")
	)
	(segment
		(start 124.335794 -32.766)
		(end 124.12726 -32.766)
		(width 0.127)
		(layer "In2.Cu")
		(net "ANT1_OUT")
	)
	(segment
		(start 19.812 -28.575)
		(end 18.669 -28.575)
		(width 0.127)
		(layer "In2.Cu")
		(net "ANT1_OUT")
	)
	(segment
		(start 93.532706 -26.689812)
		(end 93.198188 -26.355294)
		(width 0.127)
		(layer "In2.Cu")
		(net "ANT1_OUT")
	)
	(segment
		(start 125.25248 -33.682686)
		(end 124.335794 -32.766)
		(width 0.127)
		(layer "In2.Cu")
		(net "ANT1_OUT")
	)
	(segment
		(start 95.166434 -27.23642)
		(end 94.619826 -26.689812)
		(width 0.127)
		(layer "In2.Cu")
		(net "ANT1_OUT")
	)
	(segment
		(start 104.84358 -27.23642)
		(end 95.166434 -27.23642)
		(width 0.127)
		(layer "In2.Cu")
		(net "ANT1_OUT")
	)
	(segment
		(start 116.34724 -43.323256)
		(end 116.846858 -42.823638)
		(width 0.127)
		(layer "In2.Cu")
		(net "ANT1_OUT")
	)
	(segment
		(start 117.016784 -40.716962)
		(end 117.510306 -40.716962)
		(width 0.127)
		(layer "In2.Cu")
		(net "ANT1_OUT")
	)
	(segment
		(start 122.92076 -27.3177)
		(end 119.08028 -27.3177)
		(width 0.127)
		(layer "In2.Cu")
		(net "ANT1_OUT")
	)
	(segment
		(start 116.846858 -42.823638)
		(end 116.846858 -40.886888)
		(width 0.127)
		(layer "In2.Cu")
		(net "ANT1_OUT")
	)
	(segment
		(start 85.582506 -24.7777)
		(end 75.816206 -34.544)
		(width 0.127)
		(layer "In2.Cu")
		(net "ANT1_OUT")
	)
	(segment
		(start 123.55322 -35.7251)
		(end 124.932694 -35.7251)
		(width 0.127)
		(layer "In2.Cu")
		(net "ANT1_OUT")
	)
	(segment
		(start 118.48338 -26.7208)
		(end 105.3592 -26.7208)
		(width 0.127)
		(layer "In2.Cu")
		(net "ANT1_OUT")
	)
	(segment
		(start 116.846858 -40.886888)
		(end 117.016784 -40.716962)
		(width 0.127)
		(layer "In2.Cu")
		(net "ANT1_OUT")
	)
	(segment
		(start 120.448832 -39.8145)
		(end 121.09704 -39.166292)
		(width 0.127)
		(layer "In2.Cu")
		(net "ANT1_OUT")
	)
	(segment
		(start 105.3592 -26.7208)
		(end 104.84358 -27.23642)
		(width 0.127)
		(layer "In2.Cu")
		(net "ANT1_OUT")
	)
	(segment
		(start 124.932694 -35.7251)
		(end 125.25248 -35.405314)
		(width 0.127)
		(layer "In2.Cu")
		(net "ANT1_OUT")
	)
	(segment
		(start 123.3297 -31.96844)
		(end 123.3297 -27.72664)
		(width 0.127)
		(layer "In2.Cu")
		(net "ANT1_OUT")
	)
	(segment
		(start 124.12726 -32.766)
		(end 123.3297 -31.96844)
		(width 0.127)
		(layer "In2.Cu")
		(net "ANT1_OUT")
	)
	(segment
		(start 94.619826 -26.689812)
		(end 93.532706 -26.689812)
		(width 0.127)
		(layer "In2.Cu")
		(net "ANT1_OUT")
	)
	(segment
		(start 21.082 -29.845)
		(end 19.812 -28.575)
		(width 0.127)
		(layer "In2.Cu")
		(net "ANT1_OUT")
	)
	(segment
		(start 121.09704 -38.18128)
		(end 123.55322 -35.7251)
		(width 0.127)
		(layer "In2.Cu")
		(net "ANT1_OUT")
	)
	(segment
		(start 30.058868 -34.544)
		(end 25.359868 -29.845)
		(width 0.127)
		(layer "In2.Cu")
		(net "ANT1_OUT")
	)
	(segment
		(start 91.9607 -24.7777)
		(end 85.582506 -24.7777)
		(width 0.127)
		(layer "In2.Cu")
		(net "ANT1_OUT")
	)
	(segment
		(start 75.816206 -34.544)
		(end 30.058868 -34.544)
		(width 0.127)
		(layer "In2.Cu")
		(net "ANT1_OUT")
	)
	(segment
		(start 117.740684 -40.27805)
		(end 118.204234 -39.8145)
		(width 0.127)
		(layer "In2.Cu")
		(net "ANT1_OUT")
	)
	(segment
		(start 25.359868 -29.845)
		(end 21.082 -29.845)
		(width 0.127)
		(layer "In2.Cu")
		(net "ANT1_OUT")
	)
	(segment
		(start 93.198188 -26.355294)
		(end 93.198188 -26.015188)
		(width 0.127)
		(layer "In2.Cu")
		(net "ANT1_OUT")
	)
	(segment
		(start 14.3383 -63.1317)
		(end 14.3383 -62.357)
		(width 0.127)
		(layer "In7.Cu")
		(net "ANT1_OUT")
	)
	(segment
		(start 14.986 -51.181)
		(end 14.986 -47.244254)
		(width 0.127)
		(layer "In7.Cu")
		(net "ANT1_OUT")
	)
	(segment
		(start 13.208 -66.233548)
		(end 13.208 -64.262)
		(width 0.127)
		(layer "In7.Cu")
		(net "ANT1_OUT")
	)
	(segment
		(start 15.494 -32.258)
		(end 16.129 -31.623)
		(width 0.127)
		(layer "In7.Cu")
		(net "ANT1_OUT")
	)
	(segment
		(start 14.3383 -62.357)
		(end 14.986 -61.7093)
		(width 0.127)
		(layer "In7.Cu")
		(net "ANT1_OUT")
	)
	(segment
		(start 17.145 -55.025036)
		(end 17.145 -52.578)
		(width 0.127)
		(layer "In7.Cu")
		(net "ANT1_OUT")
	)
	(segment
		(start 15.3035 -56.866536)
		(end 17.145 -55.025036)
		(width 0.127)
		(layer "In7.Cu")
		(net "ANT1_OUT")
	)
	(segment
		(start 17.907 -30.734)
		(end 17.907 -29.337)
		(width 0.127)
		(layer "In7.Cu")
		(net "ANT1_OUT")
	)
	(segment
		(start 13.208 -64.262)
		(end 14.3383 -63.1317)
		(width 0.127)
		(layer "In7.Cu")
		(net "ANT1_OUT")
	)
	(segment
		(start 15.494 -36.822634)
		(end 15.494 -32.258)
		(width 0.127)
		(layer "In7.Cu")
		(net "ANT1_OUT")
	)
	(segment
		(start 17.907 -29.337)
		(end 18.669 -28.575)
		(width 0.127)
		(layer "In7.Cu")
		(net "ANT1_OUT")
	)
	(segment
		(start 15.24 -51.435)
		(end 14.986 -51.181)
		(width 0.127)
		(layer "In7.Cu")
		(net "ANT1_OUT")
	)
	(segment
		(start 17.399 -44.831254)
		(end 17.399 -38.727634)
		(width 0.127)
		(layer "In7.Cu")
		(net "ANT1_OUT")
	)
	(segment
		(start 17.145 -52.578)
		(end 16.002 -51.435)
		(width 0.127)
		(layer "In7.Cu")
		(net "ANT1_OUT")
	)
	(segment
		(start 16.002 -51.435)
		(end 15.24 -51.435)
		(width 0.127)
		(layer "In7.Cu")
		(net "ANT1_OUT")
	)
	(segment
		(start 16.129 -31.623)
		(end 17.018 -31.623)
		(width 0.127)
		(layer "In7.Cu")
		(net "ANT1_OUT")
	)
	(segment
		(start 17.018 -31.623)
		(end 17.907 -30.734)
		(width 0.127)
		(layer "In7.Cu")
		(net "ANT1_OUT")
	)
	(segment
		(start 15.3035 -57.82056)
		(end 15.3035 -56.866536)
		(width 0.127)
		(layer "In7.Cu")
		(net "ANT1_OUT")
	)
	(segment
		(start 17.399 -38.727634)
		(end 15.494 -36.822634)
		(width 0.127)
		(layer "In7.Cu")
		(net "ANT1_OUT")
	)
	(segment
		(start 12.250928 -67.19062)
		(end 13.208 -66.233548)
		(width 0.127)
		(layer "In7.Cu")
		(net "ANT1_OUT")
	)
	(segment
		(start 14.986 -61.7093)
		(end 14.986 -58.13806)
		(width 0.127)
		(layer "In7.Cu")
		(net "ANT1_OUT")
	)
	(segment
		(start 14.986 -58.13806)
		(end 15.3035 -57.82056)
		(width 0.127)
		(layer "In7.Cu")
		(net "ANT1_OUT")
	)
	(segment
		(start 14.986 -47.244254)
		(end 17.399 -44.831254)
		(width 0.127)
		(layer "In7.Cu")
		(net "ANT1_OUT")
	)
	(segment
		(start 13.335 -70.612)
		(end 12.827 -70.612)
		(width 0.11938)
		(layer "F.Cu")
		(net "ANT1_IN")
	)
	(segment
		(start 12.827 -70.612)
		(end 11.43 -69.215)
		(width 0.11938)
		(layer "F.Cu")
		(net "ANT1_IN")
	)
	(segment
		(start 11.43 -69.215)
		(end 11.43 -67.0306)
		(width 0.11938)
		(layer "F.Cu")
		(net "ANT1_IN")
	)
	(segment
		(start 11.43 -67.0306)
		(end 12.1412 -66.3194)
		(width 0.11938)
		(layer "F.Cu")
		(net "ANT1_IN")
	)
	(segment
		(start 118.847108 -53.823108)
		(end 119.34698 -54.32298)
		(width 0.11938)
		(layer "F.Cu")
		(net "ANT1_IN")
	)
	(via
		(at 13.335 -70.612)
		(size 0.508)
		(drill 0.254)
		(layers "F.Cu" "B.Cu")
		(net "ANT1_IN")
	)
	(via
		(at 119.34698 -54.32298)
		(size 0.4572)
		(drill 0.2032)
		(layers "F.Cu" "B.Cu")
		(net "ANT1_IN")
	)
	(via
		(at 25.527 -72.32142)
		(size 0.762)
		(drill 0.381)
		(layers "F.Cu" "B.Cu")
		(net "ANT1_IN")
	)
	(via
		(at 95.377 -89.027)
		(size 0.4572)
		(drill 0.2032)
		(layers "F.Cu" "B.Cu")
		(net "ANT1_IN")
	)
	(segment
		(start 21.32838 -73.66)
		(end 21.082 -73.41362)
		(width 0.11938)
		(layer "B.Cu")
		(net "ANT1_IN")
	)
	(segment
		(start 92.71889 -80.78089)
		(end 90.424 -78.486)
		(width 0.11938)
		(layer "B.Cu")
		(net "ANT1_IN")
	)
	(segment
		(start 23.18131 -72.70369)
		(end 22.225 -73.66)
		(width 0.11938)
		(layer "B.Cu")
		(net "ANT1_IN")
	)
	(segment
		(start 40.386 -71.755)
		(end 26.09342 -71.755)
		(width 0.11938)
		(layer "B.Cu")
		(net "ANT1_IN")
	)
	(segment
		(start 73.5711 -77.851)
		(end 67.26682 -84.15528)
		(width 0.11938)
		(layer "B.Cu")
		(net "ANT1_IN")
	)
	(segment
		(start 22.225 -73.66)
		(end 22.128734 -73.66)
		(width 0.11938)
		(layer "B.Cu")
		(net "ANT1_IN")
	)
	(segment
		(start 26.09342 -71.755)
		(end 25.527 -72.32142)
		(width 0.11938)
		(layer "B.Cu")
		(net "ANT1_IN")
	)
	(segment
		(start 89.494614 -79.05369)
		(end 88.813386 -79.05369)
		(width 0.11938)
		(layer "B.Cu")
		(net "ANT1_IN")
	)
	(segment
		(start 90.062304 -78.486)
		(end 89.494614 -79.05369)
		(width 0.11938)
		(layer "B.Cu")
		(net "ANT1_IN")
	)
	(segment
		(start 76.327 -77.851)
		(end 73.5711 -77.851)
		(width 0.11938)
		(layer "B.Cu")
		(net "ANT1_IN")
	)
	(segment
		(start 88.432386 -78.67269)
		(end 87.543386 -78.67269)
		(width 0.11938)
		(layer "B.Cu")
		(net "ANT1_IN")
	)
	(segment
		(start 90.424 -78.486)
		(end 90.062304 -78.486)
		(width 0.11938)
		(layer "B.Cu")
		(net "ANT1_IN")
	)
	(segment
		(start 59.41568 -72.24268)
		(end 57.658 -70.485)
		(width 0.11938)
		(layer "B.Cu")
		(net "ANT1_IN")
	)
	(segment
		(start 87.102696 -78.232)
		(end 84.876894 -78.232)
		(width 0.11938)
		(layer "B.Cu")
		(net "ANT1_IN")
	)
	(segment
		(start 25.527 -72.32142)
		(end 25.14473 -72.70369)
		(width 0.11938)
		(layer "B.Cu")
		(net "ANT1_IN")
	)
	(segment
		(start 61.304424 -84.15528)
		(end 59.41568 -82.266536)
		(width 0.11938)
		(layer "B.Cu")
		(net "ANT1_IN")
	)
	(segment
		(start 67.26682 -84.15528)
		(end 61.304424 -84.15528)
		(width 0.11938)
		(layer "B.Cu")
		(net "ANT1_IN")
	)
	(segment
		(start 88.813386 -79.05369)
		(end 88.432386 -78.67269)
		(width 0.11938)
		(layer "B.Cu")
		(net "ANT1_IN")
	)
	(segment
		(start 57.658 -70.485)
		(end 41.656 -70.485)
		(width 0.11938)
		(layer "B.Cu")
		(net "ANT1_IN")
	)
	(segment
		(start 84.876894 -78.232)
		(end 83.352894 -79.756)
		(width 0.11938)
		(layer "B.Cu")
		(net "ANT1_IN")
	)
	(segment
		(start 21.505164 -73.707498)
		(end 21.457666 -73.66)
		(width 0.11938)
		(layer "B.Cu")
		(net "ANT1_IN")
	)
	(segment
		(start 95.377 -89.027)
		(end 92.71889 -86.36889)
		(width 0.11938)
		(layer "B.Cu")
		(net "ANT1_IN")
	)
	(segment
		(start 78.232 -79.756)
		(end 76.327 -77.851)
		(width 0.11938)
		(layer "B.Cu")
		(net "ANT1_IN")
	)
	(segment
		(start 87.543386 -78.67269)
		(end 87.102696 -78.232)
		(width 0.11938)
		(layer "B.Cu")
		(net "ANT1_IN")
	)
	(segment
		(start 21.082 -72.517)
		(end 19.177 -70.612)
		(width 0.11938)
		(layer "B.Cu")
		(net "ANT1_IN")
	)
	(segment
		(start 59.41568 -82.266536)
		(end 59.41568 -72.24268)
		(width 0.11938)
		(layer "B.Cu")
		(net "ANT1_IN")
	)
	(segment
		(start 119.846852 -53.823108)
		(end 119.34698 -54.32298)
		(width 0.11938)
		(layer "B.Cu")
		(net "ANT1_IN")
	)
	(segment
		(start 41.656 -70.485)
		(end 40.386 -71.755)
		(width 0.11938)
		(layer "B.Cu")
		(net "ANT1_IN")
	)
	(segment
		(start 83.352894 -79.756)
		(end 78.232 -79.756)
		(width 0.11938)
		(layer "B.Cu")
		(net "ANT1_IN")
	)
	(segment
		(start 119.847106 -53.823108)
		(end 119.846852 -53.823108)
		(width 0.11938)
		(layer "B.Cu")
		(net "ANT1_IN")
	)
	(segment
		(start 22.128734 -73.66)
		(end 22.081236 -73.707498)
		(width 0.11938)
		(layer "B.Cu")
		(net "ANT1_IN")
	)
	(segment
		(start 21.082 -73.41362)
		(end 21.082 -72.517)
		(width 0.11938)
		(layer "B.Cu")
		(net "ANT1_IN")
	)
	(segment
		(start 19.177 -70.612)
		(end 13.335 -70.612)
		(width 0.11938)
		(layer "B.Cu")
		(net "ANT1_IN")
	)
	(segment
		(start 22.081236 -73.707498)
		(end 21.505164 -73.707498)
		(width 0.11938)
		(layer "B.Cu")
		(net "ANT1_IN")
	)
	(segment
		(start 92.71889 -86.36889)
		(end 92.71889 -80.78089)
		(width 0.11938)
		(layer "B.Cu")
		(net "ANT1_IN")
	)
	(segment
		(start 21.457666 -73.66)
		(end 21.32838 -73.66)
		(width 0.11938)
		(layer "B.Cu")
		(net "ANT1_IN")
	)
	(segment
		(start 25.14473 -72.70369)
		(end 23.18131 -72.70369)
		(width 0.11938)
		(layer "B.Cu")
		(net "ANT1_IN")
	)
	(segment
		(start 104.587548 -86.9315)
		(end 104.778048 -86.741)
		(width 0.127)
		(layer "In7.Cu")
		(net "ANT1_IN")
	)
	(segment
		(start 121.539 -68.7832)
		(end 122.8725 -67.4497)
		(width 0.127)
		(layer "In7.Cu")
		(net "ANT1_IN")
	)
	(segment
		(start 117.602 -80.931766)
		(end 119.6086 -78.925166)
		(width 0.127)
		(layer "In7.Cu")
		(net "ANT1_IN")
	)
	(segment
		(start 122.8725 -61.0235)
		(end 120.142 -58.293)
		(width 0.127)
		(layer "In7.Cu")
		(net "ANT1_IN")
	)
	(segment
		(start 119.6086 -78.925166)
		(end 119.6086 -72.7964)
		(width 0.127)
		(layer "In7.Cu")
		(net "ANT1_IN")
	)
	(segment
		(start 117.602 -82.931)
		(end 117.602 -80.931766)
		(width 0.127)
		(layer "In7.Cu")
		(net "ANT1_IN")
	)
	(segment
		(start 116.459 -84.074)
		(end 117.602 -82.931)
		(width 0.127)
		(layer "In7.Cu")
		(net "ANT1_IN")
	)
	(segment
		(start 119.6086 -72.7964)
		(end 121.539 -70.866)
		(width 0.127)
		(layer "In7.Cu")
		(net "ANT1_IN")
	)
	(segment
		(start 95.377 -89.027)
		(end 95.8088 -88.5952)
		(width 0.127)
		(layer "In7.Cu")
		(net "ANT1_IN")
	)
	(segment
		(start 122.8725 -67.4497)
		(end 122.8725 -61.0235)
		(width 0.127)
		(layer "In7.Cu")
		(net "ANT1_IN")
	)
	(segment
		(start 99.7585 -86.9315)
		(end 104.587548 -86.9315)
		(width 0.127)
		(layer "In7.Cu")
		(net "ANT1_IN")
	)
	(segment
		(start 120.142 -58.293)
		(end 120.142 -56.896)
		(width 0.127)
		(layer "In7.Cu")
		(net "ANT1_IN")
	)
	(segment
		(start 98.0948 -88.5952)
		(end 99.7585 -86.9315)
		(width 0.127)
		(layer "In7.Cu")
		(net "ANT1_IN")
	)
	(segment
		(start 120.142 -56.896)
		(end 118.95328 -55.70728)
		(width 0.127)
		(layer "In7.Cu")
		(net "ANT1_IN")
	)
	(segment
		(start 109.855 -86.741)
		(end 110.744 -87.63)
		(width 0.127)
		(layer "In7.Cu")
		(net "ANT1_IN")
	)
	(segment
		(start 110.744 -87.63)
		(end 111.76 -87.63)
		(width 0.127)
		(layer "In7.Cu")
		(net "ANT1_IN")
	)
	(segment
		(start 115.316 -84.074)
		(end 116.459 -84.074)
		(width 0.127)
		(layer "In7.Cu")
		(net "ANT1_IN")
	)
	(segment
		(start 104.778048 -86.741)
		(end 109.855 -86.741)
		(width 0.127)
		(layer "In7.Cu")
		(net "ANT1_IN")
	)
	(segment
		(start 111.76 -87.63)
		(end 115.316 -84.074)
		(width 0.127)
		(layer "In7.Cu")
		(net "ANT1_IN")
	)
	(segment
		(start 118.95328 -54.71668)
		(end 119.34698 -54.32298)
		(width 0.127)
		(layer "In7.Cu")
		(net "ANT1_IN")
	)
	(segment
		(start 121.539 -70.866)
		(end 121.539 -68.7832)
		(width 0.127)
		(layer "In7.Cu")
		(net "ANT1_IN")
	)
	(segment
		(start 95.8088 -88.5952)
		(end 98.0948 -88.5952)
		(width 0.127)
		(layer "In7.Cu")
		(net "ANT1_IN")
	)
	(segment
		(start 118.95328 -55.70728)
		(end 118.95328 -54.71668)
		(width 0.127)
		(layer "In7.Cu")
		(net "ANT1_IN")
	)
	(segment
		(start 116.847112 -44.823126)
		(end 117.346984 -45.322998)
		(width 0.11938)
		(layer "F.Cu")
		(net "ANT4_OUT")
	)
	(segment
		(start 106.045 -18.542)
		(end 106.045 -19.05)
		(width 0.11938)
		(layer "F.Cu")
		(net "ANT4_OUT")
	)
	(segment
		(start 116.84 -19.304)
		(end 115.443 -17.907)
		(width 0.11938)
		(layer "F.Cu")
		(net "ANT4_OUT")
	)
	(segment
		(start 106.68 -17.907)
		(end 106.045 -18.542)
		(width 0.11938)
		(layer "F.Cu")
		(net "ANT4_OUT")
	)
	(segment
		(start 13.589 -24.09571)
		(end 13.14831 -24.5364)
		(width 0.11938)
		(layer "F.Cu")
		(net "ANT4_OUT")
	)
	(segment
		(start 13.589 -23.5204)
		(end 13.589 -24.09571)
		(width 0.11938)
		(layer "F.Cu")
		(net "ANT4_OUT")
	)
	(segment
		(start 115.443 -17.907)
		(end 106.68 -17.907)
		(width 0.11938)
		(layer "F.Cu")
		(net "ANT4_OUT")
	)
	(via
		(at 117.346984 -45.322998)
		(size 0.4572)
		(drill 0.2032)
		(layers "F.Cu" "B.Cu")
		(net "ANT4_OUT")
	)
	(via
		(at 106.045 -19.05)
		(size 0.508)
		(drill 0.254)
		(layers "F.Cu" "B.Cu")
		(net "ANT4_OUT")
	)
	(via
		(at 22.987 -26.67)
		(size 0.508)
		(drill 0.254)
		(layers "F.Cu" "B.Cu")
		(net "ANT4_OUT")
	)
	(via
		(at 13.14831 -24.5364)
		(size 0.4572)
		(drill 0.2032)
		(layers "F.Cu" "B.Cu")
		(net "ANT4_OUT")
	)
	(via
		(at 116.84 -19.304)
		(size 0.508)
		(drill 0.254)
		(layers "F.Cu" "B.Cu")
		(net "ANT4_OUT")
	)
	(segment
		(start 17.447006 -28.51531)
		(end 16.624808 -28.51531)
		(width 0.11938)
		(layer "B.Cu")
		(net "ANT4_OUT")
	)
	(segment
		(start 20.26031 -29.39669)
		(end 18.328386 -29.39669)
		(width 0.11938)
		(layer "B.Cu")
		(net "ANT4_OUT")
	)
	(segment
		(start 16.379698 -28.2702)
		(end 15.8242 -28.2702)
		(width 0.11938)
		(layer "B.Cu")
		(net "ANT4_OUT")
	)
	(segment
		(start 22.987 -26.67)
		(end 20.26031 -29.39669)
		(width 0.11938)
		(layer "B.Cu")
		(net "ANT4_OUT")
	)
	(segment
		(start 15.8242 -28.2702)
		(end 13.14831 -25.59431)
		(width 0.11938)
		(layer "B.Cu")
		(net "ANT4_OUT")
	)
	(segment
		(start 18.328386 -29.39669)
		(end 17.447006 -28.51531)
		(width 0.11938)
		(layer "B.Cu")
		(net "ANT4_OUT")
	)
	(segment
		(start 13.14831 -25.59431)
		(end 13.14831 -24.5364)
		(width 0.11938)
		(layer "B.Cu")
		(net "ANT4_OUT")
	)
	(segment
		(start 16.624808 -28.51531)
		(end 16.379698 -28.2702)
		(width 0.11938)
		(layer "B.Cu")
		(net "ANT4_OUT")
	)
	(segment
		(start 122.507756 -45.004736)
		(end 122.261376 -44.758356)
		(width 0.127)
		(layer "In2.Cu")
		(net "ANT4_OUT")
	)
	(segment
		(start 95.504 -22.86)
		(end 95.504 -21.209)
		(width 0.127)
		(layer "In2.Cu")
		(net "ANT4_OUT")
	)
	(segment
		(start 127.363982 -41.9735)
		(end 125.747018 -41.9735)
		(width 0.127)
		(layer "In2.Cu")
		(net "ANT4_OUT")
	)
	(segment
		(start 31.369 -32.512)
		(end 26.162 -27.305)
		(width 0.127)
		(layer "In2.Cu")
		(net "ANT4_OUT")
	)
	(segment
		(start 88.565482 -22.098)
		(end 87.993982 -22.6695)
		(width 0.127)
		(layer "In2.Cu")
		(net "ANT4_OUT")
	)
	(segment
		(start 128.5875 -40.749982)
		(end 127.363982 -41.9735)
		(width 0.127)
		(layer "In2.Cu")
		(net "ANT4_OUT")
	)
	(segment
		(start 128.5875 -35.70732)
		(end 128.5875 -40.749982)
		(width 0.127)
		(layer "In2.Cu")
		(net "ANT4_OUT")
	)
	(segment
		(start 129.667 -26.162254)
		(end 129.667 -29.844746)
		(width 0.127)
		(layer "In2.Cu")
		(net "ANT4_OUT")
	)
	(segment
		(start 95.504 -21.209)
		(end 94.869 -20.574)
		(width 0.127)
		(layer "In2.Cu")
		(net "ANT4_OUT")
	)
	(segment
		(start 104.41178 -24.36622)
		(end 97.01022 -24.36622)
		(width 0.127)
		(layer "In2.Cu")
		(net "ANT4_OUT")
	)
	(segment
		(start 97.01022 -24.36622)
		(end 95.504 -22.86)
		(width 0.127)
		(layer "In2.Cu")
		(net "ANT4_OUT")
	)
	(segment
		(start 74.948542 -32.512)
		(end 31.369 -32.512)
		(width 0.127)
		(layer "In2.Cu")
		(net "ANT4_OUT")
	)
	(segment
		(start 106.045 -19.05)
		(end 105.664 -19.431)
		(width 0.127)
		(layer "In2.Cu")
		(net "ANT4_OUT")
	)
	(segment
		(start 105.664 -19.431)
		(end 105.664 -23.114)
		(width 0.127)
		(layer "In2.Cu")
		(net "ANT4_OUT")
	)
	(segment
		(start 125.747018 -41.9735)
		(end 125.222 -42.498518)
		(width 0.127)
		(layer "In2.Cu")
		(net "ANT4_OUT")
	)
	(segment
		(start 117.911626 -44.758356)
		(end 117.346984 -45.322998)
		(width 0.127)
		(layer "In2.Cu")
		(net "ANT4_OUT")
	)
	(segment
		(start 116.967 -19.304)
		(end 117.221 -19.05)
		(width 0.127)
		(layer "In2.Cu")
		(net "ANT4_OUT")
	)
	(segment
		(start 122.261376 -44.758356)
		(end 117.911626 -44.758356)
		(width 0.127)
		(layer "In2.Cu")
		(net "ANT4_OUT")
	)
	(segment
		(start 125.222 -42.841926)
		(end 123.952 -44.111926)
		(width 0.127)
		(layer "In2.Cu")
		(net "ANT4_OUT")
	)
	(segment
		(start 92.031566 -20.574)
		(end 90.507566 -22.098)
		(width 0.127)
		(layer "In2.Cu")
		(net "ANT4_OUT")
	)
	(segment
		(start 122.554746 -19.05)
		(end 129.667 -26.162254)
		(width 0.127)
		(layer "In2.Cu")
		(net "ANT4_OUT")
	)
	(segment
		(start 129.159 -30.352746)
		(end 129.159 -35.13582)
		(width 0.127)
		(layer "In2.Cu")
		(net "ANT4_OUT")
	)
	(segment
		(start 23.622 -27.305)
		(end 22.987 -26.67)
		(width 0.127)
		(layer "In2.Cu")
		(net "ANT4_OUT")
	)
	(segment
		(start 94.869 -20.574)
		(end 92.031566 -20.574)
		(width 0.127)
		(layer "In2.Cu")
		(net "ANT4_OUT")
	)
	(segment
		(start 123.524518 -45.004736)
		(end 122.507756 -45.004736)
		(width 0.127)
		(layer "In2.Cu")
		(net "ANT4_OUT")
	)
	(segment
		(start 125.222 -42.498518)
		(end 125.222 -42.841926)
		(width 0.127)
		(layer "In2.Cu")
		(net "ANT4_OUT")
	)
	(segment
		(start 129.159 -35.13582)
		(end 128.5875 -35.70732)
		(width 0.127)
		(layer "In2.Cu")
		(net "ANT4_OUT")
	)
	(segment
		(start 123.952 -44.577254)
		(end 123.524518 -45.004736)
		(width 0.127)
		(layer "In2.Cu")
		(net "ANT4_OUT")
	)
	(segment
		(start 116.84 -19.304)
		(end 116.967 -19.304)
		(width 0.127)
		(layer "In2.Cu")
		(net "ANT4_OUT")
	)
	(segment
		(start 87.993982 -22.6695)
		(end 84.791042 -22.6695)
		(width 0.127)
		(layer "In2.Cu")
		(net "ANT4_OUT")
	)
	(segment
		(start 123.952 -44.111926)
		(end 123.952 -44.577254)
		(width 0.127)
		(layer "In2.Cu")
		(net "ANT4_OUT")
	)
	(segment
		(start 84.791042 -22.6695)
		(end 74.948542 -32.512)
		(width 0.127)
		(layer "In2.Cu")
		(net "ANT4_OUT")
	)
	(segment
		(start 117.221 -19.05)
		(end 122.554746 -19.05)
		(width 0.127)
		(layer "In2.Cu")
		(net "ANT4_OUT")
	)
	(segment
		(start 129.667 -29.844746)
		(end 129.159 -30.352746)
		(width 0.127)
		(layer "In2.Cu")
		(net "ANT4_OUT")
	)
	(segment
		(start 90.507566 -22.098)
		(end 88.565482 -22.098)
		(width 0.127)
		(layer "In2.Cu")
		(net "ANT4_OUT")
	)
	(segment
		(start 105.664 -23.114)
		(end 104.41178 -24.36622)
		(width 0.127)
		(layer "In2.Cu")
		(net "ANT4_OUT")
	)
	(segment
		(start 26.162 -27.305)
		(end 23.622 -27.305)
		(width 0.127)
		(layer "In2.Cu")
		(net "ANT4_OUT")
	)
	(segment
		(start 11.3538 -23.215854)
		(end 11.658346 -23.5204)
		(width 0.11938)
		(layer "F.Cu")
		(net "ANT4_IN")
	)
	(segment
		(start 11.3538 -21.7424)
		(end 11.3538 -23.215854)
		(width 0.11938)
		(layer "F.Cu")
		(net "ANT4_IN")
	)
	(segment
		(start 11.684 -20.828)
		(end 11.684 -21.4122)
		(width 0.11938)
		(layer "F.Cu")
		(net "ANT4_IN")
	)
	(segment
		(start 117.84711 -44.823126)
		(end 118.346982 -45.322998)
		(width 0.11938)
		(layer "F.Cu")
		(net "ANT4_IN")
	)
	(segment
		(start 11.658346 -23.5204)
		(end 12.319 -23.5204)
		(width 0.11938)
		(layer "F.Cu")
		(net "ANT4_IN")
	)
	(segment
		(start 11.684 -21.4122)
		(end 11.3538 -21.7424)
		(width 0.11938)
		(layer "F.Cu")
		(net "ANT4_IN")
	)
	(via
		(at 118.346982 -45.322998)
		(size 0.4572)
		(drill 0.2032)
		(layers "F.Cu" "B.Cu")
		(net "ANT4_IN")
	)
	(via
		(at 52.7812 -21.08454)
		(size 0.508)
		(drill 0.254)
		(layers "F.Cu" "B.Cu")
		(net "ANT4_IN")
	)
	(via
		(at 11.684 -20.828)
		(size 0.4572)
		(drill 0.2032)
		(layers "F.Cu" "B.Cu")
		(net "ANT4_IN")
	)
	(segment
		(start 117.8306 -44.806616)
		(end 118.346982 -45.322998)
		(width 0.11938)
		(layer "B.Cu")
		(net "ANT4_IN")
	)
	(segment
		(start 117.8306 -44.577)
		(end 117.8306 -44.806616)
		(width 0.11938)
		(layer "B.Cu")
		(net "ANT4_IN")
	)
	(segment
		(start 95.169736 -15.8369)
		(end 93.036136 -17.9705)
		(width 0.127)
		(layer "In2.Cu")
		(net "ANT4_IN")
	)
	(segment
		(start 118.766082 -45.742098)
		(end 120.904 -45.742098)
		(width 0.127)
		(layer "In2.Cu")
		(net "ANT4_IN")
	)
	(segment
		(start 126.876048 -43.18)
		(end 129.0955 -40.960548)
		(width 0.127)
		(layer "In2.Cu")
		(net "ANT4_IN")
	)
	(segment
		(start 129.0955 -35.917886)
		(end 129.667 -35.346386)
		(width 0.127)
		(layer "In2.Cu")
		(net "ANT4_IN")
	)
	(segment
		(start 121.063258 -45.901356)
		(end 121.965212 -45.901356)
		(width 0.127)
		(layer "In2.Cu")
		(net "ANT4_IN")
	)
	(segment
		(start 128.524 -24.003)
		(end 128.524 -22.352)
		(width 0.127)
		(layer "In2.Cu")
		(net "ANT4_IN")
	)
	(segment
		(start 128.524 -22.352)
		(end 122.46864 -16.29664)
		(width 0.127)
		(layer "In2.Cu")
		(net "ANT4_IN")
	)
	(segment
		(start 122.206004 -45.660564)
		(end 123.630436 -45.660564)
		(width 0.127)
		(layer "In2.Cu")
		(net "ANT4_IN")
	)
	(segment
		(start 124.46 -44.831)
		(end 124.46 -44.322492)
		(width 0.127)
		(layer "In2.Cu")
		(net "ANT4_IN")
	)
	(segment
		(start 74.295 -19.431)
		(end 73.279 -18.415)
		(width 0.127)
		(layer "In2.Cu")
		(net "ANT4_IN")
	)
	(segment
		(start 105.665524 -15.8369)
		(end 95.169736 -15.8369)
		(width 0.127)
		(layer "In2.Cu")
		(net "ANT4_IN")
	)
	(segment
		(start 123.630436 -45.660564)
		(end 124.46 -44.831)
		(width 0.127)
		(layer "In2.Cu")
		(net "ANT4_IN")
	)
	(segment
		(start 130.175 -25.654)
		(end 128.524 -24.003)
		(width 0.127)
		(layer "In2.Cu")
		(net "ANT4_IN")
	)
	(segment
		(start 120.904 -45.742098)
		(end 121.063258 -45.901356)
		(width 0.127)
		(layer "In2.Cu")
		(net "ANT4_IN")
	)
	(segment
		(start 52.25542 -20.55876)
		(end 52.7812 -21.08454)
		(width 0.127)
		(layer "In2.Cu")
		(net "ANT4_IN")
	)
	(segment
		(start 121.965212 -45.901356)
		(end 122.206004 -45.660564)
		(width 0.127)
		(layer "In2.Cu")
		(net "ANT4_IN")
	)
	(segment
		(start 129.667 -30.607)
		(end 130.175 -30.099)
		(width 0.127)
		(layer "In2.Cu")
		(net "ANT4_IN")
	)
	(segment
		(start 78.346554 -18.478246)
		(end 77.3938 -19.431)
		(width 0.127)
		(layer "In2.Cu")
		(net "ANT4_IN")
	)
	(segment
		(start 77.3938 -19.431)
		(end 74.295 -19.431)
		(width 0.127)
		(layer "In2.Cu")
		(net "ANT4_IN")
	)
	(segment
		(start 62.019434 -16.383)
		(end 58.630312 -16.383)
		(width 0.127)
		(layer "In2.Cu")
		(net "ANT4_IN")
	)
	(segment
		(start 129.0955 -40.960548)
		(end 129.0955 -35.917886)
		(width 0.127)
		(layer "In2.Cu")
		(net "ANT4_IN")
	)
	(segment
		(start 73.279 -18.415)
		(end 67.183 -18.415)
		(width 0.127)
		(layer "In2.Cu")
		(net "ANT4_IN")
	)
	(segment
		(start 52.25542 -19.773646)
		(end 52.25542 -20.55876)
		(width 0.127)
		(layer "In2.Cu")
		(net "ANT4_IN")
	)
	(segment
		(start 58.630312 -16.383)
		(end 56.892952 -18.12036)
		(width 0.127)
		(layer "In2.Cu")
		(net "ANT4_IN")
	)
	(segment
		(start 52.613306 -19.41576)
		(end 52.25542 -19.773646)
		(width 0.127)
		(layer "In2.Cu")
		(net "ANT4_IN")
	)
	(segment
		(start 93.036136 -17.9705)
		(end 82.536538 -17.9705)
		(width 0.127)
		(layer "In2.Cu")
		(net "ANT4_IN")
	)
	(segment
		(start 118.346982 -45.322998)
		(end 118.766082 -45.742098)
		(width 0.127)
		(layer "In2.Cu")
		(net "ANT4_IN")
	)
	(segment
		(start 129.667 -35.346386)
		(end 129.667 -30.607)
		(width 0.127)
		(layer "In2.Cu")
		(net "ANT4_IN")
	)
	(segment
		(start 106.125264 -16.29664)
		(end 105.665524 -15.8369)
		(width 0.127)
		(layer "In2.Cu")
		(net "ANT4_IN")
	)
	(segment
		(start 124.46 -44.322492)
		(end 125.602492 -43.18)
		(width 0.127)
		(layer "In2.Cu")
		(net "ANT4_IN")
	)
	(segment
		(start 64.559434 -18.923)
		(end 62.019434 -16.383)
		(width 0.127)
		(layer "In2.Cu")
		(net "ANT4_IN")
	)
	(segment
		(start 125.602492 -43.18)
		(end 126.876048 -43.18)
		(width 0.127)
		(layer "In2.Cu")
		(net "ANT4_IN")
	)
	(segment
		(start 130.175 -30.099)
		(end 130.175 -25.654)
		(width 0.127)
		(layer "In2.Cu")
		(net "ANT4_IN")
	)
	(segment
		(start 53.479954 -19.41576)
		(end 52.613306 -19.41576)
		(width 0.127)
		(layer "In2.Cu")
		(net "ANT4_IN")
	)
	(segment
		(start 66.675 -18.923)
		(end 64.559434 -18.923)
		(width 0.127)
		(layer "In2.Cu")
		(net "ANT4_IN")
	)
	(segment
		(start 67.183 -18.415)
		(end 66.675 -18.923)
		(width 0.127)
		(layer "In2.Cu")
		(net "ANT4_IN")
	)
	(segment
		(start 82.028792 -18.478246)
		(end 78.346554 -18.478246)
		(width 0.127)
		(layer "In2.Cu")
		(net "ANT4_IN")
	)
	(segment
		(start 122.46864 -16.29664)
		(end 106.125264 -16.29664)
		(width 0.127)
		(layer "In2.Cu")
		(net "ANT4_IN")
	)
	(segment
		(start 56.892952 -18.12036)
		(end 54.775354 -18.12036)
		(width 0.127)
		(layer "In2.Cu")
		(net "ANT4_IN")
	)
	(segment
		(start 82.536538 -17.9705)
		(end 82.028792 -18.478246)
		(width 0.127)
		(layer "In2.Cu")
		(net "ANT4_IN")
	)
	(segment
		(start 54.775354 -18.12036)
		(end 53.479954 -19.41576)
		(width 0.127)
		(layer "In2.Cu")
		(net "ANT4_IN")
	)
	(segment
		(start 30.21076 -15.76324)
		(end 31.496 -14.478)
		(width 0.127)
		(layer "In7.Cu")
		(net "ANT4_IN")
	)
	(segment
		(start 12.0142 -20.4978)
		(end 12.0142 -19.223482)
		(width 0.127)
		(layer "In7.Cu")
		(net "ANT4_IN")
	)
	(segment
		(start 12.913106 -18.1229)
		(end 13.114782 -18.1229)
		(width 0.127)
		(layer "In7.Cu")
		(net "ANT4_IN")
	)
	(segment
		(start 38.9636 -15.7226)
		(end 39.5986 -15.7226)
		(width 0.127)
		(layer "In7.Cu")
		(net "ANT4_IN")
	)
	(segment
		(start 12.0142 -19.223482)
		(end 12.578588 -18.659094)
		(width 0.127)
		(layer "In7.Cu")
		(net "ANT4_IN")
	)
	(segment
		(start 22.6187 -15.76324)
		(end 30.21076 -15.76324)
		(width 0.127)
		(layer "In7.Cu")
		(net "ANT4_IN")
	)
	(segment
		(start 36.957254 -14.478)
		(end 37.719254 -15.24)
		(width 0.127)
		(layer "In7.Cu")
		(net "ANT4_IN")
	)
	(segment
		(start 44.2214 -20.3454)
		(end 52.04206 -20.3454)
		(width 0.127)
		(layer "In7.Cu")
		(net "ANT4_IN")
	)
	(segment
		(start 16.251682 -14.986)
		(end 21.84146 -14.986)
		(width 0.127)
		(layer "In7.Cu")
		(net "ANT4_IN")
	)
	(segment
		(start 13.114782 -18.1229)
		(end 16.251682 -14.986)
		(width 0.127)
		(layer "In7.Cu")
		(net "ANT4_IN")
	)
	(segment
		(start 11.684 -20.828)
		(end 12.0142 -20.4978)
		(width 0.127)
		(layer "In7.Cu")
		(net "ANT4_IN")
	)
	(segment
		(start 37.719254 -15.24)
		(end 38.481 -15.24)
		(width 0.127)
		(layer "In7.Cu")
		(net "ANT4_IN")
	)
	(segment
		(start 52.04206 -20.3454)
		(end 52.7812 -21.08454)
		(width 0.127)
		(layer "In7.Cu")
		(net "ANT4_IN")
	)
	(segment
		(start 21.84146 -14.986)
		(end 22.6187 -15.76324)
		(width 0.127)
		(layer "In7.Cu")
		(net "ANT4_IN")
	)
	(segment
		(start 31.496 -14.478)
		(end 36.957254 -14.478)
		(width 0.127)
		(layer "In7.Cu")
		(net "ANT4_IN")
	)
	(segment
		(start 12.578588 -18.659094)
		(end 12.578588 -18.457418)
		(width 0.127)
		(layer "In7.Cu")
		(net "ANT4_IN")
	)
	(segment
		(start 38.481 -15.24)
		(end 38.9636 -15.7226)
		(width 0.127)
		(layer "In7.Cu")
		(net "ANT4_IN")
	)
	(segment
		(start 39.5986 -15.7226)
		(end 44.2214 -20.3454)
		(width 0.127)
		(layer "In7.Cu")
		(net "ANT4_IN")
	)
	(segment
		(start 12.578588 -18.457418)
		(end 12.913106 -18.1229)
		(width 0.127)
		(layer "In7.Cu")
		(net "ANT4_IN")
	)
	(segment
		(start 116.847112 -43.823128)
		(end 117.346984 -43.323256)
		(width 0.11938)
		(layer "F.Cu")
		(net "ANT3_OUT")
	)
	(segment
		(start 13.462 -38.44798)
		(end 13.462 -37.7444)
		(width 0.11938)
		(layer "F.Cu")
		(net "ANT3_OUT")
	)
	(segment
		(start 13.74902 -38.735)
		(end 13.462 -38.44798)
		(width 0.11938)
		(layer "F.Cu")
		(net "ANT3_OUT")
	)
	(via
		(at 15.875 -25.527)
		(size 0.508)
		(drill 0.254)
		(layers "F.Cu" "B.Cu")
		(net "ANT3_OUT")
	)
	(via
		(at 13.74902 -38.735)
		(size 0.508)
		(drill 0.254)
		(layers "F.Cu" "B.Cu")
		(net "ANT3_OUT")
	)
	(via
		(at 117.346984 -43.323256)
		(size 0.4572)
		(drill 0.2032)
		(layers "F.Cu" "B.Cu")
		(net "ANT3_OUT")
	)
	(segment
		(start 94.234 -24.036528)
		(end 94.234 -22.733)
		(width 0.127)
		(layer "In2.Cu")
		(net "ANT3_OUT")
	)
	(segment
		(start 119.50192 -26.3017)
		(end 118.85422 -25.654)
		(width 0.127)
		(layer "In2.Cu")
		(net "ANT3_OUT")
	)
	(segment
		(start 114.3127 -24.9047)
		(end 107.2261 -24.9047)
		(width 0.127)
		(layer "In2.Cu")
		(net "ANT3_OUT")
	)
	(segment
		(start 125.353826 -36.7411)
		(end 126.26848 -35.826446)
		(width 0.127)
		(layer "In2.Cu")
		(net "ANT3_OUT")
	)
	(segment
		(start 16.8021 -26.4541)
		(end 15.875 -25.527)
		(width 0.127)
		(layer "In2.Cu")
		(net "ANT3_OUT")
	)
	(segment
		(start 123.97486 -36.7411)
		(end 125.353826 -36.7411)
		(width 0.127)
		(layer "In2.Cu")
		(net "ANT3_OUT")
	)
	(segment
		(start 125.8697 -32.791654)
		(end 125.8697 -30.624018)
		(width 0.127)
		(layer "In2.Cu")
		(net "ANT3_OUT")
	)
	(segment
		(start 104.3686 -26.0731)
		(end 98.833432 -26.0731)
		(width 0.127)
		(layer "In2.Cu")
		(net "ANT3_OUT")
	)
	(segment
		(start 96.73082 -26.02992)
		(end 95.47987 -26.02992)
		(width 0.127)
		(layer "In2.Cu")
		(net "ANT3_OUT")
	)
	(segment
		(start 75.395074 -33.528)
		(end 30.48 -33.528)
		(width 0.127)
		(layer "In2.Cu")
		(net "ANT3_OUT")
	)
	(segment
		(start 98.345752 -25.58542)
		(end 97.17532 -25.58542)
		(width 0.127)
		(layer "In2.Cu")
		(net "ANT3_OUT")
	)
	(segment
		(start 117.346984 -43.323256)
		(end 117.856 -42.81424)
		(width 0.127)
		(layer "In2.Cu")
		(net "ANT3_OUT")
	)
	(segment
		(start 119.282718 -40.8305)
		(end 120.870472 -40.8305)
		(width 0.127)
		(layer "In2.Cu")
		(net "ANT3_OUT")
	)
	(segment
		(start 97.17532 -25.58542)
		(end 96.73082 -26.02992)
		(width 0.127)
		(layer "In2.Cu")
		(net "ANT3_OUT")
	)
	(segment
		(start 125.8697 -30.624018)
		(end 125.222 -29.976318)
		(width 0.127)
		(layer "In2.Cu")
		(net "ANT3_OUT")
	)
	(segment
		(start 126.26848 -35.826446)
		(end 126.26848 -33.190434)
		(width 0.127)
		(layer "In2.Cu")
		(net "ANT3_OUT")
	)
	(segment
		(start 126.26848 -33.190434)
		(end 125.8697 -32.791654)
		(width 0.127)
		(layer "In2.Cu")
		(net "ANT3_OUT")
	)
	(segment
		(start 125.222 -28.1813)
		(end 123.3424 -26.3017)
		(width 0.127)
		(layer "In2.Cu")
		(net "ANT3_OUT")
	)
	(segment
		(start 115.062 -25.654)
		(end 114.3127 -24.9047)
		(width 0.127)
		(layer "In2.Cu")
		(net "ANT3_OUT")
	)
	(segment
		(start 118.85422 -25.654)
		(end 115.062 -25.654)
		(width 0.127)
		(layer "In2.Cu")
		(net "ANT3_OUT")
	)
	(segment
		(start 122.03938 -38.67658)
		(end 123.97486 -36.7411)
		(width 0.127)
		(layer "In2.Cu")
		(net "ANT3_OUT")
	)
	(segment
		(start 91.500198 -22.5425)
		(end 90.928698 -23.114)
		(width 0.127)
		(layer "In2.Cu")
		(net "ANT3_OUT")
	)
	(segment
		(start 118.872 -41.241218)
		(end 119.282718 -40.8305)
		(width 0.127)
		(layer "In2.Cu")
		(net "ANT3_OUT")
	)
	(segment
		(start 22.098 -28.702)
		(end 19.8501 -26.4541)
		(width 0.127)
		(layer "In2.Cu")
		(net "ANT3_OUT")
	)
	(segment
		(start 94.234 -22.733)
		(end 94.0435 -22.5425)
		(width 0.127)
		(layer "In2.Cu")
		(net "ANT3_OUT")
	)
	(segment
		(start 120.870472 -40.8305)
		(end 122.03938 -39.661592)
		(width 0.127)
		(layer "In2.Cu")
		(net "ANT3_OUT")
	)
	(segment
		(start 122.03938 -39.661592)
		(end 122.03938 -38.67658)
		(width 0.127)
		(layer "In2.Cu")
		(net "ANT3_OUT")
	)
	(segment
		(start 125.222 -29.976318)
		(end 125.222 -28.1813)
		(width 0.127)
		(layer "In2.Cu")
		(net "ANT3_OUT")
	)
	(segment
		(start 117.856 -42.81424)
		(end 117.856 -42.137838)
		(width 0.127)
		(layer "In2.Cu")
		(net "ANT3_OUT")
	)
	(segment
		(start 95.47987 -26.02992)
		(end 95.145352 -25.695402)
		(width 0.127)
		(layer "In2.Cu")
		(net "ANT3_OUT")
	)
	(segment
		(start 104.9528 -25.4889)
		(end 104.3686 -26.0731)
		(width 0.127)
		(layer "In2.Cu")
		(net "ANT3_OUT")
	)
	(segment
		(start 30.48 -33.528)
		(end 25.654 -28.702)
		(width 0.127)
		(layer "In2.Cu")
		(net "ANT3_OUT")
	)
	(segment
		(start 95.145352 -24.94788)
		(end 94.234 -24.036528)
		(width 0.127)
		(layer "In2.Cu")
		(net "ANT3_OUT")
	)
	(segment
		(start 19.8501 -26.4541)
		(end 16.8021 -26.4541)
		(width 0.127)
		(layer "In2.Cu")
		(net "ANT3_OUT")
	)
	(segment
		(start 88.415114 -23.6855)
		(end 85.237574 -23.6855)
		(width 0.127)
		(layer "In2.Cu")
		(net "ANT3_OUT")
	)
	(segment
		(start 118.210838 -41.783)
		(end 118.480078 -41.783)
		(width 0.127)
		(layer "In2.Cu")
		(net "ANT3_OUT")
	)
	(segment
		(start 88.986614 -23.114)
		(end 88.415114 -23.6855)
		(width 0.127)
		(layer "In2.Cu")
		(net "ANT3_OUT")
	)
	(segment
		(start 85.237574 -23.6855)
		(end 75.395074 -33.528)
		(width 0.127)
		(layer "In2.Cu")
		(net "ANT3_OUT")
	)
	(segment
		(start 106.6419 -25.4889)
		(end 104.9528 -25.4889)
		(width 0.127)
		(layer "In2.Cu")
		(net "ANT3_OUT")
	)
	(segment
		(start 117.856 -42.137838)
		(end 118.210838 -41.783)
		(width 0.127)
		(layer "In2.Cu")
		(net "ANT3_OUT")
	)
	(segment
		(start 118.872 -41.391078)
		(end 118.872 -41.241218)
		(width 0.127)
		(layer "In2.Cu")
		(net "ANT3_OUT")
	)
	(segment
		(start 118.480078 -41.783)
		(end 118.872 -41.391078)
		(width 0.127)
		(layer "In2.Cu")
		(net "ANT3_OUT")
	)
	(segment
		(start 90.928698 -23.114)
		(end 88.986614 -23.114)
		(width 0.127)
		(layer "In2.Cu")
		(net "ANT3_OUT")
	)
	(segment
		(start 123.3424 -26.3017)
		(end 119.50192 -26.3017)
		(width 0.127)
		(layer "In2.Cu")
		(net "ANT3_OUT")
	)
	(segment
		(start 98.833432 -26.0731)
		(end 98.345752 -25.58542)
		(width 0.127)
		(layer "In2.Cu")
		(net "ANT3_OUT")
	)
	(segment
		(start 95.145352 -25.695402)
		(end 95.145352 -24.94788)
		(width 0.127)
		(layer "In2.Cu")
		(net "ANT3_OUT")
	)
	(segment
		(start 107.2261 -24.9047)
		(end 106.6419 -25.4889)
		(width 0.127)
		(layer "In2.Cu")
		(net "ANT3_OUT")
	)
	(segment
		(start 25.654 -28.702)
		(end 22.098 -28.702)
		(width 0.127)
		(layer "In2.Cu")
		(net "ANT3_OUT")
	)
	(segment
		(start 94.0435 -22.5425)
		(end 91.500198 -22.5425)
		(width 0.127)
		(layer "In2.Cu")
		(net "ANT3_OUT")
	)
	(segment
		(start 14.22146 -32.240982)
		(end 14.097 -32.365442)
		(width 0.127)
		(layer "In7.Cu")
		(net "ANT3_OUT")
	)
	(segment
		(start 14.097 -33.782)
		(end 12.827 -35.052)
		(width 0.127)
		(layer "In7.Cu")
		(net "ANT3_OUT")
	)
	(segment
		(start 14.22146 -30.22854)
		(end 14.22146 -32.240982)
		(width 0.127)
		(layer "In7.Cu")
		(net "ANT3_OUT")
	)
	(segment
		(start 12.827 -37.81298)
		(end 13.74902 -38.735)
		(width 0.127)
		(layer "In7.Cu")
		(net "ANT3_OUT")
	)
	(segment
		(start 16.383 -26.035)
		(end 16.383 -26.797254)
		(width 0.127)
		(layer "In7.Cu")
		(net "ANT3_OUT")
	)
	(segment
		(start 15.875 -25.527)
		(end 16.383 -26.035)
		(width 0.127)
		(layer "In7.Cu")
		(net "ANT3_OUT")
	)
	(segment
		(start 15.367 -27.813254)
		(end 15.367 -29.083)
		(width 0.127)
		(layer "In7.Cu")
		(net "ANT3_OUT")
	)
	(segment
		(start 15.367 -29.083)
		(end 14.22146 -30.22854)
		(width 0.127)
		(layer "In7.Cu")
		(net "ANT3_OUT")
	)
	(segment
		(start 12.827 -35.052)
		(end 12.827 -37.81298)
		(width 0.127)
		(layer "In7.Cu")
		(net "ANT3_OUT")
	)
	(segment
		(start 14.097 -32.365442)
		(end 14.097 -33.782)
		(width 0.127)
		(layer "In7.Cu")
		(net "ANT3_OUT")
	)
	(segment
		(start 16.383 -26.797254)
		(end 15.367 -27.813254)
		(width 0.127)
		(layer "In7.Cu")
		(net "ANT3_OUT")
	)
	(segment
		(start 12.192 -32.512)
		(end 12.065 -32.512)
		(width 0.11938)
		(layer "F.Cu")
		(net "ANT3_IN")
	)
	(segment
		(start 12.065 -32.512)
		(end 11.085576 -33.491424)
		(width 0.11938)
		(layer "F.Cu")
		(net "ANT3_IN")
	)
	(segment
		(start 11.085576 -37.374576)
		(end 11.4554 -37.7444)
		(width 0.11938)
		(layer "F.Cu")
		(net "ANT3_IN")
	)
	(segment
		(start 12.271248 -32.591248)
		(end 12.192 -32.512)
		(width 0.11938)
		(layer "F.Cu")
		(net "ANT3_IN")
	)
	(segment
		(start 12.29106 -32.591248)
		(end 12.271248 -32.591248)
		(width 0.11938)
		(layer "F.Cu")
		(net "ANT3_IN")
	)
	(segment
		(start 117.84711 -43.823128)
		(end 118.346982 -43.323256)
		(width 0.11938)
		(layer "F.Cu")
		(net "ANT3_IN")
	)
	(segment
		(start 11.085576 -33.491424)
		(end 11.085576 -37.374576)
		(width 0.11938)
		(layer "F.Cu")
		(net "ANT3_IN")
	)
	(segment
		(start 11.4554 -37.7444)
		(end 12.192 -37.7444)
		(width 0.11938)
		(layer "F.Cu")
		(net "ANT3_IN")
	)
	(via
		(at 12.29106 -32.591248)
		(size 0.508)
		(drill 0.254)
		(layers "F.Cu" "B.Cu")
		(net "ANT3_IN")
	)
	(via
		(at 23.749 -28.067)
		(size 0.508)
		(drill 0.254)
		(layers "F.Cu" "B.Cu")
		(net "ANT3_IN")
	)
	(via
		(at 118.346982 -43.323256)
		(size 0.4572)
		(drill 0.2032)
		(layers "F.Cu" "B.Cu")
		(net "ANT3_IN")
	)
	(segment
		(start 12.47775 -31.08325)
		(end 12.319 -31.242)
		(width 0.11938)
		(layer "B.Cu")
		(net "ANT3_IN")
	)
	(segment
		(start 19.334734 -31.97987)
		(end 16.459454 -31.97987)
		(width 0.11938)
		(layer "B.Cu")
		(net "ANT3_IN")
	)
	(segment
		(start 16.459454 -31.97987)
		(end 16.034004 -31.55442)
		(width 0.11938)
		(layer "B.Cu")
		(net "ANT3_IN")
	)
	(segment
		(start 23.749 -28.067)
		(end 22.987 -28.829)
		(width 0.11938)
		(layer "B.Cu")
		(net "ANT3_IN")
	)
	(segment
		(start 16.034004 -31.55442)
		(end 14.79042 -31.55442)
		(width 0.11938)
		(layer "B.Cu")
		(net "ANT3_IN")
	)
	(segment
		(start 12.319 -31.242)
		(end 12.319 -32.563308)
		(width 0.11938)
		(layer "B.Cu")
		(net "ANT3_IN")
	)
	(segment
		(start 22.987 -30.607)
		(end 22.53869 -31.05531)
		(width 0.11938)
		(layer "B.Cu")
		(net "ANT3_IN")
	)
	(segment
		(start 22.53869 -31.05531)
		(end 20.259294 -31.05531)
		(width 0.11938)
		(layer "B.Cu")
		(net "ANT3_IN")
	)
	(segment
		(start 14.31925 -31.08325)
		(end 12.47775 -31.08325)
		(width 0.11938)
		(layer "B.Cu")
		(net "ANT3_IN")
	)
	(segment
		(start 22.987 -28.829)
		(end 22.987 -30.607)
		(width 0.11938)
		(layer "B.Cu")
		(net "ANT3_IN")
	)
	(segment
		(start 12.319 -32.563308)
		(end 12.29106 -32.591248)
		(width 0.11938)
		(layer "B.Cu")
		(net "ANT3_IN")
	)
	(segment
		(start 20.259294 -31.05531)
		(end 19.334734 -31.97987)
		(width 0.11938)
		(layer "B.Cu")
		(net "ANT3_IN")
	)
	(segment
		(start 118.846854 -42.823384)
		(end 118.346982 -43.323256)
		(width 0.11938)
		(layer "B.Cu")
		(net "ANT3_IN")
	)
	(segment
		(start 118.846854 -42.82313)
		(end 118.846854 -42.823384)
		(width 0.11938)
		(layer "B.Cu")
		(net "ANT3_IN")
	)
	(segment
		(start 14.79042 -31.55442)
		(end 14.31925 -31.08325)
		(width 0.11938)
		(layer "B.Cu")
		(net "ANT3_IN")
	)
	(segment
		(start 125.61316 -37.200586)
		(end 126.77648 -36.037266)
		(width 0.127)
		(layer "In2.Cu")
		(net "ANT3_IN")
	)
	(segment
		(start 91.289632 -22.0345)
		(end 90.718132 -22.606)
		(width 0.127)
		(layer "In2.Cu")
		(net "ANT3_IN")
	)
	(segment
		(start 126.3777 -32.581088)
		(end 126.3777 -30.413452)
		(width 0.127)
		(layer "In2.Cu")
		(net "ANT3_IN")
	)
	(segment
		(start 126.77648 -36.037266)
		(end 126.77648 -32.979868)
		(width 0.127)
		(layer "In2.Cu")
		(net "ANT3_IN")
	)
	(segment
		(start 118.872 -42.798238)
		(end 118.872 -42.031158)
		(width 0.127)
		(layer "In2.Cu")
		(net "ANT3_IN")
	)
	(segment
		(start 114.6937 -24.3967)
		(end 107.01528 -24.3967)
		(width 0.127)
		(layer "In2.Cu")
		(net "ANT3_IN")
	)
	(segment
		(start 119.253 -24.892)
		(end 115.189 -24.892)
		(width 0.127)
		(layer "In2.Cu")
		(net "ANT3_IN")
	)
	(segment
		(start 118.999 -41.904158)
		(end 120.517158 -41.904158)
		(width 0.127)
		(layer "In2.Cu")
		(net "ANT3_IN")
	)
	(segment
		(start 120.517158 -41.904158)
		(end 120.65 -42.037)
		(width 0.127)
		(layer "In2.Cu")
		(net "ANT3_IN")
	)
	(segment
		(start 75.184508 -33.02)
		(end 30.988 -33.02)
		(width 0.127)
		(layer "In2.Cu")
		(net "ANT3_IN")
	)
	(segment
		(start 123.552966 -25.7937)
		(end 120.1547 -25.7937)
		(width 0.127)
		(layer "In2.Cu")
		(net "ANT3_IN")
	)
	(segment
		(start 125.1585 -38.4175)
		(end 125.61316 -37.96284)
		(width 0.127)
		(layer "In2.Cu")
		(net "ANT3_IN")
	)
	(segment
		(start 106.53776 -24.87422)
		(end 96.799654 -24.87422)
		(width 0.127)
		(layer "In2.Cu")
		(net "ANT3_IN")
	)
	(segment
		(start 124.0155 -39.5605)
		(end 124.0155 -38.5445)
		(width 0.127)
		(layer "In2.Cu")
		(net "ANT3_IN")
	)
	(segment
		(start 124.0155 -38.5445)
		(end 124.1425 -38.4175)
		(width 0.127)
		(layer "In2.Cu")
		(net "ANT3_IN")
	)
	(segment
		(start 88.204548 -23.1775)
		(end 85.027008 -23.1775)
		(width 0.127)
		(layer "In2.Cu")
		(net "ANT3_IN")
	)
	(segment
		(start 94.869 -22.0345)
		(end 91.289632 -22.0345)
		(width 0.127)
		(layer "In2.Cu")
		(net "ANT3_IN")
	)
	(segment
		(start 85.027008 -23.1775)
		(end 75.184508 -33.02)
		(width 0.127)
		(layer "In2.Cu")
		(net "ANT3_IN")
	)
	(segment
		(start 125.73 -29.765752)
		(end 125.73 -27.970734)
		(width 0.127)
		(layer "In2.Cu")
		(net "ANT3_IN")
	)
	(segment
		(start 115.189 -24.892)
		(end 114.6937 -24.3967)
		(width 0.127)
		(layer "In2.Cu")
		(net "ANT3_IN")
	)
	(segment
		(start 120.65 -42.037)
		(end 121.539 -42.037)
		(width 0.127)
		(layer "In2.Cu")
		(net "ANT3_IN")
	)
	(segment
		(start 124.1425 -38.4175)
		(end 125.1585 -38.4175)
		(width 0.127)
		(layer "In2.Cu")
		(net "ANT3_IN")
	)
	(segment
		(start 26.035 -28.067)
		(end 23.749 -28.067)
		(width 0.127)
		(layer "In2.Cu")
		(net "ANT3_IN")
	)
	(segment
		(start 30.988 -33.02)
		(end 26.035 -28.067)
		(width 0.127)
		(layer "In2.Cu")
		(net "ANT3_IN")
	)
	(segment
		(start 118.872 -42.031158)
		(end 118.999 -41.904158)
		(width 0.127)
		(layer "In2.Cu")
		(net "ANT3_IN")
	)
	(segment
		(start 126.77648 -32.979868)
		(end 126.3777 -32.581088)
		(width 0.127)
		(layer "In2.Cu")
		(net "ANT3_IN")
	)
	(segment
		(start 107.01528 -24.3967)
		(end 106.53776 -24.87422)
		(width 0.127)
		(layer "In2.Cu")
		(net "ANT3_IN")
	)
	(segment
		(start 120.1547 -25.7937)
		(end 119.253 -24.892)
		(width 0.127)
		(layer "In2.Cu")
		(net "ANT3_IN")
	)
	(segment
		(start 118.346982 -43.323256)
		(end 118.872 -42.798238)
		(width 0.127)
		(layer "In2.Cu")
		(net "ANT3_IN")
	)
	(segment
		(start 125.61316 -37.96284)
		(end 125.61316 -37.200586)
		(width 0.127)
		(layer "In2.Cu")
		(net "ANT3_IN")
	)
	(segment
		(start 88.776048 -22.606)
		(end 88.204548 -23.1775)
		(width 0.127)
		(layer "In2.Cu")
		(net "ANT3_IN")
	)
	(segment
		(start 126.3777 -30.413452)
		(end 125.73 -29.765752)
		(width 0.127)
		(layer "In2.Cu")
		(net "ANT3_IN")
	)
	(segment
		(start 94.996 -23.070566)
		(end 94.996 -22.1615)
		(width 0.127)
		(layer "In2.Cu")
		(net "ANT3_IN")
	)
	(segment
		(start 125.73 -27.970734)
		(end 123.552966 -25.7937)
		(width 0.127)
		(layer "In2.Cu")
		(net "ANT3_IN")
	)
	(segment
		(start 90.718132 -22.606)
		(end 88.776048 -22.606)
		(width 0.127)
		(layer "In2.Cu")
		(net "ANT3_IN")
	)
	(segment
		(start 121.539 -42.037)
		(end 124.0155 -39.5605)
		(width 0.127)
		(layer "In2.Cu")
		(net "ANT3_IN")
	)
	(segment
		(start 94.996 -22.1615)
		(end 94.869 -22.0345)
		(width 0.127)
		(layer "In2.Cu")
		(net "ANT3_IN")
	)
	(segment
		(start 96.799654 -24.87422)
		(end 94.996 -23.070566)
		(width 0.127)
		(layer "In2.Cu")
		(net "ANT3_IN")
	)
	(segment
		(start 25.51684 -16.60144)
		(end 26.3144 -17.399)
		(width 0.11938)
		(layer "F.Cu")
		(net "PRI_EEPROM_SDA")
	)
	(segment
		(start 29.79674 -16.7132)
		(end 29.81198 -16.72844)
		(width 0.11938)
		(layer "F.Cu")
		(net "PRI_EEPROM_SDA")
	)
	(segment
		(start 26.3144 -17.399)
		(end 28.1686 -17.399)
		(width 0.11938)
		(layer "F.Cu")
		(net "PRI_EEPROM_SDA")
	)
	(segment
		(start 28.8544 -16.7132)
		(end 29.79674 -16.7132)
		(width 0.11938)
		(layer "F.Cu")
		(net "PRI_EEPROM_SDA")
	)
	(segment
		(start 28.6512 -16.9164)
		(end 28.8544 -16.7132)
		(width 0.11938)
		(layer "F.Cu")
		(net "PRI_EEPROM_SDA")
	)
	(segment
		(start 28.1686 -17.399)
		(end 28.6512 -16.9164)
		(width 0.11938)
		(layer "F.Cu")
		(net "PRI_EEPROM_SDA")
	)
	(segment
		(start 24.3205 -16.60144)
		(end 25.51684 -16.60144)
		(width 0.11938)
		(layer "F.Cu")
		(net "PRI_EEPROM_SDA")
	)
	(via
		(at 28.6512 -16.9164)
		(size 0.4572)
		(drill 0.2032)
		(layers "F.Cu" "B.Cu")
		(net "PRI_EEPROM_SDA")
	)
	(segment
		(start 153.049986 -108.599732)
		(end 151.793702 -108.599732)
		(width 0.11938)
		(layer "F.Cu")
		(net "UNNAMED_14_OPTICAL_I138_A")
	)
	(via
		(at 151.793702 -108.599732)
		(size 0.508)
		(drill 0.254)
		(layers "F.Cu" "B.Cu")
		(net "UNNAMED_14_OPTICAL_I138_A")
	)
	(segment
		(start 152.164034 -108.2294)
		(end 153.0858 -108.2294)
		(width 0.11938)
		(layer "B.Cu")
		(net "UNNAMED_14_OPTICAL_I138_A")
	)
	(segment
		(start 151.793702 -108.599732)
		(end 152.164034 -108.2294)
		(width 0.11938)
		(layer "B.Cu")
		(net "UNNAMED_14_OPTICAL_I138_A")
	)
	(segment
		(start 14.732 -22.4536)
		(end 14.732 -21.971)
		(width 0.11938)
		(layer "F.Cu")
		(net "SMA4_SIG_OUT_BF_EN_N")
	)
	(segment
		(start 15.7734 -22.4536)
		(end 14.732 -22.4536)
		(width 0.11938)
		(layer "F.Cu")
		(net "SMA4_SIG_OUT_BF_EN_N")
	)
	(segment
		(start 16.129 -22.098)
		(end 15.7734 -22.4536)
		(width 0.11938)
		(layer "F.Cu")
		(net "SMA4_SIG_OUT_BF_EN_N")
	)
	(segment
		(start 15.113 -21.59)
		(end 15.113 -20.828)
		(width 0.11938)
		(layer "F.Cu")
		(net "SMA4_SIG_OUT_BF_EN_N")
	)
	(segment
		(start 105.847134 -46.823122)
		(end 105.347262 -47.322994)
		(width 0.11938)
		(layer "F.Cu")
		(net "SMA4_SIG_OUT_BF_EN_N")
	)
	(segment
		(start 16.129 -21.463)
		(end 16.129 -22.098)
		(width 0.11938)
		(layer "F.Cu")
		(net "SMA4_SIG_OUT_BF_EN_N")
	)
	(segment
		(start 15.113 -20.828)
		(end 14.649704 -20.364704)
		(width 0.11938)
		(layer "F.Cu")
		(net "SMA4_SIG_OUT_BF_EN_N")
	)
	(segment
		(start 14.732 -21.971)
		(end 15.113 -21.59)
		(width 0.11938)
		(layer "F.Cu")
		(net "SMA4_SIG_OUT_BF_EN_N")
	)
	(segment
		(start 14.649704 -20.364704)
		(end 14.649704 -19.790156)
		(width 0.11938)
		(layer "F.Cu")
		(net "SMA4_SIG_OUT_BF_EN_N")
	)
	(via
		(at 24.003 -41.402)
		(size 0.508)
		(drill 0.254)
		(layers "F.Cu" "B.Cu")
		(net "SMA4_SIG_OUT_BF_EN_N")
	)
	(via
		(at 105.347262 -47.322994)
		(size 0.4572)
		(drill 0.2032)
		(layers "F.Cu" "B.Cu")
		(net "SMA4_SIG_OUT_BF_EN_N")
	)
	(segment
		(start 26.67 -41.548304)
		(end 25.359614 -42.85869)
		(width 0.11938)
		(layer "B.Cu")
		(net "SMA4_SIG_OUT_BF_EN_N")
	)
	(segment
		(start 26.67 -34.183066)
		(end 26.67 -41.548304)
		(width 0.11938)
		(layer "B.Cu")
		(net "SMA4_SIG_OUT_BF_EN_N")
	)
	(segment
		(start 24.678386 -42.85869)
		(end 24.003 -42.183304)
		(width 0.11938)
		(layer "B.Cu")
		(net "SMA4_SIG_OUT_BF_EN_N")
	)
	(segment
		(start 16.637 -24.638)
		(end 16.637 -26.035)
		(width 0.11938)
		(layer "B.Cu")
		(net "SMA4_SIG_OUT_BF_EN_N")
	)
	(segment
		(start 24.824182 -26.347928)
		(end 24.824182 -32.337248)
		(width 0.11938)
		(layer "B.Cu")
		(net "SMA4_SIG_OUT_BF_EN_N")
	)
	(segment
		(start 24.824182 -32.337248)
		(end 26.67 -34.183066)
		(width 0.11938)
		(layer "B.Cu")
		(net "SMA4_SIG_OUT_BF_EN_N")
	)
	(segment
		(start 25.359614 -42.85869)
		(end 24.678386 -42.85869)
		(width 0.11938)
		(layer "B.Cu")
		(net "SMA4_SIG_OUT_BF_EN_N")
	)
	(segment
		(start 22.791928 -25.975818)
		(end 24.452072 -25.975818)
		(width 0.11938)
		(layer "B.Cu")
		(net "SMA4_SIG_OUT_BF_EN_N")
	)
	(segment
		(start 15.4305 -23.4315)
		(end 16.637 -24.638)
		(width 0.11938)
		(layer "B.Cu")
		(net "SMA4_SIG_OUT_BF_EN_N")
	)
	(segment
		(start 18.101818 -27.499818)
		(end 21.267928 -27.499818)
		(width 0.11938)
		(layer "B.Cu")
		(net "SMA4_SIG_OUT_BF_EN_N")
	)
	(segment
		(start 21.267928 -27.499818)
		(end 22.791928 -25.975818)
		(width 0.11938)
		(layer "B.Cu")
		(net "SMA4_SIG_OUT_BF_EN_N")
	)
	(segment
		(start 16.637 -26.035)
		(end 18.101818 -27.499818)
		(width 0.11938)
		(layer "B.Cu")
		(net "SMA4_SIG_OUT_BF_EN_N")
	)
	(segment
		(start 16.129 -21.463)
		(end 15.4305 -22.1615)
		(width 0.11938)
		(layer "B.Cu")
		(net "SMA4_SIG_OUT_BF_EN_N")
	)
	(segment
		(start 15.4305 -22.1615)
		(end 15.4305 -23.4315)
		(width 0.11938)
		(layer "B.Cu")
		(net "SMA4_SIG_OUT_BF_EN_N")
	)
	(segment
		(start 24.452072 -25.975818)
		(end 24.824182 -26.347928)
		(width 0.11938)
		(layer "B.Cu")
		(net "SMA4_SIG_OUT_BF_EN_N")
	)
	(segment
		(start 24.003 -42.183304)
		(end 24.003 -41.402)
		(width 0.11938)
		(layer "B.Cu")
		(net "SMA4_SIG_OUT_BF_EN_N")
	)
	(segment
		(start 103.464106 -47.932594)
		(end 100.093526 -47.932594)
		(width 0.1016)
		(layer "In7.Cu")
		(net "SMA4_SIG_OUT_BF_EN_N")
	)
	(segment
		(start 104.890316 -47.77994)
		(end 103.61676 -47.77994)
		(width 0.1016)
		(layer "In7.Cu")
		(net "SMA4_SIG_OUT_BF_EN_N")
	)
	(segment
		(start 76.6445 -53.1495)
		(end 76.2 -53.594)
		(width 0.127)
		(layer "In7.Cu")
		(net "SMA4_SIG_OUT_BF_EN_N")
	)
	(segment
		(start 93.941646 -52.148486)
		(end 91.547442 -52.148486)
		(width 0.127)
		(layer "In7.Cu")
		(net "SMA4_SIG_OUT_BF_EN_N")
	)
	(segment
		(start 81.628488 -53.1495)
		(end 76.6445 -53.1495)
		(width 0.127)
		(layer "In7.Cu")
		(net "SMA4_SIG_OUT_BF_EN_N")
	)
	(segment
		(start 26.926032 -41.526968)
		(end 25.781 -42.672)
		(width 0.127)
		(layer "In7.Cu")
		(net "SMA4_SIG_OUT_BF_EN_N")
	)
	(segment
		(start 98.806 -48.514)
		(end 97.576132 -48.514)
		(width 0.127)
		(layer "In7.Cu")
		(net "SMA4_SIG_OUT_BF_EN_N")
	)
	(segment
		(start 24.765 -42.672)
		(end 24.003 -41.91)
		(width 0.127)
		(layer "In7.Cu")
		(net "SMA4_SIG_OUT_BF_EN_N")
	)
	(segment
		(start 25.781 -42.672)
		(end 24.765 -42.672)
		(width 0.127)
		(layer "In7.Cu")
		(net "SMA4_SIG_OUT_BF_EN_N")
	)
	(segment
		(start 51.283616 -41.526968)
		(end 26.926032 -41.526968)
		(width 0.127)
		(layer "In7.Cu")
		(net "SMA4_SIG_OUT_BF_EN_N")
	)
	(segment
		(start 65.786 -53.594)
		(end 65.3415 -53.1495)
		(width 0.127)
		(layer "In7.Cu")
		(net "SMA4_SIG_OUT_BF_EN_N")
	)
	(segment
		(start 105.347262 -47.322994)
		(end 104.890316 -47.77994)
		(width 0.1016)
		(layer "In7.Cu")
		(net "SMA4_SIG_OUT_BF_EN_N")
	)
	(segment
		(start 97.576132 -48.514)
		(end 93.941646 -52.148486)
		(width 0.127)
		(layer "In7.Cu")
		(net "SMA4_SIG_OUT_BF_EN_N")
	)
	(segment
		(start 91.547442 -52.148486)
		(end 90.902028 -52.7939)
		(width 0.127)
		(layer "In7.Cu")
		(net "SMA4_SIG_OUT_BF_EN_N")
	)
	(segment
		(start 24.003 -41.91)
		(end 24.003 -41.402)
		(width 0.127)
		(layer "In7.Cu")
		(net "SMA4_SIG_OUT_BF_EN_N")
	)
	(segment
		(start 76.2 -53.594)
		(end 65.786 -53.594)
		(width 0.127)
		(layer "In7.Cu")
		(net "SMA4_SIG_OUT_BF_EN_N")
	)
	(segment
		(start 100.093526 -47.932594)
		(end 99.51212 -48.514)
		(width 0.1016)
		(layer "In7.Cu")
		(net "SMA4_SIG_OUT_BF_EN_N")
	)
	(segment
		(start 62.906148 -53.1495)
		(end 51.283616 -41.526968)
		(width 0.127)
		(layer "In7.Cu")
		(net "SMA4_SIG_OUT_BF_EN_N")
	)
	(segment
		(start 90.902028 -52.7939)
		(end 81.984088 -52.7939)
		(width 0.127)
		(layer "In7.Cu")
		(net "SMA4_SIG_OUT_BF_EN_N")
	)
	(segment
		(start 103.61676 -47.77994)
		(end 103.464106 -47.932594)
		(width 0.1016)
		(layer "In7.Cu")
		(net "SMA4_SIG_OUT_BF_EN_N")
	)
	(segment
		(start 99.51212 -48.514)
		(end 98.806 -48.514)
		(width 0.1016)
		(layer "In7.Cu")
		(net "SMA4_SIG_OUT_BF_EN_N")
	)
	(segment
		(start 65.3415 -53.1495)
		(end 62.906148 -53.1495)
		(width 0.127)
		(layer "In7.Cu")
		(net "SMA4_SIG_OUT_BF_EN_N")
	)
	(segment
		(start 81.984088 -52.7939)
		(end 81.628488 -53.1495)
		(width 0.127)
		(layer "In7.Cu")
		(net "SMA4_SIG_OUT_BF_EN_N")
	)
	(segment
		(start 14.097 -15.24)
		(end 14.149832 -15.292832)
		(width 0.11938)
		(layer "F.Cu")
		(net "SMA4_SIG_IN_BF_EN_N")
	)
	(segment
		(start 106.847132 -46.823122)
		(end 106.34726 -47.322994)
		(width 0.11938)
		(layer "F.Cu")
		(net "SMA4_SIG_IN_BF_EN_N")
	)
	(segment
		(start 14.149832 -15.292832)
		(end 14.149832 -16.409924)
		(width 0.11938)
		(layer "F.Cu")
		(net "SMA4_SIG_IN_BF_EN_N")
	)
	(segment
		(start 14.097 -14.986)
		(end 14.097 -15.24)
		(width 0.11938)
		(layer "F.Cu")
		(net "SMA4_SIG_IN_BF_EN_N")
	)
	(via
		(at 106.34726 -47.322994)
		(size 0.4572)
		(drill 0.2032)
		(layers "F.Cu" "B.Cu")
		(net "SMA4_SIG_IN_BF_EN_N")
	)
	(via
		(at 14.097 -14.986)
		(size 0.508)
		(drill 0.254)
		(layers "F.Cu" "B.Cu")
		(net "SMA4_SIG_IN_BF_EN_N")
	)
	(via
		(at 24.765 -43.688)
		(size 0.508)
		(drill 0.254)
		(layers "F.Cu" "B.Cu")
		(net "SMA4_SIG_IN_BF_EN_N")
	)
	(segment
		(start 16.129 -18.0086)
		(end 16.129 -20.066)
		(width 0.11938)
		(layer "B.Cu")
		(net "SMA4_SIG_IN_BF_EN_N")
	)
	(segment
		(start 27.04338 -41.7068)
		(end 25.06218 -43.688)
		(width 0.11938)
		(layer "B.Cu")
		(net "SMA4_SIG_IN_BF_EN_N")
	)
	(segment
		(start 16.3576 -17.78)
		(end 16.129 -18.0086)
		(width 0.11938)
		(layer "B.Cu")
		(net "SMA4_SIG_IN_BF_EN_N")
	)
	(segment
		(start 24.638 -25.527)
		(end 25.273 -26.162)
		(width 0.11938)
		(layer "B.Cu")
		(net "SMA4_SIG_IN_BF_EN_N")
	)
	(segment
		(start 14.097 -14.986)
		(end 14.097 -15.24)
		(width 0.11938)
		(layer "B.Cu")
		(net "SMA4_SIG_IN_BF_EN_N")
	)
	(segment
		(start 17.018 -24.384)
		(end 17.018 -25.781)
		(width 0.11938)
		(layer "B.Cu")
		(net "SMA4_SIG_IN_BF_EN_N")
	)
	(segment
		(start 17.018 -25.781)
		(end 18.25879 -27.02179)
		(width 0.11938)
		(layer "B.Cu")
		(net "SMA4_SIG_IN_BF_EN_N")
	)
	(segment
		(start 17.018 -21.971)
		(end 16.129 -22.86)
		(width 0.11938)
		(layer "B.Cu")
		(net "SMA4_SIG_IN_BF_EN_N")
	)
	(segment
		(start 14.149832 -15.292832)
		(end 14.149832 -15.297912)
		(width 0.11938)
		(layer "B.Cu")
		(net "SMA4_SIG_IN_BF_EN_N")
	)
	(segment
		(start 16.129 -22.86)
		(end 16.129 -23.495)
		(width 0.11938)
		(layer "B.Cu")
		(net "SMA4_SIG_IN_BF_EN_N")
	)
	(segment
		(start 17.018 -20.955)
		(end 17.018 -21.971)
		(width 0.11938)
		(layer "B.Cu")
		(net "SMA4_SIG_IN_BF_EN_N")
	)
	(segment
		(start 27.04338 -34.02838)
		(end 27.04338 -41.7068)
		(width 0.11938)
		(layer "B.Cu")
		(net "SMA4_SIG_IN_BF_EN_N")
	)
	(segment
		(start 16.129 -23.495)
		(end 17.018 -24.384)
		(width 0.11938)
		(layer "B.Cu")
		(net "SMA4_SIG_IN_BF_EN_N")
	)
	(segment
		(start 21.11121 -27.02179)
		(end 22.606 -25.527)
		(width 0.11938)
		(layer "B.Cu")
		(net "SMA4_SIG_IN_BF_EN_N")
	)
	(segment
		(start 14.149832 -15.297912)
		(end 14.6558 -15.80388)
		(width 0.11938)
		(layer "B.Cu")
		(net "SMA4_SIG_IN_BF_EN_N")
	)
	(segment
		(start 22.606 -25.527)
		(end 24.638 -25.527)
		(width 0.11938)
		(layer "B.Cu")
		(net "SMA4_SIG_IN_BF_EN_N")
	)
	(segment
		(start 14.6558 -15.80388)
		(end 14.6558 -16.637)
		(width 0.11938)
		(layer "B.Cu")
		(net "SMA4_SIG_IN_BF_EN_N")
	)
	(segment
		(start 16.3576 -17.78)
		(end 15.2146 -16.637)
		(width 0.11938)
		(layer "B.Cu")
		(net "SMA4_SIG_IN_BF_EN_N")
	)
	(segment
		(start 15.2146 -16.637)
		(end 14.6558 -16.637)
		(width 0.11938)
		(layer "B.Cu")
		(net "SMA4_SIG_IN_BF_EN_N")
	)
	(segment
		(start 25.06218 -43.688)
		(end 24.765 -43.688)
		(width 0.11938)
		(layer "B.Cu")
		(net "SMA4_SIG_IN_BF_EN_N")
	)
	(segment
		(start 16.129 -20.066)
		(end 17.018 -20.955)
		(width 0.11938)
		(layer "B.Cu")
		(net "SMA4_SIG_IN_BF_EN_N")
	)
	(segment
		(start 14.097 -15.24)
		(end 14.149832 -15.292832)
		(width 0.11938)
		(layer "B.Cu")
		(net "SMA4_SIG_IN_BF_EN_N")
	)
	(segment
		(start 25.273 -26.162)
		(end 25.273 -32.258)
		(width 0.11938)
		(layer "B.Cu")
		(net "SMA4_SIG_IN_BF_EN_N")
	)
	(segment
		(start 25.273 -32.258)
		(end 27.04338 -34.02838)
		(width 0.11938)
		(layer "B.Cu")
		(net "SMA4_SIG_IN_BF_EN_N")
	)
	(segment
		(start 18.25879 -27.02179)
		(end 21.11121 -27.02179)
		(width 0.11938)
		(layer "B.Cu")
		(net "SMA4_SIG_IN_BF_EN_N")
	)
	(segment
		(start 91.375992 -53.9369)
		(end 89.0651 -53.9369)
		(width 0.127)
		(layer "In7.Cu")
		(net "SMA4_SIG_IN_BF_EN_N")
	)
	(segment
		(start 97.415096 -50.292)
		(end 94.240096 -53.467)
		(width 0.127)
		(layer "In7.Cu")
		(net "SMA4_SIG_IN_BF_EN_N")
	)
	(segment
		(start 83.5025 -54.5465)
		(end 77.343 -54.5465)
		(width 0.127)
		(layer "In7.Cu")
		(net "SMA4_SIG_IN_BF_EN_N")
	)
	(segment
		(start 100.218748 -48.907192)
		(end 99.84994 -49.276)
		(width 0.1016)
		(layer "In7.Cu")
		(net "SMA4_SIG_IN_BF_EN_N")
	)
	(segment
		(start 105.361994 -48.907192)
		(end 100.218748 -48.907192)
		(width 0.1016)
		(layer "In7.Cu")
		(net "SMA4_SIG_IN_BF_EN_N")
	)
	(segment
		(start 91.845892 -53.467)
		(end 91.375992 -53.9369)
		(width 0.127)
		(layer "In7.Cu")
		(net "SMA4_SIG_IN_BF_EN_N")
	)
	(segment
		(start 88.41232 -54.58968)
		(end 88.41232 -55.344314)
		(width 0.127)
		(layer "In7.Cu")
		(net "SMA4_SIG_IN_BF_EN_N")
	)
	(segment
		(start 77.343 -54.5465)
		(end 76.2 -55.6895)
		(width 0.127)
		(layer "In7.Cu")
		(net "SMA4_SIG_IN_BF_EN_N")
	)
	(segment
		(start 84.8995 -55.9435)
		(end 83.5025 -54.5465)
		(width 0.127)
		(layer "In7.Cu")
		(net "SMA4_SIG_IN_BF_EN_N")
	)
	(segment
		(start 89.0651 -53.9369)
		(end 88.41232 -54.58968)
		(width 0.127)
		(layer "In7.Cu")
		(net "SMA4_SIG_IN_BF_EN_N")
	)
	(segment
		(start 88.41232 -55.344314)
		(end 87.813134 -55.9435)
		(width 0.127)
		(layer "In7.Cu")
		(net "SMA4_SIG_IN_BF_EN_N")
	)
	(segment
		(start 105.791 -47.879254)
		(end 105.791 -48.478186)
		(width 0.1016)
		(layer "In7.Cu")
		(net "SMA4_SIG_IN_BF_EN_N")
	)
	(segment
		(start 98.171 -50.292)
		(end 97.415096 -50.292)
		(width 0.127)
		(layer "In7.Cu")
		(net "SMA4_SIG_IN_BF_EN_N")
	)
	(segment
		(start 87.813134 -55.9435)
		(end 84.8995 -55.9435)
		(width 0.127)
		(layer "In7.Cu")
		(net "SMA4_SIG_IN_BF_EN_N")
	)
	(segment
		(start 76.2 -55.6895)
		(end 35.242754 -55.6895)
		(width 0.127)
		(layer "In7.Cu")
		(net "SMA4_SIG_IN_BF_EN_N")
	)
	(segment
		(start 105.791 -48.478186)
		(end 105.361994 -48.907192)
		(width 0.1016)
		(layer "In7.Cu")
		(net "SMA4_SIG_IN_BF_EN_N")
	)
	(segment
		(start 35.242754 -55.6895)
		(end 24.5745 -45.021246)
		(width 0.127)
		(layer "In7.Cu")
		(net "SMA4_SIG_IN_BF_EN_N")
	)
	(segment
		(start 99.84994 -49.276)
		(end 99.187 -49.276)
		(width 0.1016)
		(layer "In7.Cu")
		(net "SMA4_SIG_IN_BF_EN_N")
	)
	(segment
		(start 24.5745 -43.8785)
		(end 24.765 -43.688)
		(width 0.127)
		(layer "In7.Cu")
		(net "SMA4_SIG_IN_BF_EN_N")
	)
	(segment
		(start 99.187 -49.276)
		(end 98.171 -50.292)
		(width 0.127)
		(layer "In7.Cu")
		(net "SMA4_SIG_IN_BF_EN_N")
	)
	(segment
		(start 24.5745 -45.021246)
		(end 24.5745 -43.8785)
		(width 0.127)
		(layer "In7.Cu")
		(net "SMA4_SIG_IN_BF_EN_N")
	)
	(segment
		(start 94.240096 -53.467)
		(end 91.845892 -53.467)
		(width 0.127)
		(layer "In7.Cu")
		(net "SMA4_SIG_IN_BF_EN_N")
	)
	(segment
		(start 106.34726 -47.322994)
		(end 105.791 -47.879254)
		(width 0.1016)
		(layer "In7.Cu")
		(net "SMA4_SIG_IN_BF_EN_N")
	)
	(segment
		(start 99.949 -99.314)
		(end 101.031802 -100.396802)
		(width 0.11938)
		(layer "F.Cu")
		(net "SMA4_LED_RED_N")
	)
	(segment
		(start 101.031802 -100.396802)
		(end 102.84206 -100.396802)
		(width 0.11938)
		(layer "F.Cu")
		(net "SMA4_LED_RED_N")
	)
	(segment
		(start 20.001738 -47.879)
		(end 21.209 -47.879)
		(width 0.11938)
		(layer "F.Cu")
		(net "SMA4_LED_RED_N")
	)
	(via
		(at 99.949 -99.314)
		(size 0.4572)
		(drill 0.2032)
		(layers "F.Cu" "B.Cu")
		(net "SMA4_LED_RED_N")
	)
	(via
		(at 21.209 -47.879)
		(size 0.508)
		(drill 0.254)
		(layers "F.Cu" "B.Cu")
		(net "SMA4_LED_RED_N")
	)
	(segment
		(start 89.057734 -89.819734)
		(end 95.123 -95.885)
		(width 0.127)
		(layer "In7.Cu")
		(net "SMA4_LED_RED_N")
	)
	(segment
		(start 50.8 -85.11667)
		(end 51.4985 -85.81517)
		(width 0.127)
		(layer "In7.Cu")
		(net "SMA4_LED_RED_N")
	)
	(segment
		(start 55.503064 -89.819734)
		(end 89.057734 -89.819734)
		(width 0.127)
		(layer "In7.Cu")
		(net "SMA4_LED_RED_N")
	)
	(segment
		(start 30.150054 -73.0504)
		(end 30.302454 -73.2028)
		(width 0.127)
		(layer "In7.Cu")
		(net "SMA4_LED_RED_N")
	)
	(segment
		(start 15.06728 -65.19672)
		(end 15.06728 -70.185534)
		(width 0.127)
		(layer "In7.Cu")
		(net "SMA4_LED_RED_N")
	)
	(segment
		(start 97.797112 -99.8601)
		(end 99.4029 -99.8601)
		(width 0.127)
		(layer "In7.Cu")
		(net "SMA4_LED_RED_N")
	)
	(segment
		(start 49.657 -80.041242)
		(end 49.657 -82.984086)
		(width 0.127)
		(layer "In7.Cu")
		(net "SMA4_LED_RED_N")
	)
	(segment
		(start 95.123 -95.885)
		(end 95.123 -97.185988)
		(width 0.127)
		(layer "In7.Cu")
		(net "SMA4_LED_RED_N")
	)
	(segment
		(start 17.237202 -58.42)
		(end 16.129 -58.42)
		(width 0.127)
		(layer "In7.Cu")
		(net "SMA4_LED_RED_N")
	)
	(segment
		(start 42.818558 -73.2028)
		(end 49.657 -80.041242)
		(width 0.127)
		(layer "In7.Cu")
		(net "SMA4_LED_RED_N")
	)
	(segment
		(start 15.875 -63.50254)
		(end 15.7353 -63.64224)
		(width 0.127)
		(layer "In7.Cu")
		(net "SMA4_LED_RED_N")
	)
	(segment
		(start 52.43703 -86.7537)
		(end 55.503064 -89.819734)
		(width 0.127)
		(layer "In7.Cu")
		(net "SMA4_LED_RED_N")
	)
	(segment
		(start 19.916902 -72.3265)
		(end 24.636476 -72.3265)
		(width 0.127)
		(layer "In7.Cu")
		(net "SMA4_LED_RED_N")
	)
	(segment
		(start 51.960018 -86.7537)
		(end 52.43703 -86.7537)
		(width 0.127)
		(layer "In7.Cu")
		(net "SMA4_LED_RED_N")
	)
	(segment
		(start 21.209 -47.879)
		(end 20.031202 -49.056798)
		(width 0.127)
		(layer "In7.Cu")
		(net "SMA4_LED_RED_N")
	)
	(segment
		(start 15.7353 -64.5287)
		(end 15.06728 -65.19672)
		(width 0.127)
		(layer "In7.Cu")
		(net "SMA4_LED_RED_N")
	)
	(segment
		(start 16.129 -58.42)
		(end 15.875 -58.674)
		(width 0.127)
		(layer "In7.Cu")
		(net "SMA4_LED_RED_N")
	)
	(segment
		(start 50.8 -84.127086)
		(end 50.8 -85.11667)
		(width 0.127)
		(layer "In7.Cu")
		(net "SMA4_LED_RED_N")
	)
	(segment
		(start 99.4029 -99.8601)
		(end 99.949 -99.314)
		(width 0.127)
		(layer "In7.Cu")
		(net "SMA4_LED_RED_N")
	)
	(segment
		(start 25.360376 -73.0504)
		(end 30.150054 -73.0504)
		(width 0.127)
		(layer "In7.Cu")
		(net "SMA4_LED_RED_N")
	)
	(segment
		(start 20.031202 -49.056798)
		(end 20.031202 -55.626)
		(width 0.127)
		(layer "In7.Cu")
		(net "SMA4_LED_RED_N")
	)
	(segment
		(start 51.4985 -86.292182)
		(end 51.960018 -86.7537)
		(width 0.127)
		(layer "In7.Cu")
		(net "SMA4_LED_RED_N")
	)
	(segment
		(start 19.561302 -72.6821)
		(end 19.916902 -72.3265)
		(width 0.127)
		(layer "In7.Cu")
		(net "SMA4_LED_RED_N")
	)
	(segment
		(start 95.123 -97.185988)
		(end 97.797112 -99.8601)
		(width 0.127)
		(layer "In7.Cu")
		(net "SMA4_LED_RED_N")
	)
	(segment
		(start 15.7353 -63.64224)
		(end 15.7353 -64.5287)
		(width 0.127)
		(layer "In7.Cu")
		(net "SMA4_LED_RED_N")
	)
	(segment
		(start 15.875 -58.674)
		(end 15.875 -63.50254)
		(width 0.127)
		(layer "In7.Cu")
		(net "SMA4_LED_RED_N")
	)
	(segment
		(start 20.031202 -55.626)
		(end 17.237202 -58.42)
		(width 0.127)
		(layer "In7.Cu")
		(net "SMA4_LED_RED_N")
	)
	(segment
		(start 18.676112 -72.6821)
		(end 19.561302 -72.6821)
		(width 0.127)
		(layer "In7.Cu")
		(net "SMA4_LED_RED_N")
	)
	(segment
		(start 16.733012 -70.739)
		(end 18.676112 -72.6821)
		(width 0.127)
		(layer "In7.Cu")
		(net "SMA4_LED_RED_N")
	)
	(segment
		(start 15.06728 -70.185534)
		(end 15.620746 -70.739)
		(width 0.127)
		(layer "In7.Cu")
		(net "SMA4_LED_RED_N")
	)
	(segment
		(start 51.4985 -85.81517)
		(end 51.4985 -86.292182)
		(width 0.127)
		(layer "In7.Cu")
		(net "SMA4_LED_RED_N")
	)
	(segment
		(start 49.657 -82.984086)
		(end 50.8 -84.127086)
		(width 0.127)
		(layer "In7.Cu")
		(net "SMA4_LED_RED_N")
	)
	(segment
		(start 15.620746 -70.739)
		(end 16.733012 -70.739)
		(width 0.127)
		(layer "In7.Cu")
		(net "SMA4_LED_RED_N")
	)
	(segment
		(start 30.302454 -73.2028)
		(end 42.818558 -73.2028)
		(width 0.127)
		(layer "In7.Cu")
		(net "SMA4_LED_RED_N")
	)
	(segment
		(start 24.636476 -72.3265)
		(end 25.360376 -73.0504)
		(width 0.127)
		(layer "In7.Cu")
		(net "SMA4_LED_RED_N")
	)
	(segment
		(start 98.679 -99.314)
		(end 100.261674 -100.896674)
		(width 0.11938)
		(layer "F.Cu")
		(net "SMA4_LED_GREEN_N")
	)
	(segment
		(start 100.261674 -100.896674)
		(end 102.84206 -100.896674)
		(width 0.11938)
		(layer "F.Cu")
		(net "SMA4_LED_GREEN_N")
	)
	(segment
		(start 20.001738 -49.022)
		(end 21.209 -49.022)
		(width 0.11938)
		(layer "F.Cu")
		(net "SMA4_LED_GREEN_N")
	)
	(via
		(at 98.679 -99.314)
		(size 0.4572)
		(drill 0.2032)
		(layers "F.Cu" "B.Cu")
		(net "SMA4_LED_GREEN_N")
	)
	(via
		(at 21.209 -49.022)
		(size 0.508)
		(drill 0.254)
		(layers "F.Cu" "B.Cu")
		(net "SMA4_LED_GREEN_N")
	)
	(segment
		(start 30.530546 -72.8218)
		(end 42.976546 -72.8218)
		(width 0.127)
		(layer "In7.Cu")
		(net "SMA4_LED_GREEN_N")
	)
	(segment
		(start 17.018 -58.801)
		(end 16.256 -59.563)
		(width 0.127)
		(layer "In7.Cu")
		(net "SMA4_LED_GREEN_N")
	)
	(segment
		(start 15.748 -70.231)
		(end 16.764 -70.231)
		(width 0.127)
		(layer "In7.Cu")
		(net "SMA4_LED_GREEN_N")
	)
	(segment
		(start 15.53972 -65.486026)
		(end 15.53972 -70.02272)
		(width 0.127)
		(layer "In7.Cu")
		(net "SMA4_LED_GREEN_N")
	)
	(segment
		(start 25.518364 -72.6694)
		(end 30.378146 -72.6694)
		(width 0.127)
		(layer "In7.Cu")
		(net "SMA4_LED_GREEN_N")
	)
	(segment
		(start 95.8215 -97.0915)
		(end 98.044 -99.314)
		(width 0.127)
		(layer "In7.Cu")
		(net "SMA4_LED_GREEN_N")
	)
	(segment
		(start 16.256 -61.595)
		(end 17.1323 -62.4713)
		(width 0.127)
		(layer "In7.Cu")
		(net "SMA4_LED_GREEN_N")
	)
	(segment
		(start 44.411646 -74.2569)
		(end 47.459646 -74.2569)
		(width 0.127)
		(layer "In7.Cu")
		(net "SMA4_LED_GREEN_N")
	)
	(segment
		(start 16.72336 -64.6303)
		(end 16.395446 -64.6303)
		(width 0.127)
		(layer "In7.Cu")
		(net "SMA4_LED_GREEN_N")
	)
	(segment
		(start 42.976546 -72.8218)
		(end 44.411646 -74.2569)
		(width 0.127)
		(layer "In7.Cu")
		(net "SMA4_LED_GREEN_N")
	)
	(segment
		(start 18.8341 -72.3011)
		(end 19.403314 -72.3011)
		(width 0.127)
		(layer "In7.Cu")
		(net "SMA4_LED_GREEN_N")
	)
	(segment
		(start 51.943 -84.582254)
		(end 52.832 -85.471254)
		(width 0.127)
		(layer "In7.Cu")
		(net "SMA4_LED_GREEN_N")
	)
	(segment
		(start 20.447 -55.88)
		(end 17.526 -58.801)
		(width 0.127)
		(layer "In7.Cu")
		(net "SMA4_LED_GREEN_N")
	)
	(segment
		(start 20.447 -49.784)
		(end 20.447 -55.88)
		(width 0.127)
		(layer "In7.Cu")
		(net "SMA4_LED_GREEN_N")
	)
	(segment
		(start 52.832 -86.609682)
		(end 55.661052 -89.438734)
		(width 0.127)
		(layer "In7.Cu")
		(net "SMA4_LED_GREEN_N")
	)
	(segment
		(start 19.758914 -71.9455)
		(end 24.794464 -71.9455)
		(width 0.127)
		(layer "In7.Cu")
		(net "SMA4_LED_GREEN_N")
	)
	(segment
		(start 51.943 -78.740254)
		(end 51.943 -84.582254)
		(width 0.127)
		(layer "In7.Cu")
		(net "SMA4_LED_GREEN_N")
	)
	(segment
		(start 55.661052 -89.438734)
		(end 89.311734 -89.438734)
		(width 0.127)
		(layer "In7.Cu")
		(net "SMA4_LED_GREEN_N")
	)
	(segment
		(start 17.1323 -62.4713)
		(end 17.1323 -64.22136)
		(width 0.127)
		(layer "In7.Cu")
		(net "SMA4_LED_GREEN_N")
	)
	(segment
		(start 98.044 -99.314)
		(end 98.679 -99.314)
		(width 0.127)
		(layer "In7.Cu")
		(net "SMA4_LED_GREEN_N")
	)
	(segment
		(start 95.8215 -95.9485)
		(end 95.8215 -97.0915)
		(width 0.127)
		(layer "In7.Cu")
		(net "SMA4_LED_GREEN_N")
	)
	(segment
		(start 17.1323 -64.22136)
		(end 16.72336 -64.6303)
		(width 0.127)
		(layer "In7.Cu")
		(net "SMA4_LED_GREEN_N")
	)
	(segment
		(start 16.256 -59.563)
		(end 16.256 -61.595)
		(width 0.127)
		(layer "In7.Cu")
		(net "SMA4_LED_GREEN_N")
	)
	(segment
		(start 17.526 -58.801)
		(end 17.018 -58.801)
		(width 0.127)
		(layer "In7.Cu")
		(net "SMA4_LED_GREEN_N")
	)
	(segment
		(start 16.395446 -64.6303)
		(end 15.53972 -65.486026)
		(width 0.127)
		(layer "In7.Cu")
		(net "SMA4_LED_GREEN_N")
	)
	(segment
		(start 19.403314 -72.3011)
		(end 19.758914 -71.9455)
		(width 0.127)
		(layer "In7.Cu")
		(net "SMA4_LED_GREEN_N")
	)
	(segment
		(start 21.209 -49.022)
		(end 20.447 -49.784)
		(width 0.127)
		(layer "In7.Cu")
		(net "SMA4_LED_GREEN_N")
	)
	(segment
		(start 30.378146 -72.6694)
		(end 30.530546 -72.8218)
		(width 0.127)
		(layer "In7.Cu")
		(net "SMA4_LED_GREEN_N")
	)
	(segment
		(start 24.794464 -71.9455)
		(end 25.518364 -72.6694)
		(width 0.127)
		(layer "In7.Cu")
		(net "SMA4_LED_GREEN_N")
	)
	(segment
		(start 47.459646 -74.2569)
		(end 51.943 -78.740254)
		(width 0.127)
		(layer "In7.Cu")
		(net "SMA4_LED_GREEN_N")
	)
	(segment
		(start 15.53972 -70.02272)
		(end 15.748 -70.231)
		(width 0.127)
		(layer "In7.Cu")
		(net "SMA4_LED_GREEN_N")
	)
	(segment
		(start 16.764 -70.231)
		(end 18.8341 -72.3011)
		(width 0.127)
		(layer "In7.Cu")
		(net "SMA4_LED_GREEN_N")
	)
	(segment
		(start 89.311734 -89.438734)
		(end 95.8215 -95.9485)
		(width 0.127)
		(layer "In7.Cu")
		(net "SMA4_LED_GREEN_N")
	)
	(segment
		(start 52.832 -85.471254)
		(end 52.832 -86.609682)
		(width 0.127)
		(layer "In7.Cu")
		(net "SMA4_LED_GREEN_N")
	)
	(segment
		(start 20.447 -44.45)
		(end 21.209 -45.212)
		(width 0.11938)
		(layer "F.Cu")
		(net "SMA4_LED_BLUE_N")
	)
	(segment
		(start 20.001738 -44.45)
		(end 20.447 -44.45)
		(width 0.11938)
		(layer "F.Cu")
		(net "SMA4_LED_BLUE_N")
	)
	(segment
		(start 101.801676 -99.896676)
		(end 102.80396 -99.896676)
		(width 0.11938)
		(layer "F.Cu")
		(net "SMA4_LED_BLUE_N")
	)
	(segment
		(start 101.219 -99.314)
		(end 101.801676 -99.896676)
		(width 0.11938)
		(layer "F.Cu")
		(net "SMA4_LED_BLUE_N")
	)
	(via
		(at 101.219 -99.314)
		(size 0.4572)
		(drill 0.2032)
		(layers "F.Cu" "B.Cu")
		(net "SMA4_LED_BLUE_N")
	)
	(via
		(at 21.209 -45.212)
		(size 0.508)
		(drill 0.254)
		(layers "F.Cu" "B.Cu")
		(net "SMA4_LED_BLUE_N")
	)
	(segment
		(start 24.4094 -73.3044)
		(end 22.274022 -73.3044)
		(width 0.127)
		(layer "In7.Cu")
		(net "SMA4_LED_BLUE_N")
	)
	(segment
		(start 101.219 -99.314)
		(end 100.2919 -100.2411)
		(width 0.127)
		(layer "In7.Cu")
		(net "SMA4_LED_BLUE_N")
	)
	(segment
		(start 42.9895 -73.9775)
		(end 36.277042 -73.9775)
		(width 0.127)
		(layer "In7.Cu")
		(net "SMA4_LED_BLUE_N")
	)
	(segment
		(start 50.419 -89.408)
		(end 50.419 -84.306918)
		(width 0.127)
		(layer "In7.Cu")
		(net "SMA4_LED_BLUE_N")
	)
	(segment
		(start 15.113 -63.673228)
		(end 15.494 -63.292228)
		(width 0.127)
		(layer "In7.Cu")
		(net "SMA4_LED_BLUE_N")
	)
	(segment
		(start 25.4508 -74.3458)
		(end 24.4094 -73.3044)
		(width 0.127)
		(layer "In7.Cu")
		(net "SMA4_LED_BLUE_N")
	)
	(segment
		(start 21.566886 -73.558908)
		(end 21.071078 -73.0631)
		(width 0.127)
		(layer "In7.Cu")
		(net "SMA4_LED_BLUE_N")
	)
	(segment
		(start 94.615 -97.216976)
		(end 94.615 -95.915988)
		(width 0.127)
		(layer "In7.Cu")
		(net "SMA4_LED_BLUE_N")
	)
	(segment
		(start 18.518124 -73.0631)
		(end 17.908524 -72.4535)
		(width 0.127)
		(layer "In7.Cu")
		(net "SMA4_LED_BLUE_N")
	)
	(segment
		(start 19.518122 -53.379878)
		(end 19.518122 -46.902878)
		(width 0.127)
		(layer "In7.Cu")
		(net "SMA4_LED_BLUE_N")
	)
	(segment
		(start 56.961278 -90.200734)
		(end 56.357012 -90.805)
		(width 0.127)
		(layer "In7.Cu")
		(net "SMA4_LED_BLUE_N")
	)
	(segment
		(start 30.1244 -74.3458)
		(end 25.4508 -74.3458)
		(width 0.127)
		(layer "In7.Cu")
		(net "SMA4_LED_BLUE_N")
	)
	(segment
		(start 97.639124 -100.2411)
		(end 94.615 -97.216976)
		(width 0.127)
		(layer "In7.Cu")
		(net "SMA4_LED_BLUE_N")
	)
	(segment
		(start 16.4719 -72.133714)
		(end 16.4719 -72.129142)
		(width 0.127)
		(layer "In7.Cu")
		(net "SMA4_LED_BLUE_N")
	)
	(segment
		(start 49.276 -83.163918)
		(end 49.276 -80.264)
		(width 0.127)
		(layer "In7.Cu")
		(net "SMA4_LED_BLUE_N")
	)
	(segment
		(start 100.2919 -100.2411)
		(end 97.639124 -100.2411)
		(width 0.127)
		(layer "In7.Cu")
		(net "SMA4_LED_BLUE_N")
	)
	(segment
		(start 15.8115 -58.031126)
		(end 15.8115 -57.0865)
		(width 0.127)
		(layer "In7.Cu")
		(net "SMA4_LED_BLUE_N")
	)
	(segment
		(start 56.357012 -90.805)
		(end 51.816 -90.805)
		(width 0.127)
		(layer "In7.Cu")
		(net "SMA4_LED_BLUE_N")
	)
	(segment
		(start 30.6578 -74.8792)
		(end 30.1244 -74.3458)
		(width 0.127)
		(layer "In7.Cu")
		(net "SMA4_LED_BLUE_N")
	)
	(segment
		(start 14.68628 -65.038732)
		(end 15.113 -64.612012)
		(width 0.127)
		(layer "In7.Cu")
		(net "SMA4_LED_BLUE_N")
	)
	(segment
		(start 21.071078 -73.0631)
		(end 18.518124 -73.0631)
		(width 0.127)
		(layer "In7.Cu")
		(net "SMA4_LED_BLUE_N")
	)
	(segment
		(start 35.261042 -74.4855)
		(end 34.867342 -74.8792)
		(width 0.127)
		(layer "In7.Cu")
		(net "SMA4_LED_BLUE_N")
	)
	(segment
		(start 15.494 -63.292228)
		(end 15.494 -58.348626)
		(width 0.127)
		(layer "In7.Cu")
		(net "SMA4_LED_BLUE_N")
	)
	(segment
		(start 94.615 -95.915988)
		(end 88.899746 -90.200734)
		(width 0.127)
		(layer "In7.Cu")
		(net "SMA4_LED_BLUE_N")
	)
	(segment
		(start 35.769042 -74.4855)
		(end 35.261042 -74.4855)
		(width 0.127)
		(layer "In7.Cu")
		(net "SMA4_LED_BLUE_N")
	)
	(segment
		(start 16.791686 -72.4535)
		(end 16.4719 -72.133714)
		(width 0.127)
		(layer "In7.Cu")
		(net "SMA4_LED_BLUE_N")
	)
	(segment
		(start 36.277042 -73.9775)
		(end 35.769042 -74.4855)
		(width 0.127)
		(layer "In7.Cu")
		(net "SMA4_LED_BLUE_N")
	)
	(segment
		(start 34.867342 -74.8792)
		(end 30.6578 -74.8792)
		(width 0.127)
		(layer "In7.Cu")
		(net "SMA4_LED_BLUE_N")
	)
	(segment
		(start 15.113 -64.612012)
		(end 15.113 -63.673228)
		(width 0.127)
		(layer "In7.Cu")
		(net "SMA4_LED_BLUE_N")
	)
	(segment
		(start 14.68628 -70.343522)
		(end 14.68628 -65.038732)
		(width 0.127)
		(layer "In7.Cu")
		(net "SMA4_LED_BLUE_N")
	)
	(segment
		(start 22.274022 -73.3044)
		(end 22.019514 -73.558908)
		(width 0.127)
		(layer "In7.Cu")
		(net "SMA4_LED_BLUE_N")
	)
	(segment
		(start 17.908524 -72.4535)
		(end 16.791686 -72.4535)
		(width 0.127)
		(layer "In7.Cu")
		(net "SMA4_LED_BLUE_N")
	)
	(segment
		(start 15.494 -58.348626)
		(end 15.8115 -58.031126)
		(width 0.127)
		(layer "In7.Cu")
		(net "SMA4_LED_BLUE_N")
	)
	(segment
		(start 22.019514 -73.558908)
		(end 21.566886 -73.558908)
		(width 0.127)
		(layer "In7.Cu")
		(net "SMA4_LED_BLUE_N")
	)
	(segment
		(start 51.816 -90.805)
		(end 50.419 -89.408)
		(width 0.127)
		(layer "In7.Cu")
		(net "SMA4_LED_BLUE_N")
	)
	(segment
		(start 49.276 -80.264)
		(end 42.9895 -73.9775)
		(width 0.127)
		(layer "In7.Cu")
		(net "SMA4_LED_BLUE_N")
	)
	(segment
		(start 19.518122 -46.902878)
		(end 21.209 -45.212)
		(width 0.127)
		(layer "In7.Cu")
		(net "SMA4_LED_BLUE_N")
	)
	(segment
		(start 16.4719 -72.129142)
		(end 14.68628 -70.343522)
		(width 0.127)
		(layer "In7.Cu")
		(net "SMA4_LED_BLUE_N")
	)
	(segment
		(start 88.899746 -90.200734)
		(end 56.961278 -90.200734)
		(width 0.127)
		(layer "In7.Cu")
		(net "SMA4_LED_BLUE_N")
	)
	(segment
		(start 50.419 -84.306918)
		(end 49.276 -83.163918)
		(width 0.127)
		(layer "In7.Cu")
		(net "SMA4_LED_BLUE_N")
	)
	(segment
		(start 15.8115 -57.0865)
		(end 19.518122 -53.379878)
		(width 0.127)
		(layer "In7.Cu")
		(net "SMA4_LED_BLUE_N")
	)
	(segment
		(start 14.859 -35.179)
		(end 14.649704 -34.969704)
		(width 0.11938)
		(layer "F.Cu")
		(net "SMA3_SIG_OUT_BF_EN_N")
	)
	(segment
		(start 14.732 -36.068)
		(end 14.859 -35.941)
		(width 0.11938)
		(layer "F.Cu")
		(net "SMA3_SIG_OUT_BF_EN_N")
	)
	(segment
		(start 14.732 -36.6776)
		(end 14.732 -36.068)
		(width 0.11938)
		(layer "F.Cu")
		(net "SMA3_SIG_OUT_BF_EN_N")
	)
	(segment
		(start 14.986 -34.29)
		(end 16.383 -32.893)
		(width 0.11938)
		(layer "F.Cu")
		(net "SMA3_SIG_OUT_BF_EN_N")
	)
	(segment
		(start 106.847132 -47.82312)
		(end 106.34726 -48.322992)
		(width 0.11938)
		(layer "F.Cu")
		(net "SMA3_SIG_OUT_BF_EN_N")
	)
	(segment
		(start 14.649704 -34.969704)
		(end 14.649704 -34.29)
		(width 0.11938)
		(layer "F.Cu")
		(net "SMA3_SIG_OUT_BF_EN_N")
	)
	(segment
		(start 14.859 -35.941)
		(end 14.859 -35.179)
		(width 0.11938)
		(layer "F.Cu")
		(net "SMA3_SIG_OUT_BF_EN_N")
	)
	(segment
		(start 14.649704 -34.29)
		(end 14.986 -34.29)
		(width 0.11938)
		(layer "F.Cu")
		(net "SMA3_SIG_OUT_BF_EN_N")
	)
	(via
		(at 106.34726 -48.322992)
		(size 0.4572)
		(drill 0.2032)
		(layers "F.Cu" "B.Cu")
		(net "SMA3_SIG_OUT_BF_EN_N")
	)
	(via
		(at 24.257 -48.768)
		(size 0.508)
		(drill 0.254)
		(layers "F.Cu" "B.Cu")
		(net "SMA3_SIG_OUT_BF_EN_N")
	)
	(segment
		(start 24.257 -48.768)
		(end 23.749 -48.768)
		(width 0.127)
		(layer "In2.Cu")
		(net "SMA3_SIG_OUT_BF_EN_N")
	)
	(segment
		(start 23.495 -48.514)
		(end 22.733 -48.514)
		(width 0.127)
		(layer "In2.Cu")
		(net "SMA3_SIG_OUT_BF_EN_N")
	)
	(segment
		(start 22.733 -48.514)
		(end 22.225 -48.006)
		(width 0.127)
		(layer "In2.Cu")
		(net "SMA3_SIG_OUT_BF_EN_N")
	)
	(segment
		(start 16.383 -41.402)
		(end 16.383 -32.893)
		(width 0.127)
		(layer "In2.Cu")
		(net "SMA3_SIG_OUT_BF_EN_N")
	)
	(segment
		(start 22.225 -47.244)
		(end 16.383 -41.402)
		(width 0.127)
		(layer "In2.Cu")
		(net "SMA3_SIG_OUT_BF_EN_N")
	)
	(segment
		(start 23.749 -48.768)
		(end 23.495 -48.514)
		(width 0.127)
		(layer "In2.Cu")
		(net "SMA3_SIG_OUT_BF_EN_N")
	)
	(segment
		(start 22.225 -48.006)
		(end 22.225 -47.244)
		(width 0.127)
		(layer "In2.Cu")
		(net "SMA3_SIG_OUT_BF_EN_N")
	)
	(segment
		(start 96.033844 -54.461156)
		(end 96.315022 -54.461156)
		(width 0.127)
		(layer "In7.Cu")
		(net "SMA3_SIG_OUT_BF_EN_N")
	)
	(segment
		(start 103.74122 -49.78146)
		(end 105.5497 -49.78146)
		(width 0.1016)
		(layer "In7.Cu")
		(net "SMA3_SIG_OUT_BF_EN_N")
	)
	(segment
		(start 98.3488 -51.1302)
		(end 99.314 -50.165)
		(width 0.127)
		(layer "In7.Cu")
		(net "SMA3_SIG_OUT_BF_EN_N")
	)
	(segment
		(start 105.5497 -49.78146)
		(end 105.791 -49.54016)
		(width 0.1016)
		(layer "In7.Cu")
		(net "SMA3_SIG_OUT_BF_EN_N")
	)
	(segment
		(start 103.580692 -49.941988)
		(end 103.74122 -49.78146)
		(width 0.1016)
		(layer "In7.Cu")
		(net "SMA3_SIG_OUT_BF_EN_N")
	)
	(segment
		(start 92.5449 -57.9501)
		(end 96.033844 -54.461156)
		(width 0.127)
		(layer "In7.Cu")
		(net "SMA3_SIG_OUT_BF_EN_N")
	)
	(segment
		(start 84.367624 -57.0865)
		(end 89.263728 -57.0865)
		(width 0.127)
		(layer "In7.Cu")
		(net "SMA3_SIG_OUT_BF_EN_N")
	)
	(segment
		(start 79.7941 -56.6801)
		(end 80.01 -56.896)
		(width 0.127)
		(layer "In7.Cu")
		(net "SMA3_SIG_OUT_BF_EN_N")
	)
	(segment
		(start 90.127328 -57.9501)
		(end 92.5449 -57.9501)
		(width 0.127)
		(layer "In7.Cu")
		(net "SMA3_SIG_OUT_BF_EN_N")
	)
	(segment
		(start 96.315022 -54.461156)
		(end 97.514156 -53.262022)
		(width 0.127)
		(layer "In7.Cu")
		(net "SMA3_SIG_OUT_BF_EN_N")
	)
	(segment
		(start 97.514156 -52.980844)
		(end 98.3488 -52.1462)
		(width 0.127)
		(layer "In7.Cu")
		(net "SMA3_SIG_OUT_BF_EN_N")
	)
	(segment
		(start 97.514156 -53.262022)
		(end 97.514156 -52.980844)
		(width 0.127)
		(layer "In7.Cu")
		(net "SMA3_SIG_OUT_BF_EN_N")
	)
	(segment
		(start 105.791 -49.54016)
		(end 105.791 -48.879252)
		(width 0.1016)
		(layer "In7.Cu")
		(net "SMA3_SIG_OUT_BF_EN_N")
	)
	(segment
		(start 77.8383 -57.9247)
		(end 79.0829 -56.6801)
		(width 0.127)
		(layer "In7.Cu")
		(net "SMA3_SIG_OUT_BF_EN_N")
	)
	(segment
		(start 98.3488 -52.1462)
		(end 98.3488 -51.1302)
		(width 0.127)
		(layer "In7.Cu")
		(net "SMA3_SIG_OUT_BF_EN_N")
	)
	(segment
		(start 24.638 -49.149)
		(end 25.019 -49.149)
		(width 0.127)
		(layer "In7.Cu")
		(net "SMA3_SIG_OUT_BF_EN_N")
	)
	(segment
		(start 24.257 -48.768)
		(end 24.638 -49.149)
		(width 0.127)
		(layer "In7.Cu")
		(net "SMA3_SIG_OUT_BF_EN_N")
	)
	(segment
		(start 84.177124 -56.896)
		(end 84.367624 -57.0865)
		(width 0.127)
		(layer "In7.Cu")
		(net "SMA3_SIG_OUT_BF_EN_N")
	)
	(segment
		(start 105.791 -48.879252)
		(end 106.34726 -48.322992)
		(width 0.1016)
		(layer "In7.Cu")
		(net "SMA3_SIG_OUT_BF_EN_N")
	)
	(segment
		(start 89.263728 -57.0865)
		(end 90.127328 -57.9501)
		(width 0.127)
		(layer "In7.Cu")
		(net "SMA3_SIG_OUT_BF_EN_N")
	)
	(segment
		(start 79.0829 -56.6801)
		(end 79.7941 -56.6801)
		(width 0.127)
		(layer "In7.Cu")
		(net "SMA3_SIG_OUT_BF_EN_N")
	)
	(segment
		(start 99.314 -50.165)
		(end 99.537012 -49.941988)
		(width 0.1016)
		(layer "In7.Cu")
		(net "SMA3_SIG_OUT_BF_EN_N")
	)
	(segment
		(start 25.019 -49.149)
		(end 33.7947 -57.9247)
		(width 0.127)
		(layer "In7.Cu")
		(net "SMA3_SIG_OUT_BF_EN_N")
	)
	(segment
		(start 33.7947 -57.9247)
		(end 77.8383 -57.9247)
		(width 0.127)
		(layer "In7.Cu")
		(net "SMA3_SIG_OUT_BF_EN_N")
	)
	(segment
		(start 80.01 -56.896)
		(end 84.177124 -56.896)
		(width 0.127)
		(layer "In7.Cu")
		(net "SMA3_SIG_OUT_BF_EN_N")
	)
	(segment
		(start 99.537012 -49.941988)
		(end 103.580692 -49.941988)
		(width 0.1016)
		(layer "In7.Cu")
		(net "SMA3_SIG_OUT_BF_EN_N")
	)
	(segment
		(start 14.149832 -30.099)
		(end 14.149832 -30.909768)
		(width 0.11938)
		(layer "F.Cu")
		(net "SMA3_SIG_IN_BF_EN_N")
	)
	(segment
		(start 105.847134 -47.82312)
		(end 105.347262 -48.322992)
		(width 0.11938)
		(layer "F.Cu")
		(net "SMA3_SIG_IN_BF_EN_N")
	)
	(segment
		(start 12.827 -29.21)
		(end 13.081 -29.464)
		(width 0.11938)
		(layer "F.Cu")
		(net "SMA3_SIG_IN_BF_EN_N")
	)
	(segment
		(start 12.827 -28.59786)
		(end 14.24686 -28.59786)
		(width 0.11938)
		(layer "F.Cu")
		(net "SMA3_SIG_IN_BF_EN_N")
	)
	(segment
		(start 13.081 -29.464)
		(end 13.514832 -29.464)
		(width 0.11938)
		(layer "F.Cu")
		(net "SMA3_SIG_IN_BF_EN_N")
	)
	(segment
		(start 13.514832 -29.464)
		(end 14.149832 -30.099)
		(width 0.11938)
		(layer "F.Cu")
		(net "SMA3_SIG_IN_BF_EN_N")
	)
	(segment
		(start 12.827 -28.59786)
		(end 12.827 -29.21)
		(width 0.11938)
		(layer "F.Cu")
		(net "SMA3_SIG_IN_BF_EN_N")
	)
	(segment
		(start 14.24686 -28.59786)
		(end 14.351 -28.702)
		(width 0.11938)
		(layer "F.Cu")
		(net "SMA3_SIG_IN_BF_EN_N")
	)
	(via
		(at 25.146 -44.577)
		(size 0.508)
		(drill 0.254)
		(layers "F.Cu" "B.Cu")
		(net "SMA3_SIG_IN_BF_EN_N")
	)
	(via
		(at 22.479 -37.846)
		(size 0.508)
		(drill 0.254)
		(layers "F.Cu" "B.Cu")
		(net "SMA3_SIG_IN_BF_EN_N")
	)
	(via
		(at 105.347262 -48.322992)
		(size 0.4572)
		(drill 0.2032)
		(layers "F.Cu" "B.Cu")
		(net "SMA3_SIG_IN_BF_EN_N")
	)
	(segment
		(start 14.351 -29.002482)
		(end 15.638018 -30.2895)
		(width 0.127)
		(layer "In2.Cu")
		(net "SMA3_SIG_IN_BF_EN_N")
	)
	(segment
		(start 25.654 -38.5572)
		(end 25.654 -44.069)
		(width 0.127)
		(layer "In2.Cu")
		(net "SMA3_SIG_IN_BF_EN_N")
	)
	(segment
		(start 14.351 -28.702)
		(end 14.351 -29.002482)
		(width 0.127)
		(layer "In2.Cu")
		(net "SMA3_SIG_IN_BF_EN_N")
	)
	(segment
		(start 17.2085 -30.7975)
		(end 18.2245 -31.8135)
		(width 0.127)
		(layer "In2.Cu")
		(net "SMA3_SIG_IN_BF_EN_N")
	)
	(segment
		(start 22.606 -37.719)
		(end 24.8158 -37.719)
		(width 0.127)
		(layer "In2.Cu")
		(net "SMA3_SIG_IN_BF_EN_N")
	)
	(segment
		(start 25.654 -44.069)
		(end 25.146 -44.577)
		(width 0.127)
		(layer "In2.Cu")
		(net "SMA3_SIG_IN_BF_EN_N")
	)
	(segment
		(start 17.907 -36.322)
		(end 19.431 -37.846)
		(width 0.127)
		(layer "In2.Cu")
		(net "SMA3_SIG_IN_BF_EN_N")
	)
	(segment
		(start 17.907 -35.940746)
		(end 17.907 -36.322)
		(width 0.127)
		(layer "In2.Cu")
		(net "SMA3_SIG_IN_BF_EN_N")
	)
	(segment
		(start 18.2245 -31.8135)
		(end 18.2245 -35.623246)
		(width 0.127)
		(layer "In2.Cu")
		(net "SMA3_SIG_IN_BF_EN_N")
	)
	(segment
		(start 17.035018 -30.7975)
		(end 17.2085 -30.7975)
		(width 0.127)
		(layer "In2.Cu")
		(net "SMA3_SIG_IN_BF_EN_N")
	)
	(segment
		(start 15.638018 -30.2895)
		(end 16.527018 -30.2895)
		(width 0.127)
		(layer "In2.Cu")
		(net "SMA3_SIG_IN_BF_EN_N")
	)
	(segment
		(start 16.527018 -30.2895)
		(end 17.035018 -30.7975)
		(width 0.127)
		(layer "In2.Cu")
		(net "SMA3_SIG_IN_BF_EN_N")
	)
	(segment
		(start 19.431 -37.846)
		(end 22.479 -37.846)
		(width 0.127)
		(layer "In2.Cu")
		(net "SMA3_SIG_IN_BF_EN_N")
	)
	(segment
		(start 22.479 -37.846)
		(end 22.606 -37.719)
		(width 0.127)
		(layer "In2.Cu")
		(net "SMA3_SIG_IN_BF_EN_N")
	)
	(segment
		(start 18.2245 -35.623246)
		(end 17.907 -35.940746)
		(width 0.127)
		(layer "In2.Cu")
		(net "SMA3_SIG_IN_BF_EN_N")
	)
	(segment
		(start 24.8158 -37.719)
		(end 25.654 -38.5572)
		(width 0.127)
		(layer "In2.Cu")
		(net "SMA3_SIG_IN_BF_EN_N")
	)
	(segment
		(start 100.109274 -48.703992)
		(end 104.966262 -48.703992)
		(width 0.1016)
		(layer "In7.Cu")
		(net "SMA3_SIG_IN_BF_EN_N")
	)
	(segment
		(start 85.217 -54.483)
		(end 86.0425 -55.3085)
		(width 0.127)
		(layer "In7.Cu")
		(net "SMA3_SIG_IN_BF_EN_N")
	)
	(segment
		(start 86.0425 -55.3085)
		(end 86.723728 -55.3085)
		(width 0.127)
		(layer "In7.Cu")
		(net "SMA3_SIG_IN_BF_EN_N")
	)
	(segment
		(start 98.146108 -49.022)
		(end 99.06 -49.022)
		(width 0.127)
		(layer "In7.Cu")
		(net "SMA3_SIG_IN_BF_EN_N")
	)
	(segment
		(start 91.218004 -53.5559)
		(end 91.687904 -53.086)
		(width 0.127)
		(layer "In7.Cu")
		(net "SMA3_SIG_IN_BF_EN_N")
	)
	(segment
		(start 82.300064 -53.5559)
		(end 85.0519 -53.5559)
		(width 0.127)
		(layer "In7.Cu")
		(net "SMA3_SIG_IN_BF_EN_N")
	)
	(segment
		(start 99.06 -49.022)
		(end 99.791266 -49.022)
		(width 0.1016)
		(layer "In7.Cu")
		(net "SMA3_SIG_IN_BF_EN_N")
	)
	(segment
		(start 94.082108 -53.086)
		(end 98.146108 -49.022)
		(width 0.127)
		(layer "In7.Cu")
		(net "SMA3_SIG_IN_BF_EN_N")
	)
	(segment
		(start 25.146 -44.958)
		(end 35.4965 -55.3085)
		(width 0.127)
		(layer "In7.Cu")
		(net "SMA3_SIG_IN_BF_EN_N")
	)
	(segment
		(start 76.042012 -55.3085)
		(end 77.439012 -53.9115)
		(width 0.127)
		(layer "In7.Cu")
		(net "SMA3_SIG_IN_BF_EN_N")
	)
	(segment
		(start 91.687904 -53.086)
		(end 94.082108 -53.086)
		(width 0.127)
		(layer "In7.Cu")
		(net "SMA3_SIG_IN_BF_EN_N")
	)
	(segment
		(start 104.966262 -48.703992)
		(end 105.347262 -48.322992)
		(width 0.1016)
		(layer "In7.Cu")
		(net "SMA3_SIG_IN_BF_EN_N")
	)
	(segment
		(start 85.0519 -53.5559)
		(end 85.217 -53.721)
		(width 0.127)
		(layer "In7.Cu")
		(net "SMA3_SIG_IN_BF_EN_N")
	)
	(segment
		(start 99.791266 -49.022)
		(end 100.109274 -48.703992)
		(width 0.1016)
		(layer "In7.Cu")
		(net "SMA3_SIG_IN_BF_EN_N")
	)
	(segment
		(start 35.4965 -55.3085)
		(end 76.042012 -55.3085)
		(width 0.127)
		(layer "In7.Cu")
		(net "SMA3_SIG_IN_BF_EN_N")
	)
	(segment
		(start 88.476328 -53.5559)
		(end 91.218004 -53.5559)
		(width 0.127)
		(layer "In7.Cu")
		(net "SMA3_SIG_IN_BF_EN_N")
	)
	(segment
		(start 85.217 -53.721)
		(end 85.217 -54.483)
		(width 0.127)
		(layer "In7.Cu")
		(net "SMA3_SIG_IN_BF_EN_N")
	)
	(segment
		(start 81.944464 -53.9115)
		(end 82.300064 -53.5559)
		(width 0.127)
		(layer "In7.Cu")
		(net "SMA3_SIG_IN_BF_EN_N")
	)
	(segment
		(start 86.723728 -55.3085)
		(end 88.476328 -53.5559)
		(width 0.127)
		(layer "In7.Cu")
		(net "SMA3_SIG_IN_BF_EN_N")
	)
	(segment
		(start 25.146 -44.577)
		(end 25.146 -44.958)
		(width 0.127)
		(layer "In7.Cu")
		(net "SMA3_SIG_IN_BF_EN_N")
	)
	(segment
		(start 77.439012 -53.9115)
		(end 81.944464 -53.9115)
		(width 0.127)
		(layer "In7.Cu")
		(net "SMA3_SIG_IN_BF_EN_N")
	)
	(segment
		(start 8.4328 -67.667632)
		(end 8.4328 -66.677032)
		(width 0.11938)
		(layer "F.Cu")
		(net "SMA3_LED_RED_N")
	)
	(segment
		(start 102.84206 -102.396798)
		(end 100.745798 -102.396798)
		(width 0.11938)
		(layer "F.Cu")
		(net "SMA3_LED_RED_N")
	)
	(segment
		(start 100.745798 -102.396798)
		(end 99.949 -101.6)
		(width 0.11938)
		(layer "F.Cu")
		(net "SMA3_LED_RED_N")
	)
	(via
		(at 99.949 -101.6)
		(size 0.4572)
		(drill 0.2032)
		(layers "F.Cu" "B.Cu")
		(net "SMA3_LED_RED_N")
	)
	(via
		(at 8.4328 -66.677032)
		(size 0.508)
		(drill 0.254)
		(layers "F.Cu" "B.Cu")
		(net "SMA3_LED_RED_N")
	)
	(segment
		(start 93.599 -96.062546)
		(end 93.599 -97.408746)
		(width 0.127)
		(layer "In7.Cu")
		(net "SMA3_LED_RED_N")
	)
	(segment
		(start 37.066982 -74.7395)
		(end 37.308282 -74.9808)
		(width 0.127)
		(layer "In7.Cu")
		(net "SMA3_LED_RED_N")
	)
	(segment
		(start 51.509168 -91.948)
		(end 57.307988 -91.948)
		(width 0.127)
		(layer "In7.Cu")
		(net "SMA3_LED_RED_N")
	)
	(segment
		(start 99.314 -102.235)
		(end 99.949 -101.6)
		(width 0.127)
		(layer "In7.Cu")
		(net "SMA3_LED_RED_N")
	)
	(segment
		(start 42.621454 -76.4032)
		(end 42.926254 -76.708)
		(width 0.127)
		(layer "In7.Cu")
		(net "SMA3_LED_RED_N")
	)
	(segment
		(start 16.47571 -73.2155)
		(end 17.592548 -73.2155)
		(width 0.127)
		(layer "In7.Cu")
		(net "SMA3_LED_RED_N")
	)
	(segment
		(start 9.525 -68.199)
		(end 9.525 -68.229988)
		(width 0.127)
		(layer "In7.Cu")
		(net "SMA3_LED_RED_N")
	)
	(segment
		(start 19.575018 -74.6125)
		(end 20.048982 -74.6125)
		(width 0.127)
		(layer "In7.Cu")
		(net "SMA3_LED_RED_N")
	)
	(segment
		(start 88.595454 -91.059)
		(end 93.599 -96.062546)
		(width 0.127)
		(layer "In7.Cu")
		(net "SMA3_LED_RED_N")
	)
	(segment
		(start 22.516846 -74.3585)
		(end 23.342346 -75.184)
		(width 0.127)
		(layer "In7.Cu")
		(net "SMA3_LED_RED_N")
	)
	(segment
		(start 38.39337 -75.5269)
		(end 40.428164 -75.5269)
		(width 0.127)
		(layer "In7.Cu")
		(net "SMA3_LED_RED_N")
	)
	(segment
		(start 35.183318 -75.6412)
		(end 35.577018 -75.2475)
		(width 0.127)
		(layer "In7.Cu")
		(net "SMA3_LED_RED_N")
	)
	(segment
		(start 17.592548 -73.2155)
		(end 18.202148 -73.8251)
		(width 0.127)
		(layer "In7.Cu")
		(net "SMA3_LED_RED_N")
	)
	(segment
		(start 47.371 -87.809832)
		(end 51.509168 -91.948)
		(width 0.127)
		(layer "In7.Cu")
		(net "SMA3_LED_RED_N")
	)
	(segment
		(start 23.342346 -75.184)
		(end 29.119322 -75.184)
		(width 0.127)
		(layer "In7.Cu")
		(net "SMA3_LED_RED_N")
	)
	(segment
		(start 35.577018 -75.2475)
		(end 36.085018 -75.2475)
		(width 0.127)
		(layer "In7.Cu")
		(net "SMA3_LED_RED_N")
	)
	(segment
		(start 36.085018 -75.2475)
		(end 36.593018 -74.7395)
		(width 0.127)
		(layer "In7.Cu")
		(net "SMA3_LED_RED_N")
	)
	(segment
		(start 40.428164 -75.5269)
		(end 41.304464 -76.4032)
		(width 0.127)
		(layer "In7.Cu")
		(net "SMA3_LED_RED_N")
	)
	(segment
		(start 47.371 -79.756)
		(end 47.371 -87.809832)
		(width 0.127)
		(layer "In7.Cu")
		(net "SMA3_LED_RED_N")
	)
	(segment
		(start 37.84727 -74.9808)
		(end 38.39337 -75.5269)
		(width 0.127)
		(layer "In7.Cu")
		(net "SMA3_LED_RED_N")
	)
	(segment
		(start 44.323 -76.708)
		(end 47.371 -79.756)
		(width 0.127)
		(layer "In7.Cu")
		(net "SMA3_LED_RED_N")
	)
	(segment
		(start 58.196988 -91.059)
		(end 88.595454 -91.059)
		(width 0.127)
		(layer "In7.Cu")
		(net "SMA3_LED_RED_N")
	)
	(segment
		(start 12.923012 -71.628)
		(end 14.88821 -71.628)
		(width 0.127)
		(layer "In7.Cu")
		(net "SMA3_LED_RED_N")
	)
	(segment
		(start 29.119322 -75.184)
		(end 29.576522 -75.6412)
		(width 0.127)
		(layer "In7.Cu")
		(net "SMA3_LED_RED_N")
	)
	(segment
		(start 18.202148 -73.8251)
		(end 18.787618 -73.8251)
		(width 0.127)
		(layer "In7.Cu")
		(net "SMA3_LED_RED_N")
	)
	(segment
		(start 93.599 -97.408746)
		(end 98.425254 -102.235)
		(width 0.127)
		(layer "In7.Cu")
		(net "SMA3_LED_RED_N")
	)
	(segment
		(start 14.88821 -71.628)
		(end 16.47571 -73.2155)
		(width 0.127)
		(layer "In7.Cu")
		(net "SMA3_LED_RED_N")
	)
	(segment
		(start 41.304464 -76.4032)
		(end 42.621454 -76.4032)
		(width 0.127)
		(layer "In7.Cu")
		(net "SMA3_LED_RED_N")
	)
	(segment
		(start 8.4328 -66.677032)
		(end 8.4328 -67.1068)
		(width 0.127)
		(layer "In7.Cu")
		(net "SMA3_LED_RED_N")
	)
	(segment
		(start 20.302982 -74.3585)
		(end 22.516846 -74.3585)
		(width 0.127)
		(layer "In7.Cu")
		(net "SMA3_LED_RED_N")
	)
	(segment
		(start 37.308282 -74.9808)
		(end 37.84727 -74.9808)
		(width 0.127)
		(layer "In7.Cu")
		(net "SMA3_LED_RED_N")
	)
	(segment
		(start 20.048982 -74.6125)
		(end 20.302982 -74.3585)
		(width 0.127)
		(layer "In7.Cu")
		(net "SMA3_LED_RED_N")
	)
	(segment
		(start 98.425254 -102.235)
		(end 99.314 -102.235)
		(width 0.127)
		(layer "In7.Cu")
		(net "SMA3_LED_RED_N")
	)
	(segment
		(start 36.593018 -74.7395)
		(end 37.066982 -74.7395)
		(width 0.127)
		(layer "In7.Cu")
		(net "SMA3_LED_RED_N")
	)
	(segment
		(start 18.787618 -73.8251)
		(end 19.575018 -74.6125)
		(width 0.127)
		(layer "In7.Cu")
		(net "SMA3_LED_RED_N")
	)
	(segment
		(start 42.926254 -76.708)
		(end 44.323 -76.708)
		(width 0.127)
		(layer "In7.Cu")
		(net "SMA3_LED_RED_N")
	)
	(segment
		(start 57.307988 -91.948)
		(end 58.196988 -91.059)
		(width 0.127)
		(layer "In7.Cu")
		(net "SMA3_LED_RED_N")
	)
	(segment
		(start 29.576522 -75.6412)
		(end 35.183318 -75.6412)
		(width 0.127)
		(layer "In7.Cu")
		(net "SMA3_LED_RED_N")
	)
	(segment
		(start 8.4328 -67.1068)
		(end 9.525 -68.199)
		(width 0.127)
		(layer "In7.Cu")
		(net "SMA3_LED_RED_N")
	)
	(segment
		(start 9.525 -68.229988)
		(end 12.923012 -71.628)
		(width 0.127)
		(layer "In7.Cu")
		(net "SMA3_LED_RED_N")
	)
	(segment
		(start 9.5758 -67.2592)
		(end 9.5758 -67.667632)
		(width 0.11938)
		(layer "F.Cu")
		(net "SMA3_LED_GREEN_N")
	)
	(segment
		(start 99.975924 -102.896924)
		(end 98.679 -101.6)
		(width 0.11938)
		(layer "F.Cu")
		(net "SMA3_LED_GREEN_N")
	)
	(segment
		(start 102.80396 -102.896924)
		(end 99.975924 -102.896924)
		(width 0.11938)
		(layer "F.Cu")
		(net "SMA3_LED_GREEN_N")
	)
	(segment
		(start 10.287 -66.548)
		(end 9.5758 -67.2592)
		(width 0.11938)
		(layer "F.Cu")
		(net "SMA3_LED_GREEN_N")
	)
	(via
		(at 10.287 -66.548)
		(size 0.508)
		(drill 0.254)
		(layers "F.Cu" "B.Cu")
		(net "SMA3_LED_GREEN_N")
	)
	(via
		(at 98.679 -101.6)
		(size 0.4572)
		(drill 0.2032)
		(layers "F.Cu" "B.Cu")
		(net "SMA3_LED_GREEN_N")
	)
	(segment
		(start 98.425 -101.6)
		(end 94.107 -97.282)
		(width 0.127)
		(layer "In7.Cu")
		(net "SMA3_LED_GREEN_N")
	)
	(segment
		(start 57.404 -91.313)
		(end 51.689 -91.313)
		(width 0.127)
		(layer "In7.Cu")
		(net "SMA3_LED_GREEN_N")
	)
	(segment
		(start 48.895 -80.548988)
		(end 43.657012 -75.311)
		(width 0.127)
		(layer "In7.Cu")
		(net "SMA3_LED_GREEN_N")
	)
	(segment
		(start 22.637242 -73.939908)
		(end 21.408898 -73.939908)
		(width 0.127)
		(layer "In7.Cu")
		(net "SMA3_LED_GREEN_N")
	)
	(segment
		(start 35.41903 -74.8665)
		(end 35.02533 -75.2602)
		(width 0.127)
		(layer "In7.Cu")
		(net "SMA3_LED_GREEN_N")
	)
	(segment
		(start 88.838024 -90.678)
		(end 58.039 -90.678)
		(width 0.127)
		(layer "In7.Cu")
		(net "SMA3_LED_GREEN_N")
	)
	(segment
		(start 48.895 -88.519)
		(end 48.895 -80.548988)
		(width 0.127)
		(layer "In7.Cu")
		(net "SMA3_LED_GREEN_N")
	)
	(segment
		(start 35.02533 -75.2602)
		(end 29.73451 -75.2602)
		(width 0.127)
		(layer "In7.Cu")
		(net "SMA3_LED_GREEN_N")
	)
	(segment
		(start 15.046198 -71.247)
		(end 13.081 -71.247)
		(width 0.127)
		(layer "In7.Cu")
		(net "SMA3_LED_GREEN_N")
	)
	(segment
		(start 20.91309 -73.4441)
		(end 18.360136 -73.4441)
		(width 0.127)
		(layer "In7.Cu")
		(net "SMA3_LED_GREEN_N")
	)
	(segment
		(start 13.081 -71.247)
		(end 9.906 -68.072)
		(width 0.127)
		(layer "In7.Cu")
		(net "SMA3_LED_GREEN_N")
	)
	(segment
		(start 23.500334 -74.803)
		(end 22.637242 -73.939908)
		(width 0.127)
		(layer "In7.Cu")
		(net "SMA3_LED_GREEN_N")
	)
	(segment
		(start 9.906 -66.929)
		(end 10.287 -66.548)
		(width 0.127)
		(layer "In7.Cu")
		(net "SMA3_LED_GREEN_N")
	)
	(segment
		(start 29.73451 -75.2602)
		(end 29.27731 -74.803)
		(width 0.127)
		(layer "In7.Cu")
		(net "SMA3_LED_GREEN_N")
	)
	(segment
		(start 35.92703 -74.8665)
		(end 35.41903 -74.8665)
		(width 0.127)
		(layer "In7.Cu")
		(net "SMA3_LED_GREEN_N")
	)
	(segment
		(start 18.360136 -73.4441)
		(end 17.750536 -72.8345)
		(width 0.127)
		(layer "In7.Cu")
		(net "SMA3_LED_GREEN_N")
	)
	(segment
		(start 21.408898 -73.939908)
		(end 20.91309 -73.4441)
		(width 0.127)
		(layer "In7.Cu")
		(net "SMA3_LED_GREEN_N")
	)
	(segment
		(start 51.689 -91.313)
		(end 48.895 -88.519)
		(width 0.127)
		(layer "In7.Cu")
		(net "SMA3_LED_GREEN_N")
	)
	(segment
		(start 29.27731 -74.803)
		(end 23.500334 -74.803)
		(width 0.127)
		(layer "In7.Cu")
		(net "SMA3_LED_GREEN_N")
	)
	(segment
		(start 94.107 -95.946976)
		(end 88.838024 -90.678)
		(width 0.127)
		(layer "In7.Cu")
		(net "SMA3_LED_GREEN_N")
	)
	(segment
		(start 40.965882 -75.311)
		(end 40.013382 -74.3585)
		(width 0.127)
		(layer "In7.Cu")
		(net "SMA3_LED_GREEN_N")
	)
	(segment
		(start 94.107 -97.282)
		(end 94.107 -95.946976)
		(width 0.127)
		(layer "In7.Cu")
		(net "SMA3_LED_GREEN_N")
	)
	(segment
		(start 36.43503 -74.3585)
		(end 35.92703 -74.8665)
		(width 0.127)
		(layer "In7.Cu")
		(net "SMA3_LED_GREEN_N")
	)
	(segment
		(start 58.039 -90.678)
		(end 57.404 -91.313)
		(width 0.127)
		(layer "In7.Cu")
		(net "SMA3_LED_GREEN_N")
	)
	(segment
		(start 40.013382 -74.3585)
		(end 36.43503 -74.3585)
		(width 0.127)
		(layer "In7.Cu")
		(net "SMA3_LED_GREEN_N")
	)
	(segment
		(start 17.750536 -72.8345)
		(end 16.633698 -72.8345)
		(width 0.127)
		(layer "In7.Cu")
		(net "SMA3_LED_GREEN_N")
	)
	(segment
		(start 16.633698 -72.8345)
		(end 15.046198 -71.247)
		(width 0.127)
		(layer "In7.Cu")
		(net "SMA3_LED_GREEN_N")
	)
	(segment
		(start 98.679 -101.6)
		(end 98.425 -101.6)
		(width 0.127)
		(layer "In7.Cu")
		(net "SMA3_LED_GREEN_N")
	)
	(segment
		(start 9.906 -68.072)
		(end 9.906 -66.929)
		(width 0.127)
		(layer "In7.Cu")
		(net "SMA3_LED_GREEN_N")
	)
	(segment
		(start 43.657012 -75.311)
		(end 40.965882 -75.311)
		(width 0.127)
		(layer "In7.Cu")
		(net "SMA3_LED_GREEN_N")
	)
	(segment
		(start 4.826 -66.675)
		(end 5.0038 -66.8528)
		(width 0.11938)
		(layer "F.Cu")
		(net "SMA3_LED_BLUE_N")
	)
	(segment
		(start 5.0038 -66.8528)
		(end 5.0038 -67.667632)
		(width 0.11938)
		(layer "F.Cu")
		(net "SMA3_LED_BLUE_N")
	)
	(segment
		(start 102.84206 -101.896926)
		(end 101.515926 -101.896926)
		(width 0.11938)
		(layer "F.Cu")
		(net "SMA3_LED_BLUE_N")
	)
	(segment
		(start 101.515926 -101.896926)
		(end 101.219 -101.6)
		(width 0.11938)
		(layer "F.Cu")
		(net "SMA3_LED_BLUE_N")
	)
	(via
		(at 4.826 -66.675)
		(size 0.508)
		(drill 0.254)
		(layers "F.Cu" "B.Cu")
		(net "SMA3_LED_BLUE_N")
	)
	(via
		(at 101.219 -101.6)
		(size 0.4572)
		(drill 0.2032)
		(layers "F.Cu" "B.Cu")
		(net "SMA3_LED_BLUE_N")
	)
	(segment
		(start 29.418534 -76.0222)
		(end 28.961334 -75.565)
		(width 0.127)
		(layer "In7.Cu")
		(net "SMA3_LED_BLUE_N")
	)
	(segment
		(start 100.203 -102.616)
		(end 98.267266 -102.616)
		(width 0.127)
		(layer "In7.Cu")
		(net "SMA3_LED_BLUE_N")
	)
	(segment
		(start 15.130018 -74.7395)
		(end 8.208518 -67.818)
		(width 0.127)
		(layer "In7.Cu")
		(net "SMA3_LED_BLUE_N")
	)
	(segment
		(start 51.308 -92.456)
		(end 46.99 -88.138)
		(width 0.127)
		(layer "In7.Cu")
		(net "SMA3_LED_BLUE_N")
	)
	(segment
		(start 93.218 -96.220534)
		(end 89.453466 -92.456)
		(width 0.127)
		(layer "In7.Cu")
		(net "SMA3_LED_BLUE_N")
	)
	(segment
		(start 4.828032 -66.677032)
		(end 4.826 -66.675)
		(width 0.127)
		(layer "In7.Cu")
		(net "SMA3_LED_BLUE_N")
	)
	(segment
		(start 24.29256 -76.6445)
		(end 23.71344 -76.6445)
		(width 0.127)
		(layer "In7.Cu")
		(net "SMA3_LED_BLUE_N")
	)
	(segment
		(start 93.218 -97.566734)
		(end 93.218 -96.220534)
		(width 0.127)
		(layer "In7.Cu")
		(net "SMA3_LED_BLUE_N")
	)
	(segment
		(start 40.064182 -75.9079)
		(end 39.357046 -75.9079)
		(width 0.127)
		(layer "In7.Cu")
		(net "SMA3_LED_BLUE_N")
	)
	(segment
		(start 23.71344 -76.6445)
		(end 23.62454 -76.5556)
		(width 0.127)
		(layer "In7.Cu")
		(net "SMA3_LED_BLUE_N")
	)
	(segment
		(start 83.82 -92.456)
		(end 82.931 -91.567)
		(width 0.127)
		(layer "In7.Cu")
		(net "SMA3_LED_BLUE_N")
	)
	(segment
		(start 21.93544 -75.7555)
		(end 21.23694 -75.057)
		(width 0.127)
		(layer "In7.Cu")
		(net "SMA3_LED_BLUE_N")
	)
	(segment
		(start 33.1216 -76.6064)
		(end 32.5374 -76.0222)
		(width 0.127)
		(layer "In7.Cu")
		(net "SMA3_LED_BLUE_N")
	)
	(segment
		(start 98.267266 -102.616)
		(end 93.218 -97.566734)
		(width 0.127)
		(layer "In7.Cu")
		(net "SMA3_LED_BLUE_N")
	)
	(segment
		(start 23.599648 -76.5556)
		(end 22.799548 -75.7555)
		(width 0.127)
		(layer "In7.Cu")
		(net "SMA3_LED_BLUE_N")
	)
	(segment
		(start 21.23694 -75.057)
		(end 19.431 -75.057)
		(width 0.127)
		(layer "In7.Cu")
		(net "SMA3_LED_BLUE_N")
	)
	(segment
		(start 46.99 -88.138)
		(end 46.99 -82.833718)
		(width 0.127)
		(layer "In7.Cu")
		(net "SMA3_LED_BLUE_N")
	)
	(segment
		(start 38.658546 -76.6064)
		(end 33.1216 -76.6064)
		(width 0.127)
		(layer "In7.Cu")
		(net "SMA3_LED_BLUE_N")
	)
	(segment
		(start 39.357046 -75.9079)
		(end 38.658546 -76.6064)
		(width 0.127)
		(layer "In7.Cu")
		(net "SMA3_LED_BLUE_N")
	)
	(segment
		(start 23.62454 -76.5556)
		(end 23.599648 -76.5556)
		(width 0.127)
		(layer "In7.Cu")
		(net "SMA3_LED_BLUE_N")
	)
	(segment
		(start 19.431 -75.057)
		(end 18.923 -74.549)
		(width 0.127)
		(layer "In7.Cu")
		(net "SMA3_LED_BLUE_N")
	)
	(segment
		(start 32.5374 -76.0222)
		(end 29.418534 -76.0222)
		(width 0.127)
		(layer "In7.Cu")
		(net "SMA3_LED_BLUE_N")
	)
	(segment
		(start 16.44396 -74.7395)
		(end 15.130018 -74.7395)
		(width 0.127)
		(layer "In7.Cu")
		(net "SMA3_LED_BLUE_N")
	)
	(segment
		(start 46.99 -82.833718)
		(end 40.064182 -75.9079)
		(width 0.127)
		(layer "In7.Cu")
		(net "SMA3_LED_BLUE_N")
	)
	(segment
		(start 22.799548 -75.7555)
		(end 21.93544 -75.7555)
		(width 0.127)
		(layer "In7.Cu")
		(net "SMA3_LED_BLUE_N")
	)
	(segment
		(start 101.219 -101.6)
		(end 100.203 -102.616)
		(width 0.127)
		(layer "In7.Cu")
		(net "SMA3_LED_BLUE_N")
	)
	(segment
		(start 18.923 -74.549)
		(end 16.63446 -74.549)
		(width 0.127)
		(layer "In7.Cu")
		(net "SMA3_LED_BLUE_N")
	)
	(segment
		(start 57.338976 -92.456)
		(end 51.308 -92.456)
		(width 0.127)
		(layer "In7.Cu")
		(net "SMA3_LED_BLUE_N")
	)
	(segment
		(start 5.082032 -66.677032)
		(end 4.828032 -66.677032)
		(width 0.127)
		(layer "In7.Cu")
		(net "SMA3_LED_BLUE_N")
	)
	(segment
		(start 8.208518 -67.818)
		(end 6.223 -67.818)
		(width 0.127)
		(layer "In7.Cu")
		(net "SMA3_LED_BLUE_N")
	)
	(segment
		(start 82.931 -91.567)
		(end 58.227976 -91.567)
		(width 0.127)
		(layer "In7.Cu")
		(net "SMA3_LED_BLUE_N")
	)
	(segment
		(start 58.227976 -91.567)
		(end 57.338976 -92.456)
		(width 0.127)
		(layer "In7.Cu")
		(net "SMA3_LED_BLUE_N")
	)
	(segment
		(start 28.961334 -75.565)
		(end 25.37206 -75.565)
		(width 0.127)
		(layer "In7.Cu")
		(net "SMA3_LED_BLUE_N")
	)
	(segment
		(start 25.37206 -75.565)
		(end 24.29256 -76.6445)
		(width 0.127)
		(layer "In7.Cu")
		(net "SMA3_LED_BLUE_N")
	)
	(segment
		(start 89.453466 -92.456)
		(end 83.82 -92.456)
		(width 0.127)
		(layer "In7.Cu")
		(net "SMA3_LED_BLUE_N")
	)
	(segment
		(start 16.63446 -74.549)
		(end 16.44396 -74.7395)
		(width 0.127)
		(layer "In7.Cu")
		(net "SMA3_LED_BLUE_N")
	)
	(segment
		(start 6.223 -67.818)
		(end 5.082032 -66.677032)
		(width 0.127)
		(layer "In7.Cu")
		(net "SMA3_LED_BLUE_N")
	)
	(segment
		(start 15.752318 -50.677318)
		(end 15.748 -50.673)
		(width 0.11938)
		(layer "F.Cu")
		(net "SMA2_SIG_OUT_BF_EN_N")
	)
	(segment
		(start 15.752318 -50.897282)
		(end 15.752318 -50.677318)
		(width 0.11938)
		(layer "F.Cu")
		(net "SMA2_SIG_OUT_BF_EN_N")
	)
	(segment
		(start 14.649704 -49.574704)
		(end 14.649704 -48.790098)
		(width 0.11938)
		(layer "F.Cu")
		(net "SMA2_SIG_OUT_BF_EN_N")
	)
	(segment
		(start 15.748 -50.673)
		(end 14.649704 -49.574704)
		(width 0.11938)
		(layer "F.Cu")
		(net "SMA2_SIG_OUT_BF_EN_N")
	)
	(segment
		(start 14.605 -52.0446)
		(end 15.752318 -50.897282)
		(width 0.11938)
		(layer "F.Cu")
		(net "SMA2_SIG_OUT_BF_EN_N")
	)
	(segment
		(start 109.847126 -45.823124)
		(end 110.346998 -46.322996)
		(width 0.11938)
		(layer "F.Cu")
		(net "SMA2_SIG_OUT_BF_EN_N")
	)
	(via
		(at 19.05 -35.9918)
		(size 0.508)
		(drill 0.254)
		(layers "F.Cu" "B.Cu")
		(net "SMA2_SIG_OUT_BF_EN_N")
	)
	(via
		(at 110.346998 -46.322996)
		(size 0.4572)
		(drill 0.2032)
		(layers "F.Cu" "B.Cu")
		(net "SMA2_SIG_OUT_BF_EN_N")
	)
	(segment
		(start 102.09657 -35.92957)
		(end 101.74097 -35.57397)
		(width 0.127)
		(layer "In2.Cu")
		(net "SMA2_SIG_OUT_BF_EN_N")
	)
	(segment
		(start 104.8004 -37.211)
		(end 104.4448 -36.8554)
		(width 0.127)
		(layer "In2.Cu")
		(net "SMA2_SIG_OUT_BF_EN_N")
	)
	(segment
		(start 104.8004 -37.4904)
		(end 104.8004 -37.211)
		(width 0.127)
		(layer "In2.Cu")
		(net "SMA2_SIG_OUT_BF_EN_N")
	)
	(segment
		(start 98.356928 -34.925)
		(end 97.282 -33.850072)
		(width 0.127)
		(layer "In2.Cu")
		(net "SMA2_SIG_OUT_BF_EN_N")
	)
	(segment
		(start 102.740968 -36.159948)
		(end 102.51059 -35.92957)
		(width 0.127)
		(layer "In2.Cu")
		(net "SMA2_SIG_OUT_BF_EN_N")
	)
	(segment
		(start 97.282 -33.850072)
		(end 97.282 -31.020766)
		(width 0.127)
		(layer "In2.Cu")
		(net "SMA2_SIG_OUT_BF_EN_N")
	)
	(segment
		(start 27.432 -33.655)
		(end 21.3868 -33.655)
		(width 0.127)
		(layer "In2.Cu")
		(net "SMA2_SIG_OUT_BF_EN_N")
	)
	(segment
		(start 108.528358 -38.735)
		(end 108.520992 -38.742366)
		(width 0.127)
		(layer "In2.Cu")
		(net "SMA2_SIG_OUT_BF_EN_N")
	)
	(segment
		(start 94.041722 -27.2415)
		(end 93.662246 -27.2415)
		(width 0.127)
		(layer "In2.Cu")
		(net "SMA2_SIG_OUT_BF_EN_N")
	)
	(segment
		(start 105.8418 -38.488366)
		(end 105.8418 -38.2016)
		(width 0.127)
		(layer "In2.Cu")
		(net "SMA2_SIG_OUT_BF_EN_N")
	)
	(segment
		(start 105.47858 -37.83838)
		(end 105.14838 -37.83838)
		(width 0.127)
		(layer "In2.Cu")
		(net "SMA2_SIG_OUT_BF_EN_N")
	)
	(segment
		(start 92.690188 -26.56586)
		(end 92.690188 -26.269442)
		(width 0.127)
		(layer "In2.Cu")
		(net "SMA2_SIG_OUT_BF_EN_N")
	)
	(segment
		(start 109.474 -45.466)
		(end 109.474 -39.243)
		(width 0.127)
		(layer "In2.Cu")
		(net "SMA2_SIG_OUT_BF_EN_N")
	)
	(segment
		(start 92.690188 -26.269442)
		(end 91.706446 -25.2857)
		(width 0.127)
		(layer "In2.Cu")
		(net "SMA2_SIG_OUT_BF_EN_N")
	)
	(segment
		(start 97.282 -31.020766)
		(end 94.873572 -28.612338)
		(width 0.127)
		(layer "In2.Cu")
		(net "SMA2_SIG_OUT_BF_EN_N")
	)
	(segment
		(start 106.0958 -38.742366)
		(end 105.8418 -38.488366)
		(width 0.127)
		(layer "In2.Cu")
		(net "SMA2_SIG_OUT_BF_EN_N")
	)
	(segment
		(start 94.873572 -28.452826)
		(end 94.37624 -27.955494)
		(width 0.127)
		(layer "In2.Cu")
		(net "SMA2_SIG_OUT_BF_EN_N")
	)
	(segment
		(start 91.706446 -25.2857)
		(end 85.793072 -25.2857)
		(width 0.127)
		(layer "In2.Cu")
		(net "SMA2_SIG_OUT_BF_EN_N")
	)
	(segment
		(start 105.8418 -38.2016)
		(end 105.47858 -37.83838)
		(width 0.127)
		(layer "In2.Cu")
		(net "SMA2_SIG_OUT_BF_EN_N")
	)
	(segment
		(start 102.51059 -35.92957)
		(end 102.09657 -35.92957)
		(width 0.127)
		(layer "In2.Cu")
		(net "SMA2_SIG_OUT_BF_EN_N")
	)
	(segment
		(start 93.32214 -27.197812)
		(end 92.690188 -26.56586)
		(width 0.127)
		(layer "In2.Cu")
		(net "SMA2_SIG_OUT_BF_EN_N")
	)
	(segment
		(start 109.474 -39.243)
		(end 108.966 -38.735)
		(width 0.127)
		(layer "In2.Cu")
		(net "SMA2_SIG_OUT_BF_EN_N")
	)
	(segment
		(start 93.662246 -27.2415)
		(end 93.618558 -27.197812)
		(width 0.127)
		(layer "In2.Cu")
		(net "SMA2_SIG_OUT_BF_EN_N")
	)
	(segment
		(start 101.506274 -34.925)
		(end 98.356928 -34.925)
		(width 0.127)
		(layer "In2.Cu")
		(net "SMA2_SIG_OUT_BF_EN_N")
	)
	(segment
		(start 76.026772 -35.052)
		(end 28.829 -35.052)
		(width 0.127)
		(layer "In2.Cu")
		(net "SMA2_SIG_OUT_BF_EN_N")
	)
	(segment
		(start 105.14838 -37.83838)
		(end 104.8004 -37.4904)
		(width 0.127)
		(layer "In2.Cu")
		(net "SMA2_SIG_OUT_BF_EN_N")
	)
	(segment
		(start 103.022654 -36.8554)
		(end 102.740968 -36.573714)
		(width 0.127)
		(layer "In2.Cu")
		(net "SMA2_SIG_OUT_BF_EN_N")
	)
	(segment
		(start 102.740968 -36.573714)
		(end 102.740968 -36.159948)
		(width 0.127)
		(layer "In2.Cu")
		(net "SMA2_SIG_OUT_BF_EN_N")
	)
	(segment
		(start 101.74097 -35.159696)
		(end 101.506274 -34.925)
		(width 0.127)
		(layer "In2.Cu")
		(net "SMA2_SIG_OUT_BF_EN_N")
	)
	(segment
		(start 94.873572 -28.612338)
		(end 94.873572 -28.452826)
		(width 0.127)
		(layer "In2.Cu")
		(net "SMA2_SIG_OUT_BF_EN_N")
	)
	(segment
		(start 104.4448 -36.8554)
		(end 103.022654 -36.8554)
		(width 0.127)
		(layer "In2.Cu")
		(net "SMA2_SIG_OUT_BF_EN_N")
	)
	(segment
		(start 108.520992 -38.742366)
		(end 106.0958 -38.742366)
		(width 0.127)
		(layer "In2.Cu")
		(net "SMA2_SIG_OUT_BF_EN_N")
	)
	(segment
		(start 93.618558 -27.197812)
		(end 93.32214 -27.197812)
		(width 0.127)
		(layer "In2.Cu")
		(net "SMA2_SIG_OUT_BF_EN_N")
	)
	(segment
		(start 94.37624 -27.955494)
		(end 94.37624 -27.576018)
		(width 0.127)
		(layer "In2.Cu")
		(net "SMA2_SIG_OUT_BF_EN_N")
	)
	(segment
		(start 108.966 -38.735)
		(end 108.528358 -38.735)
		(width 0.127)
		(layer "In2.Cu")
		(net "SMA2_SIG_OUT_BF_EN_N")
	)
	(segment
		(start 101.74097 -35.57397)
		(end 101.74097 -35.159696)
		(width 0.127)
		(layer "In2.Cu")
		(net "SMA2_SIG_OUT_BF_EN_N")
	)
	(segment
		(start 21.3868 -33.655)
		(end 19.05 -35.9918)
		(width 0.127)
		(layer "In2.Cu")
		(net "SMA2_SIG_OUT_BF_EN_N")
	)
	(segment
		(start 28.829 -35.052)
		(end 27.432 -33.655)
		(width 0.127)
		(layer "In2.Cu")
		(net "SMA2_SIG_OUT_BF_EN_N")
	)
	(segment
		(start 85.793072 -25.2857)
		(end 76.026772 -35.052)
		(width 0.127)
		(layer "In2.Cu")
		(net "SMA2_SIG_OUT_BF_EN_N")
	)
	(segment
		(start 110.346998 -46.322996)
		(end 110.330996 -46.322996)
		(width 0.127)
		(layer "In2.Cu")
		(net "SMA2_SIG_OUT_BF_EN_N")
	)
	(segment
		(start 94.37624 -27.576018)
		(end 94.041722 -27.2415)
		(width 0.127)
		(layer "In2.Cu")
		(net "SMA2_SIG_OUT_BF_EN_N")
	)
	(segment
		(start 110.330996 -46.322996)
		(end 109.474 -45.466)
		(width 0.127)
		(layer "In2.Cu")
		(net "SMA2_SIG_OUT_BF_EN_N")
	)
	(segment
		(start 15.748 -47.371)
		(end 15.748 -50.673)
		(width 0.127)
		(layer "In7.Cu")
		(net "SMA2_SIG_OUT_BF_EN_N")
	)
	(segment
		(start 17.907 -37.1348)
		(end 17.907 -45.212)
		(width 0.127)
		(layer "In7.Cu")
		(net "SMA2_SIG_OUT_BF_EN_N")
	)
	(segment
		(start 17.907 -45.212)
		(end 15.748 -47.371)
		(width 0.127)
		(layer "In7.Cu")
		(net "SMA2_SIG_OUT_BF_EN_N")
	)
	(segment
		(start 19.05 -35.9918)
		(end 17.907 -37.1348)
		(width 0.127)
		(layer "In7.Cu")
		(net "SMA2_SIG_OUT_BF_EN_N")
	)
	(segment
		(start 14.1224 -43.1546)
		(end 13.843 -43.434)
		(width 0.11938)
		(layer "F.Cu")
		(net "SMA2_SIG_IN_BF_EN_N")
	)
	(segment
		(start 14.149832 -45.409866)
		(end 14.149832 -43.740832)
		(width 0.11938)
		(layer "F.Cu")
		(net "SMA2_SIG_IN_BF_EN_N")
	)
	(segment
		(start 14.1224 -41.91)
		(end 14.1224 -43.1546)
		(width 0.11938)
		(layer "F.Cu")
		(net "SMA2_SIG_IN_BF_EN_N")
	)
	(segment
		(start 14.149832 -43.740832)
		(end 13.843 -43.434)
		(width 0.11938)
		(layer "F.Cu")
		(net "SMA2_SIG_IN_BF_EN_N")
	)
	(segment
		(start 108.347256 -46.322996)
		(end 108.847128 -45.823124)
		(width 0.11938)
		(layer "F.Cu")
		(net "SMA2_SIG_IN_BF_EN_N")
	)
	(via
		(at 108.347256 -46.322996)
		(size 0.4572)
		(drill 0.2032)
		(layers "F.Cu" "B.Cu")
		(net "SMA2_SIG_IN_BF_EN_N")
	)
	(via
		(at 24.1808 -38.354)
		(size 0.508)
		(drill 0.254)
		(layers "F.Cu" "B.Cu")
		(net "SMA2_SIG_IN_BF_EN_N")
	)
	(segment
		(start 20.701 -37.084)
		(end 16.383 -37.084)
		(width 0.11938)
		(layer "B.Cu")
		(net "SMA2_SIG_IN_BF_EN_N")
	)
	(segment
		(start 22.561804 -36.12769)
		(end 22.231604 -36.45789)
		(width 0.11938)
		(layer "B.Cu")
		(net "SMA2_SIG_IN_BF_EN_N")
	)
	(segment
		(start 24.69769 -36.12769)
		(end 22.561804 -36.12769)
		(width 0.11938)
		(layer "B.Cu")
		(net "SMA2_SIG_IN_BF_EN_N")
	)
	(segment
		(start 25.146 -36.576)
		(end 24.69769 -36.12769)
		(width 0.11938)
		(layer "B.Cu")
		(net "SMA2_SIG_IN_BF_EN_N")
	)
	(segment
		(start 14.57071 -38.093396)
		(end 14.57071 -40.42029)
		(width 0.11938)
		(layer "B.Cu")
		(net "SMA2_SIG_IN_BF_EN_N")
	)
	(segment
		(start 21.32711 -36.45789)
		(end 20.701 -37.084)
		(width 0.11938)
		(layer "B.Cu")
		(net "SMA2_SIG_IN_BF_EN_N")
	)
	(segment
		(start 15.748 -37.719)
		(end 14.945106 -37.719)
		(width 0.11938)
		(layer "B.Cu")
		(net "SMA2_SIG_IN_BF_EN_N")
	)
	(segment
		(start 25.146 -37.3888)
		(end 25.146 -36.576)
		(width 0.11938)
		(layer "B.Cu")
		(net "SMA2_SIG_IN_BF_EN_N")
	)
	(segment
		(start 22.231604 -36.45789)
		(end 21.32711 -36.45789)
		(width 0.11938)
		(layer "B.Cu")
		(net "SMA2_SIG_IN_BF_EN_N")
	)
	(segment
		(start 16.383 -37.084)
		(end 15.748 -37.719)
		(width 0.11938)
		(layer "B.Cu")
		(net "SMA2_SIG_IN_BF_EN_N")
	)
	(segment
		(start 13.843 -41.148)
		(end 13.843 -43.434)
		(width 0.11938)
		(layer "B.Cu")
		(net "SMA2_SIG_IN_BF_EN_N")
	)
	(segment
		(start 24.1808 -38.354)
		(end 25.146 -37.3888)
		(width 0.11938)
		(layer "B.Cu")
		(net "SMA2_SIG_IN_BF_EN_N")
	)
	(segment
		(start 14.945106 -37.719)
		(end 14.57071 -38.093396)
		(width 0.11938)
		(layer "B.Cu")
		(net "SMA2_SIG_IN_BF_EN_N")
	)
	(segment
		(start 14.57071 -40.42029)
		(end 13.843 -41.148)
		(width 0.11938)
		(layer "B.Cu")
		(net "SMA2_SIG_IN_BF_EN_N")
	)
	(segment
		(start 67.818 -45.974)
		(end 60.198 -38.354)
		(width 0.127)
		(layer "In7.Cu")
		(net "SMA2_SIG_IN_BF_EN_N")
	)
	(segment
		(start 107.737656 -45.713396)
		(end 98.24974 -45.713396)
		(width 0.1016)
		(layer "In7.Cu")
		(net "SMA2_SIG_IN_BF_EN_N")
	)
	(segment
		(start 60.198 -38.354)
		(end 24.1808 -38.354)
		(width 0.127)
		(layer "In7.Cu")
		(net "SMA2_SIG_IN_BF_EN_N")
	)
	(segment
		(start 90.599514 -49.862486)
		(end 89.9541 -50.5079)
		(width 0.127)
		(layer "In7.Cu")
		(net "SMA2_SIG_IN_BF_EN_N")
	)
	(segment
		(start 97.04959 -45.80636)
		(end 92.993464 -49.862486)
		(width 0.127)
		(layer "In7.Cu")
		(net "SMA2_SIG_IN_BF_EN_N")
	)
	(segment
		(start 98.24974 -45.713396)
		(end 98.156776 -45.80636)
		(width 0.127)
		(layer "In7.Cu")
		(net "SMA2_SIG_IN_BF_EN_N")
	)
	(segment
		(start 68.453 -51.181)
		(end 67.818 -50.546)
		(width 0.127)
		(layer "In7.Cu")
		(net "SMA2_SIG_IN_BF_EN_N")
	)
	(segment
		(start 79.188564 -50.1015)
		(end 75.7555 -50.1015)
		(width 0.127)
		(layer "In7.Cu")
		(net "SMA2_SIG_IN_BF_EN_N")
	)
	(segment
		(start 79.594964 -50.5079)
		(end 79.188564 -50.1015)
		(width 0.127)
		(layer "In7.Cu")
		(net "SMA2_SIG_IN_BF_EN_N")
	)
	(segment
		(start 67.818 -50.546)
		(end 67.818 -45.974)
		(width 0.127)
		(layer "In7.Cu")
		(net "SMA2_SIG_IN_BF_EN_N")
	)
	(segment
		(start 92.993464 -49.862486)
		(end 90.599514 -49.862486)
		(width 0.127)
		(layer "In7.Cu")
		(net "SMA2_SIG_IN_BF_EN_N")
	)
	(segment
		(start 98.156776 -45.80636)
		(end 97.04959 -45.80636)
		(width 0.127)
		(layer "In7.Cu")
		(net "SMA2_SIG_IN_BF_EN_N")
	)
	(segment
		(start 74.676 -51.181)
		(end 68.453 -51.181)
		(width 0.127)
		(layer "In7.Cu")
		(net "SMA2_SIG_IN_BF_EN_N")
	)
	(segment
		(start 75.7555 -50.1015)
		(end 74.676 -51.181)
		(width 0.127)
		(layer "In7.Cu")
		(net "SMA2_SIG_IN_BF_EN_N")
	)
	(segment
		(start 89.9541 -50.5079)
		(end 79.594964 -50.5079)
		(width 0.127)
		(layer "In7.Cu")
		(net "SMA2_SIG_IN_BF_EN_N")
	)
	(segment
		(start 108.347256 -46.322996)
		(end 107.737656 -45.713396)
		(width 0.1016)
		(layer "In7.Cu")
		(net "SMA2_SIG_IN_BF_EN_N")
	)
	(segment
		(start 104.138222 -105.537)
		(end 104.257602 -105.41762)
		(width 0.11938)
		(layer "F.Cu")
		(net "SMA2_LED_RED_N")
	)
	(segment
		(start 101.092 -106.299)
		(end 101.854 -105.537)
		(width 0.11938)
		(layer "F.Cu")
		(net "SMA2_LED_RED_N")
	)
	(segment
		(start 20.8534 -30.48)
		(end 22.098 -30.48)
		(width 0.11938)
		(layer "F.Cu")
		(net "SMA2_LED_RED_N")
	)
	(segment
		(start 101.854 -105.537)
		(end 104.138222 -105.537)
		(width 0.11938)
		(layer "F.Cu")
		(net "SMA2_LED_RED_N")
	)
	(segment
		(start 104.257602 -105.41762)
		(end 104.257602 -103.81234)
		(width 0.11938)
		(layer "F.Cu")
		(net "SMA2_LED_RED_N")
	)
	(via
		(at 101.092 -106.299)
		(size 0.4572)
		(drill 0.2032)
		(layers "F.Cu" "B.Cu")
		(net "SMA2_LED_RED_N")
	)
	(via
		(at 10.541 -32.385)
		(size 0.508)
		(drill 0.254)
		(layers "F.Cu" "B.Cu")
		(net "SMA2_LED_RED_N")
	)
	(via
		(at 19.19732 -106.427016)
		(size 0.4572)
		(drill 0.2032)
		(layers "F.Cu" "B.Cu")
		(net "SMA2_LED_RED_N")
	)
	(via
		(at 22.098 -30.48)
		(size 0.508)
		(drill 0.254)
		(layers "F.Cu" "B.Cu")
		(net "SMA2_LED_RED_N")
	)
	(segment
		(start 84.074 -94.488)
		(end 83.439 -93.853)
		(width 0.11938)
		(layer "B.Cu")
		(net "SMA2_LED_RED_N")
	)
	(segment
		(start 19.19732 -106.95432)
		(end 19.19732 -106.427016)
		(width 0.11938)
		(layer "B.Cu")
		(net "SMA2_LED_RED_N")
	)
	(segment
		(start 71.929752 -107.394248)
		(end 70.485 -108.839)
		(width 0.11938)
		(layer "B.Cu")
		(net "SMA2_LED_RED_N")
	)
	(segment
		(start 83.439 -93.853)
		(end 82.55 -93.853)
		(width 0.11938)
		(layer "B.Cu")
		(net "SMA2_LED_RED_N")
	)
	(segment
		(start 16.216122 -31.115)
		(end 16.641572 -31.54045)
		(width 0.11938)
		(layer "B.Cu")
		(net "SMA2_LED_RED_N")
	)
	(segment
		(start 15.113 -31.115)
		(end 16.216122 -31.115)
		(width 0.11938)
		(layer "B.Cu")
		(net "SMA2_LED_RED_N")
	)
	(segment
		(start 81.534 -92.837)
		(end 73.487788 -92.837)
		(width 0.11938)
		(layer "B.Cu")
		(net "SMA2_LED_RED_N")
	)
	(segment
		(start 21.082 -108.839)
		(end 19.19732 -106.95432)
		(width 0.11938)
		(layer "B.Cu")
		(net "SMA2_LED_RED_N")
	)
	(segment
		(start 92.837 -96.8502)
		(end 90.4748 -94.488)
		(width 0.11938)
		(layer "B.Cu")
		(net "SMA2_LED_RED_N")
	)
	(segment
		(start 73.487788 -92.837)
		(end 71.929752 -94.395036)
		(width 0.11938)
		(layer "B.Cu")
		(net "SMA2_LED_RED_N")
	)
	(segment
		(start 10.541 -32.385)
		(end 10.541 -31.75)
		(width 0.11938)
		(layer "B.Cu")
		(net "SMA2_LED_RED_N")
	)
	(segment
		(start 82.55 -93.853)
		(end 81.534 -92.837)
		(width 0.11938)
		(layer "B.Cu")
		(net "SMA2_LED_RED_N")
	)
	(segment
		(start 16.641572 -31.54045)
		(end 19.152616 -31.54045)
		(width 0.11938)
		(layer "B.Cu")
		(net "SMA2_LED_RED_N")
	)
	(segment
		(start 19.152616 -31.54045)
		(end 20.213066 -30.48)
		(width 0.11938)
		(layer "B.Cu")
		(net "SMA2_LED_RED_N")
	)
	(segment
		(start 71.929752 -94.395036)
		(end 71.929752 -107.394248)
		(width 0.11938)
		(layer "B.Cu")
		(net "SMA2_LED_RED_N")
	)
	(segment
		(start 10.541 -31.75)
		(end 11.83386 -30.45714)
		(width 0.11938)
		(layer "B.Cu")
		(net "SMA2_LED_RED_N")
	)
	(segment
		(start 70.485 -108.839)
		(end 21.082 -108.839)
		(width 0.11938)
		(layer "B.Cu")
		(net "SMA2_LED_RED_N")
	)
	(segment
		(start 101.092 -106.299)
		(end 100.457 -106.934)
		(width 0.11938)
		(layer "B.Cu")
		(net "SMA2_LED_RED_N")
	)
	(segment
		(start 13.359638 -30.45714)
		(end 13.546328 -30.64383)
		(width 0.11938)
		(layer "B.Cu")
		(net "SMA2_LED_RED_N")
	)
	(segment
		(start 20.213066 -30.48)
		(end 22.098 -30.48)
		(width 0.11938)
		(layer "B.Cu")
		(net "SMA2_LED_RED_N")
	)
	(segment
		(start 100.457 -106.934)
		(end 99.186746 -106.934)
		(width 0.11938)
		(layer "B.Cu")
		(net "SMA2_LED_RED_N")
	)
	(segment
		(start 90.4748 -94.488)
		(end 84.074 -94.488)
		(width 0.11938)
		(layer "B.Cu")
		(net "SMA2_LED_RED_N")
	)
	(segment
		(start 13.546328 -30.64383)
		(end 14.64183 -30.64383)
		(width 0.11938)
		(layer "B.Cu")
		(net "SMA2_LED_RED_N")
	)
	(segment
		(start 92.837 -100.584254)
		(end 92.837 -96.8502)
		(width 0.11938)
		(layer "B.Cu")
		(net "SMA2_LED_RED_N")
	)
	(segment
		(start 11.83386 -30.45714)
		(end 13.359638 -30.45714)
		(width 0.11938)
		(layer "B.Cu")
		(net "SMA2_LED_RED_N")
	)
	(segment
		(start 14.64183 -30.64383)
		(end 15.113 -31.115)
		(width 0.11938)
		(layer "B.Cu")
		(net "SMA2_LED_RED_N")
	)
	(segment
		(start 99.186746 -106.934)
		(end 92.837 -100.584254)
		(width 0.11938)
		(layer "B.Cu")
		(net "SMA2_LED_RED_N")
	)
	(segment
		(start 11.43 -68.50253)
		(end 5.1689 -74.76363)
		(width 0.127)
		(layer "In2.Cu")
		(net "SMA2_LED_RED_N")
	)
	(segment
		(start 11.43 -51.308)
		(end 10.668 -52.07)
		(width 0.127)
		(layer "In2.Cu")
		(net "SMA2_LED_RED_N")
	)
	(segment
		(start 5.2578 -79.45247)
		(end 5.2578 -82.3722)
		(width 0.127)
		(layer "In2.Cu")
		(net "SMA2_LED_RED_N")
	)
	(segment
		(start 10.668 -58.42)
		(end 11.938 -59.69)
		(width 0.127)
		(layer "In2.Cu")
		(net "SMA2_LED_RED_N")
	)
	(segment
		(start 11.557 -39.751)
		(end 12.446 -40.64)
		(width 0.127)
		(layer "In2.Cu")
		(net "SMA2_LED_RED_N")
	)
	(segment
		(start 5.2578 -82.3722)
		(end 3.683 -83.947)
		(width 0.127)
		(layer "In2.Cu")
		(net "SMA2_LED_RED_N")
	)
	(segment
		(start 3.683 -88.869012)
		(end 4.983988 -90.17)
		(width 0.127)
		(layer "In2.Cu")
		(net "SMA2_LED_RED_N")
	)
	(segment
		(start 12.954 -65.151)
		(end 11.684 -66.421)
		(width 0.127)
		(layer "In2.Cu")
		(net "SMA2_LED_RED_N")
	)
	(segment
		(start 13.1572 -94.1832)
		(end 13.1572 -105.159048)
		(width 0.127)
		(layer "In2.Cu")
		(net "SMA2_LED_RED_N")
	)
	(segment
		(start 10.668 -52.07)
		(end 10.668 -58.42)
		(width 0.127)
		(layer "In2.Cu")
		(net "SMA2_LED_RED_N")
	)
	(segment
		(start 4.983988 -90.17)
		(end 9.144 -90.17)
		(width 0.127)
		(layer "In2.Cu")
		(net "SMA2_LED_RED_N")
	)
	(segment
		(start 18.436336 -107.188)
		(end 19.19732 -106.427016)
		(width 0.127)
		(layer "In2.Cu")
		(net "SMA2_LED_RED_N")
	)
	(segment
		(start 5.1689 -79.36357)
		(end 5.2578 -79.45247)
		(width 0.127)
		(layer "In2.Cu")
		(net "SMA2_LED_RED_N")
	)
	(segment
		(start 11.089386 -36.616386)
		(end 11.557 -37.084)
		(width 0.127)
		(layer "In2.Cu")
		(net "SMA2_LED_RED_N")
	)
	(segment
		(start 12.446 -48.641)
		(end 11.43 -49.657)
		(width 0.127)
		(layer "In2.Cu")
		(net "SMA2_LED_RED_N")
	)
	(segment
		(start 13.1572 -105.159048)
		(end 15.186152 -107.188)
		(width 0.127)
		(layer "In2.Cu")
		(net "SMA2_LED_RED_N")
	)
	(segment
		(start 10.541 -32.385)
		(end 10.541 -32.892746)
		(width 0.127)
		(layer "In2.Cu")
		(net "SMA2_LED_RED_N")
	)
	(segment
		(start 12.954 -63.881254)
		(end 12.954 -65.151)
		(width 0.127)
		(layer "In2.Cu")
		(net "SMA2_LED_RED_N")
	)
	(segment
		(start 11.43 -49.657)
		(end 11.43 -51.308)
		(width 0.127)
		(layer "In2.Cu")
		(net "SMA2_LED_RED_N")
	)
	(segment
		(start 9.144 -90.17)
		(end 13.1572 -94.1832)
		(width 0.127)
		(layer "In2.Cu")
		(net "SMA2_LED_RED_N")
	)
	(segment
		(start 11.684 -66.421)
		(end 11.684 -67.117722)
		(width 0.127)
		(layer "In2.Cu")
		(net "SMA2_LED_RED_N")
	)
	(segment
		(start 15.186152 -107.188)
		(end 18.436336 -107.188)
		(width 0.127)
		(layer "In2.Cu")
		(net "SMA2_LED_RED_N")
	)
	(segment
		(start 12.446 -40.64)
		(end 12.446 -48.641)
		(width 0.127)
		(layer "In2.Cu")
		(net "SMA2_LED_RED_N")
	)
	(segment
		(start 11.938 -62.865254)
		(end 12.954 -63.881254)
		(width 0.127)
		(layer "In2.Cu")
		(net "SMA2_LED_RED_N")
	)
	(segment
		(start 5.1689 -74.76363)
		(end 5.1689 -79.36357)
		(width 0.127)
		(layer "In2.Cu")
		(net "SMA2_LED_RED_N")
	)
	(segment
		(start 10.541 -32.892746)
		(end 11.089386 -33.441132)
		(width 0.127)
		(layer "In2.Cu")
		(net "SMA2_LED_RED_N")
	)
	(segment
		(start 11.089386 -33.441132)
		(end 11.089386 -36.616386)
		(width 0.127)
		(layer "In2.Cu")
		(net "SMA2_LED_RED_N")
	)
	(segment
		(start 11.557 -37.084)
		(end 11.557 -39.751)
		(width 0.127)
		(layer "In2.Cu")
		(net "SMA2_LED_RED_N")
	)
	(segment
		(start 11.938 -59.69)
		(end 11.938 -62.865254)
		(width 0.127)
		(layer "In2.Cu")
		(net "SMA2_LED_RED_N")
	)
	(segment
		(start 3.683 -83.947)
		(end 3.683 -88.869012)
		(width 0.127)
		(layer "In2.Cu")
		(net "SMA2_LED_RED_N")
	)
	(segment
		(start 11.684 -67.117722)
		(end 11.43 -67.371722)
		(width 0.127)
		(layer "In2.Cu")
		(net "SMA2_LED_RED_N")
	)
	(segment
		(start 11.43 -67.371722)
		(end 11.43 -68.50253)
		(width 0.127)
		(layer "In2.Cu")
		(net "SMA2_LED_RED_N")
	)
	(segment
		(start 104.757474 -105.681526)
		(end 104.757474 -103.81234)
		(width 0.11938)
		(layer "F.Cu")
		(net "SMA2_LED_GREEN_N")
	)
	(segment
		(start 102.362 -106.299)
		(end 104.14 -106.299)
		(width 0.11938)
		(layer "F.Cu")
		(net "SMA2_LED_GREEN_N")
	)
	(segment
		(start 20.8534 -33.02)
		(end 22.098 -33.02)
		(width 0.11938)
		(layer "F.Cu")
		(net "SMA2_LED_GREEN_N")
	)
	(segment
		(start 104.14 -106.299)
		(end 104.757474 -105.681526)
		(width 0.11938)
		(layer "F.Cu")
		(net "SMA2_LED_GREEN_N")
	)
	(via
		(at 22.098 -33.02)
		(size 0.508)
		(drill 0.254)
		(layers "F.Cu" "B.Cu")
		(net "SMA2_LED_GREEN_N")
	)
	(via
		(at 11.811 -33.782)
		(size 0.508)
		(drill 0.254)
		(layers "F.Cu" "B.Cu")
		(net "SMA2_LED_GREEN_N")
	)
	(via
		(at 102.362 -106.299)
		(size 0.4572)
		(drill 0.2032)
		(layers "F.Cu" "B.Cu")
		(net "SMA2_LED_GREEN_N")
	)
	(via
		(at 17.907 -106.426)
		(size 0.4572)
		(drill 0.2032)
		(layers "F.Cu" "B.Cu")
		(net "SMA2_LED_GREEN_N")
	)
	(segment
		(start 19.812 -33.02)
		(end 19.05 -33.782)
		(width 0.11938)
		(layer "B.Cu")
		(net "SMA2_LED_GREEN_N")
	)
	(segment
		(start 90.0684 -94.869)
		(end 83.819746 -94.869)
		(width 0.11938)
		(layer "B.Cu")
		(net "SMA2_LED_GREEN_N")
	)
	(segment
		(start 101.346 -107.315)
		(end 98.933 -107.315)
		(width 0.11938)
		(layer "B.Cu")
		(net "SMA2_LED_GREEN_N")
	)
	(segment
		(start 73.742296 -93.218)
		(end 72.379078 -94.581218)
		(width 0.11938)
		(layer "B.Cu")
		(net "SMA2_LED_GREEN_N")
	)
	(segment
		(start 81.386934 -93.218)
		(end 73.742296 -93.218)
		(width 0.11938)
		(layer "B.Cu")
		(net "SMA2_LED_GREEN_N")
	)
	(segment
		(start 15.855696 -33.528)
		(end 13.589254 -33.528)
		(width 0.11938)
		(layer "B.Cu")
		(net "SMA2_LED_GREEN_N")
	)
	(segment
		(start 70.866 -109.22)
		(end 20.7264 -109.22)
		(width 0.11938)
		(layer "B.Cu")
		(net "SMA2_LED_GREEN_N")
	)
	(segment
		(start 92.329 -97.1296)
		(end 90.0684 -94.869)
		(width 0.11938)
		(layer "B.Cu")
		(net "SMA2_LED_GREEN_N")
	)
	(segment
		(start 19.05 -33.782)
		(end 16.109696 -33.782)
		(width 0.11938)
		(layer "B.Cu")
		(net "SMA2_LED_GREEN_N")
	)
	(segment
		(start 72.379078 -107.706922)
		(end 70.866 -109.22)
		(width 0.11938)
		(layer "B.Cu")
		(net "SMA2_LED_GREEN_N")
	)
	(segment
		(start 13.335254 -33.782)
		(end 11.811 -33.782)
		(width 0.11938)
		(layer "B.Cu")
		(net "SMA2_LED_GREEN_N")
	)
	(segment
		(start 83.819746 -94.869)
		(end 83.184746 -94.234)
		(width 0.11938)
		(layer "B.Cu")
		(net "SMA2_LED_GREEN_N")
	)
	(segment
		(start 98.933 -107.315)
		(end 92.329 -100.711)
		(width 0.11938)
		(layer "B.Cu")
		(net "SMA2_LED_GREEN_N")
	)
	(segment
		(start 13.589254 -33.528)
		(end 13.335254 -33.782)
		(width 0.11938)
		(layer "B.Cu")
		(net "SMA2_LED_GREEN_N")
	)
	(segment
		(start 102.362 -106.299)
		(end 101.346 -107.315)
		(width 0.11938)
		(layer "B.Cu")
		(net "SMA2_LED_GREEN_N")
	)
	(segment
		(start 16.109696 -33.782)
		(end 15.855696 -33.528)
		(width 0.11938)
		(layer "B.Cu")
		(net "SMA2_LED_GREEN_N")
	)
	(segment
		(start 17.9324 -106.426)
		(end 17.907 -106.426)
		(width 0.11938)
		(layer "B.Cu")
		(net "SMA2_LED_GREEN_N")
	)
	(segment
		(start 82.402934 -94.234)
		(end 81.386934 -93.218)
		(width 0.11938)
		(layer "B.Cu")
		(net "SMA2_LED_GREEN_N")
	)
	(segment
		(start 92.329 -100.711)
		(end 92.329 -97.1296)
		(width 0.11938)
		(layer "B.Cu")
		(net "SMA2_LED_GREEN_N")
	)
	(segment
		(start 83.184746 -94.234)
		(end 82.402934 -94.234)
		(width 0.11938)
		(layer "B.Cu")
		(net "SMA2_LED_GREEN_N")
	)
	(segment
		(start 72.379078 -94.581218)
		(end 72.379078 -107.706922)
		(width 0.11938)
		(layer "B.Cu")
		(net "SMA2_LED_GREEN_N")
	)
	(segment
		(start 22.098 -33.02)
		(end 19.812 -33.02)
		(width 0.11938)
		(layer "B.Cu")
		(net "SMA2_LED_GREEN_N")
	)
	(segment
		(start 20.7264 -109.22)
		(end 17.9324 -106.426)
		(width 0.11938)
		(layer "B.Cu")
		(net "SMA2_LED_GREEN_N")
	)
	(segment
		(start 4.191 -84.709)
		(end 4.191 -88.773)
		(width 0.127)
		(layer "In2.Cu")
		(net "SMA2_LED_GREEN_N")
	)
	(segment
		(start 4.191 -88.773)
		(end 5.207 -89.789)
		(width 0.127)
		(layer "In2.Cu")
		(net "SMA2_LED_GREEN_N")
	)
	(segment
		(start 9.398 -89.789)
		(end 12.9032 -93.2942)
		(width 0.127)
		(layer "In2.Cu")
		(net "SMA2_LED_GREEN_N")
	)
	(segment
		(start 5.207 -89.789)
		(end 9.398 -89.789)
		(width 0.127)
		(layer "In2.Cu")
		(net "SMA2_LED_GREEN_N")
	)
	(segment
		(start 10.414 -70.057518)
		(end 10.414 -72.008746)
		(width 0.127)
		(layer "In2.Cu")
		(net "SMA2_LED_GREEN_N")
	)
	(segment
		(start 12.065 -33.782)
		(end 13.081 -34.798)
		(width 0.127)
		(layer "In2.Cu")
		(net "SMA2_LED_GREEN_N")
	)
	(segment
		(start 12.319 -62.707266)
		(end 13.335 -63.723266)
		(width 0.127)
		(layer "In2.Cu")
		(net "SMA2_LED_GREEN_N")
	)
	(segment
		(start 10.414 -72.008746)
		(end 7.746746 -74.676)
		(width 0.127)
		(layer "In2.Cu")
		(net "SMA2_LED_GREEN_N")
	)
	(segment
		(start 13.081 -34.798)
		(end 13.081 -35.687)
		(width 0.127)
		(layer "In2.Cu")
		(net "SMA2_LED_GREEN_N")
	)
	(segment
		(start 5.6388 -83.2612)
		(end 4.191 -84.709)
		(width 0.127)
		(layer "In2.Cu")
		(net "SMA2_LED_GREEN_N")
	)
	(segment
		(start 13.5382 -93.2942)
		(end 13.97 -93.726)
		(width 0.127)
		(layer "In2.Cu")
		(net "SMA2_LED_GREEN_N")
	)
	(segment
		(start 12.0015 -52.3875)
		(end 12.0015 -54.5465)
		(width 0.127)
		(layer "In2.Cu")
		(net "SMA2_LED_GREEN_N")
	)
	(segment
		(start 11.811 -33.782)
		(end 12.065 -33.782)
		(width 0.127)
		(layer "In2.Cu")
		(net "SMA2_LED_GREEN_N")
	)
	(segment
		(start 6.4516 -74.676)
		(end 5.5499 -75.5777)
		(width 0.127)
		(layer "In2.Cu")
		(net "SMA2_LED_GREEN_N")
	)
	(segment
		(start 13.335 -63.723266)
		(end 13.335 -67.136518)
		(width 0.127)
		(layer "In2.Cu")
		(net "SMA2_LED_GREEN_N")
	)
	(segment
		(start 14.732 -37.338)
		(end 14.732 -47.244)
		(width 0.127)
		(layer "In2.Cu")
		(net "SMA2_LED_GREEN_N")
	)
	(segment
		(start 17.3228 -105.8418)
		(end 17.907 -106.426)
		(width 0.127)
		(layer "In2.Cu")
		(net "SMA2_LED_GREEN_N")
	)
	(segment
		(start 13.97 -104.902)
		(end 14.9098 -105.8418)
		(width 0.127)
		(layer "In2.Cu")
		(net "SMA2_LED_GREEN_N")
	)
	(segment
		(start 12.827 -51.562)
		(end 12.0015 -52.3875)
		(width 0.127)
		(layer "In2.Cu")
		(net "SMA2_LED_GREEN_N")
	)
	(segment
		(start 12.319 -54.864)
		(end 12.319 -62.707266)
		(width 0.127)
		(layer "In2.Cu")
		(net "SMA2_LED_GREEN_N")
	)
	(segment
		(start 13.335 -67.136518)
		(end 10.414 -70.057518)
		(width 0.127)
		(layer "In2.Cu")
		(net "SMA2_LED_GREEN_N")
	)
	(segment
		(start 14.732 -47.244)
		(end 12.827 -49.149)
		(width 0.127)
		(layer "In2.Cu")
		(net "SMA2_LED_GREEN_N")
	)
	(segment
		(start 14.9098 -105.8418)
		(end 17.3228 -105.8418)
		(width 0.127)
		(layer "In2.Cu")
		(net "SMA2_LED_GREEN_N")
	)
	(segment
		(start 5.5499 -79.205582)
		(end 5.6388 -79.294482)
		(width 0.127)
		(layer "In2.Cu")
		(net "SMA2_LED_GREEN_N")
	)
	(segment
		(start 5.6388 -79.294482)
		(end 5.6388 -83.2612)
		(width 0.127)
		(layer "In2.Cu")
		(net "SMA2_LED_GREEN_N")
	)
	(segment
		(start 12.827 -49.149)
		(end 12.827 -51.562)
		(width 0.127)
		(layer "In2.Cu")
		(net "SMA2_LED_GREEN_N")
	)
	(segment
		(start 12.9032 -93.2942)
		(end 13.5382 -93.2942)
		(width 0.127)
		(layer "In2.Cu")
		(net "SMA2_LED_GREEN_N")
	)
	(segment
		(start 5.5499 -75.5777)
		(end 5.5499 -79.205582)
		(width 0.127)
		(layer "In2.Cu")
		(net "SMA2_LED_GREEN_N")
	)
	(segment
		(start 13.081 -35.687)
		(end 14.732 -37.338)
		(width 0.127)
		(layer "In2.Cu")
		(net "SMA2_LED_GREEN_N")
	)
	(segment
		(start 13.97 -93.726)
		(end 13.97 -104.902)
		(width 0.127)
		(layer "In2.Cu")
		(net "SMA2_LED_GREEN_N")
	)
	(segment
		(start 12.0015 -54.5465)
		(end 12.319 -54.864)
		(width 0.127)
		(layer "In2.Cu")
		(net "SMA2_LED_GREEN_N")
	)
	(segment
		(start 7.746746 -74.676)
		(end 6.4516 -74.676)
		(width 0.127)
		(layer "In2.Cu")
		(net "SMA2_LED_GREEN_N")
	)
	(segment
		(start 22.606 -28.067)
		(end 22.352 -28.067)
		(width 0.11938)
		(layer "F.Cu")
		(net "SMA2_LED_BLUE_N")
	)
	(segment
		(start 100.965 -105.156)
		(end 103.638096 -105.156)
		(width 0.11938)
		(layer "F.Cu")
		(net "SMA2_LED_BLUE_N")
	)
	(segment
		(start 22.352 -28.067)
		(end 20.955 -26.67)
		(width 0.11938)
		(layer "F.Cu")
		(net "SMA2_LED_BLUE_N")
	)
	(segment
		(start 20.955 -26.67)
		(end 20.8534 -26.67)
		(width 0.11938)
		(layer "F.Cu")
		(net "SMA2_LED_BLUE_N")
	)
	(segment
		(start 103.638096 -105.156)
		(end 103.757476 -105.03662)
		(width 0.11938)
		(layer "F.Cu")
		(net "SMA2_LED_BLUE_N")
	)
	(segment
		(start 99.822 -106.299)
		(end 100.965 -105.156)
		(width 0.11938)
		(layer "F.Cu")
		(net "SMA2_LED_BLUE_N")
	)
	(segment
		(start 103.757476 -105.03662)
		(end 103.757476 -103.85044)
		(width 0.11938)
		(layer "F.Cu")
		(net "SMA2_LED_BLUE_N")
	)
	(via
		(at 10.517886 -33.678114)
		(size 0.508)
		(drill 0.254)
		(layers "F.Cu" "B.Cu")
		(net "SMA2_LED_BLUE_N")
	)
	(via
		(at 22.606 -28.067)
		(size 0.508)
		(drill 0.254)
		(layers "F.Cu" "B.Cu")
		(net "SMA2_LED_BLUE_N")
	)
	(via
		(at 99.822 -106.299)
		(size 0.4572)
		(drill 0.2032)
		(layers "F.Cu" "B.Cu")
		(net "SMA2_LED_BLUE_N")
	)
	(via
		(at 20.447 -106.807)
		(size 0.508)
		(drill 0.254)
		(layers "F.Cu" "B.Cu")
		(net "SMA2_LED_BLUE_N")
	)
	(segment
		(start 82.81162 -93.47962)
		(end 81.661 -92.329)
		(width 0.11938)
		(layer "B.Cu")
		(net "SMA2_LED_BLUE_N")
	)
	(segment
		(start 20.066 -30.099)
		(end 18.99793 -31.16707)
		(width 0.11938)
		(layer "B.Cu")
		(net "SMA2_LED_BLUE_N")
	)
	(segment
		(start 99.822 -106.299)
		(end 99.187254 -106.299)
		(width 0.11938)
		(layer "B.Cu")
		(net "SMA2_LED_BLUE_N")
	)
	(segment
		(start 10.517886 -33.631886)
		(end 10.517886 -33.678114)
		(width 0.11938)
		(layer "B.Cu")
		(net "SMA2_LED_BLUE_N")
	)
	(segment
		(start 15.494 -30.734)
		(end 15.03045 -30.27045)
		(width 0.11938)
		(layer "B.Cu")
		(net "SMA2_LED_BLUE_N")
	)
	(segment
		(start 71.247 -107.188)
		(end 69.977 -108.458)
		(width 0.11938)
		(layer "B.Cu")
		(net "SMA2_LED_BLUE_N")
	)
	(segment
		(start 81.661 -92.329)
		(end 73.279 -92.329)
		(width 0.11938)
		(layer "B.Cu")
		(net "SMA2_LED_BLUE_N")
	)
	(segment
		(start 16.363188 -30.734)
		(end 15.494 -30.734)
		(width 0.11938)
		(layer "B.Cu")
		(net "SMA2_LED_BLUE_N")
	)
	(segment
		(start 83.593686 -93.47962)
		(end 82.81162 -93.47962)
		(width 0.11938)
		(layer "B.Cu")
		(net "SMA2_LED_BLUE_N")
	)
	(segment
		(start 15.03045 -30.27045)
		(end 13.701014 -30.27045)
		(width 0.11938)
		(layer "B.Cu")
		(net "SMA2_LED_BLUE_N")
	)
	(segment
		(start 21.336 -108.458)
		(end 20.447 -107.569)
		(width 0.11938)
		(layer "B.Cu")
		(net "SMA2_LED_BLUE_N")
	)
	(segment
		(start 84.228686 -94.11462)
		(end 83.593686 -93.47962)
		(width 0.11938)
		(layer "B.Cu")
		(net "SMA2_LED_BLUE_N")
	)
	(segment
		(start 93.345 -96.830134)
		(end 90.629486 -94.11462)
		(width 0.11938)
		(layer "B.Cu")
		(net "SMA2_LED_BLUE_N")
	)
	(segment
		(start 73.279 -92.329)
		(end 71.247 -94.361)
		(width 0.11938)
		(layer "B.Cu")
		(net "SMA2_LED_BLUE_N")
	)
	(segment
		(start 93.345 -100.456746)
		(end 93.345 -96.830134)
		(width 0.11938)
		(layer "B.Cu")
		(net "SMA2_LED_BLUE_N")
	)
	(segment
		(start 16.796258 -31.16707)
		(end 16.363188 -30.734)
		(width 0.11938)
		(layer "B.Cu")
		(net "SMA2_LED_BLUE_N")
	)
	(segment
		(start 22.606 -28.067)
		(end 20.574 -30.099)
		(width 0.11938)
		(layer "B.Cu")
		(net "SMA2_LED_BLUE_N")
	)
	(segment
		(start 18.99793 -31.16707)
		(end 16.796258 -31.16707)
		(width 0.11938)
		(layer "B.Cu")
		(net "SMA2_LED_BLUE_N")
	)
	(segment
		(start 13.514324 -30.08376)
		(end 11.57224 -30.08376)
		(width 0.11938)
		(layer "B.Cu")
		(net "SMA2_LED_BLUE_N")
	)
	(segment
		(start 20.447 -107.569)
		(end 20.447 -106.807)
		(width 0.11938)
		(layer "B.Cu")
		(net "SMA2_LED_BLUE_N")
	)
	(segment
		(start 11.57224 -30.08376)
		(end 9.97331 -31.68269)
		(width 0.11938)
		(layer "B.Cu")
		(net "SMA2_LED_BLUE_N")
	)
	(segment
		(start 9.97331 -31.68269)
		(end 9.97331 -33.08731)
		(width 0.11938)
		(layer "B.Cu")
		(net "SMA2_LED_BLUE_N")
	)
	(segment
		(start 13.701014 -30.27045)
		(end 13.514324 -30.08376)
		(width 0.11938)
		(layer "B.Cu")
		(net "SMA2_LED_BLUE_N")
	)
	(segment
		(start 20.574 -30.099)
		(end 20.066 -30.099)
		(width 0.11938)
		(layer "B.Cu")
		(net "SMA2_LED_BLUE_N")
	)
	(segment
		(start 90.629486 -94.11462)
		(end 84.228686 -94.11462)
		(width 0.11938)
		(layer "B.Cu")
		(net "SMA2_LED_BLUE_N")
	)
	(segment
		(start 71.247 -94.361)
		(end 71.247 -107.188)
		(width 0.11938)
		(layer "B.Cu")
		(net "SMA2_LED_BLUE_N")
	)
	(segment
		(start 9.97331 -33.08731)
		(end 10.517886 -33.631886)
		(width 0.11938)
		(layer "B.Cu")
		(net "SMA2_LED_BLUE_N")
	)
	(segment
		(start 99.187254 -106.299)
		(end 93.345 -100.456746)
		(width 0.11938)
		(layer "B.Cu")
		(net "SMA2_LED_BLUE_N")
	)
	(segment
		(start 69.977 -108.458)
		(end 21.336 -108.458)
		(width 0.11938)
		(layer "B.Cu")
		(net "SMA2_LED_BLUE_N")
	)
	(segment
		(start 4.318 -81.788)
		(end 2.921 -83.185)
		(width 0.127)
		(layer "In2.Cu")
		(net "SMA2_LED_BLUE_N")
	)
	(segment
		(start 12.7762 -105.9942)
		(end 14.478 -107.696)
		(width 0.127)
		(layer "In2.Cu")
		(net "SMA2_LED_BLUE_N")
	)
	(segment
		(start 3.847338 -72.644)
		(end 3.3528 -73.138538)
		(width 0.127)
		(layer "In2.Cu")
		(net "SMA2_LED_BLUE_N")
	)
	(segment
		(start 10.517886 -33.678114)
		(end 10.517886 -36.933886)
		(width 0.127)
		(layer "In2.Cu")
		(net "SMA2_LED_BLUE_N")
	)
	(segment
		(start 4.318 -81.0768)
		(end 4.318 -81.788)
		(width 0.127)
		(layer "In2.Cu")
		(net "SMA2_LED_BLUE_N")
	)
	(segment
		(start 12.7762 -94.4372)
		(end 12.7762 -105.9942)
		(width 0.127)
		(layer "In2.Cu")
		(net "SMA2_LED_BLUE_N")
	)
	(segment
		(start 8.89 -90.551)
		(end 12.7762 -94.4372)
		(width 0.127)
		(layer "In2.Cu")
		(net "SMA2_LED_BLUE_N")
	)
	(segment
		(start 10.517886 -36.933886)
		(end 11.176 -37.592)
		(width 0.127)
		(layer "In2.Cu")
		(net "SMA2_LED_BLUE_N")
	)
	(segment
		(start 2.921 -88.646)
		(end 4.826 -90.551)
		(width 0.127)
		(layer "In2.Cu")
		(net "SMA2_LED_BLUE_N")
	)
	(segment
		(start 11.303 -65.324482)
		(end 11.303 -66.959734)
		(width 0.127)
		(layer "In2.Cu")
		(net "SMA2_LED_BLUE_N")
	)
	(segment
		(start 11.557 -65.070482)
		(end 11.303 -65.324482)
		(width 0.127)
		(layer "In2.Cu")
		(net "SMA2_LED_BLUE_N")
	)
	(segment
		(start 14.478 -107.696)
		(end 19.558 -107.696)
		(width 0.127)
		(layer "In2.Cu")
		(net "SMA2_LED_BLUE_N")
	)
	(segment
		(start 3.3528 -73.138538)
		(end 3.3528 -80.1116)
		(width 0.127)
		(layer "In2.Cu")
		(net "SMA2_LED_BLUE_N")
	)
	(segment
		(start 10.287 -40.513)
		(end 10.287 -58.674)
		(width 0.127)
		(layer "In2.Cu")
		(net "SMA2_LED_BLUE_N")
	)
	(segment
		(start 11.557 -59.944)
		(end 11.557 -65.070482)
		(width 0.127)
		(layer "In2.Cu")
		(net "SMA2_LED_BLUE_N")
	)
	(segment
		(start 11.303 -66.959734)
		(end 11.049 -67.213734)
		(width 0.127)
		(layer "In2.Cu")
		(net "SMA2_LED_BLUE_N")
	)
	(segment
		(start 11.049 -68.344542)
		(end 6.749542 -72.644)
		(width 0.127)
		(layer "In2.Cu")
		(net "SMA2_LED_BLUE_N")
	)
	(segment
		(start 10.287 -58.674)
		(end 11.557 -59.944)
		(width 0.127)
		(layer "In2.Cu")
		(net "SMA2_LED_BLUE_N")
	)
	(segment
		(start 11.176 -37.592)
		(end 11.176 -39.624)
		(width 0.127)
		(layer "In2.Cu")
		(net "SMA2_LED_BLUE_N")
	)
	(segment
		(start 3.3528 -80.1116)
		(end 4.318 -81.0768)
		(width 0.127)
		(layer "In2.Cu")
		(net "SMA2_LED_BLUE_N")
	)
	(segment
		(start 4.826 -90.551)
		(end 8.89 -90.551)
		(width 0.127)
		(layer "In2.Cu")
		(net "SMA2_LED_BLUE_N")
	)
	(segment
		(start 6.749542 -72.644)
		(end 3.847338 -72.644)
		(width 0.127)
		(layer "In2.Cu")
		(net "SMA2_LED_BLUE_N")
	)
	(segment
		(start 11.176 -39.624)
		(end 10.287 -40.513)
		(width 0.127)
		(layer "In2.Cu")
		(net "SMA2_LED_BLUE_N")
	)
	(segment
		(start 2.921 -83.185)
		(end 2.921 -88.646)
		(width 0.127)
		(layer "In2.Cu")
		(net "SMA2_LED_BLUE_N")
	)
	(segment
		(start 19.558 -107.696)
		(end 20.447 -106.807)
		(width 0.127)
		(layer "In2.Cu")
		(net "SMA2_LED_BLUE_N")
	)
	(segment
		(start 11.049 -67.213734)
		(end 11.049 -68.344542)
		(width 0.127)
		(layer "In2.Cu")
		(net "SMA2_LED_BLUE_N")
	)
	(segment
		(start 14.649704 -65.221104)
		(end 14.6812 -65.2526)
		(width 0.11938)
		(layer "F.Cu")
		(net "SMA1_SIG_OUT_BF_EN_N")
	)
	(segment
		(start 14.6812 -65.2526)
		(end 15.113 -65.2526)
		(width 0.11938)
		(layer "F.Cu")
		(net "SMA1_SIG_OUT_BF_EN_N")
	)
	(segment
		(start 15.113 -65.2526)
		(end 16.4338 -63.9318)
		(width 0.11938)
		(layer "F.Cu")
		(net "SMA1_SIG_OUT_BF_EN_N")
	)
	(segment
		(start 14.649704 -63.290196)
		(end 14.649704 -65.221104)
		(width 0.11938)
		(layer "F.Cu")
		(net "SMA1_SIG_OUT_BF_EN_N")
	)
	(segment
		(start 107.347258 -46.322996)
		(end 107.84713 -45.823124)
		(width 0.11938)
		(layer "F.Cu")
		(net "SMA1_SIG_OUT_BF_EN_N")
	)
	(via
		(at 23.8506 -39.4208)
		(size 0.508)
		(drill 0.254)
		(layers "F.Cu" "B.Cu")
		(net "SMA1_SIG_OUT_BF_EN_N")
	)
	(via
		(at 107.347258 -46.322996)
		(size 0.4572)
		(drill 0.2032)
		(layers "F.Cu" "B.Cu")
		(net "SMA1_SIG_OUT_BF_EN_N")
	)
	(segment
		(start 25.7175 -54.9275)
		(end 26.162 -54.483)
		(width 0.127)
		(layer "In2.Cu")
		(net "SMA1_SIG_OUT_BF_EN_N")
	)
	(segment
		(start 23.241 -42.799)
		(end 23.241 -40.0304)
		(width 0.127)
		(layer "In2.Cu")
		(net "SMA1_SIG_OUT_BF_EN_N")
	)
	(segment
		(start 21.844 -44.196)
		(end 23.241 -42.799)
		(width 0.127)
		(layer "In2.Cu")
		(net "SMA1_SIG_OUT_BF_EN_N")
	)
	(segment
		(start 16.383 -63.881)
		(end 16.383 -58.358024)
		(width 0.127)
		(layer "In2.Cu")
		(net "SMA1_SIG_OUT_BF_EN_N")
	)
	(segment
		(start 16.4465 -58.294524)
		(end 16.4465 -56.506618)
		(width 0.127)
		(layer "In2.Cu")
		(net "SMA1_SIG_OUT_BF_EN_N")
	)
	(segment
		(start 25.4 -47.244)
		(end 23.114 -47.244)
		(width 0.127)
		(layer "In2.Cu")
		(net "SMA1_SIG_OUT_BF_EN_N")
	)
	(segment
		(start 23.114 -47.244)
		(end 21.844 -45.974)
		(width 0.127)
		(layer "In2.Cu")
		(net "SMA1_SIG_OUT_BF_EN_N")
	)
	(segment
		(start 26.162 -48.006)
		(end 25.4 -47.244)
		(width 0.127)
		(layer "In2.Cu")
		(net "SMA1_SIG_OUT_BF_EN_N")
	)
	(segment
		(start 26.162 -54.483)
		(end 26.162 -48.006)
		(width 0.127)
		(layer "In2.Cu")
		(net "SMA1_SIG_OUT_BF_EN_N")
	)
	(segment
		(start 16.383 -58.358024)
		(end 16.4465 -58.294524)
		(width 0.127)
		(layer "In2.Cu")
		(net "SMA1_SIG_OUT_BF_EN_N")
	)
	(segment
		(start 23.241 -40.0304)
		(end 23.8506 -39.4208)
		(width 0.127)
		(layer "In2.Cu")
		(net "SMA1_SIG_OUT_BF_EN_N")
	)
	(segment
		(start 21.844 -45.974)
		(end 21.844 -44.196)
		(width 0.127)
		(layer "In2.Cu")
		(net "SMA1_SIG_OUT_BF_EN_N")
	)
	(segment
		(start 18.216118 -54.737)
		(end 24.257 -54.737)
		(width 0.127)
		(layer "In2.Cu")
		(net "SMA1_SIG_OUT_BF_EN_N")
	)
	(segment
		(start 16.4465 -56.506618)
		(end 18.216118 -54.737)
		(width 0.127)
		(layer "In2.Cu")
		(net "SMA1_SIG_OUT_BF_EN_N")
	)
	(segment
		(start 24.4475 -54.9275)
		(end 25.7175 -54.9275)
		(width 0.127)
		(layer "In2.Cu")
		(net "SMA1_SIG_OUT_BF_EN_N")
	)
	(segment
		(start 24.257 -54.737)
		(end 24.4475 -54.9275)
		(width 0.127)
		(layer "In2.Cu")
		(net "SMA1_SIG_OUT_BF_EN_N")
	)
	(segment
		(start 16.4338 -63.9318)
		(end 16.383 -63.881)
		(width 0.127)
		(layer "In2.Cu")
		(net "SMA1_SIG_OUT_BF_EN_N")
	)
	(segment
		(start 98.820224 -45.916596)
		(end 98.48596 -46.25086)
		(width 0.1016)
		(layer "In7.Cu")
		(net "SMA1_SIG_OUT_BF_EN_N")
	)
	(segment
		(start 74.93 -51.689)
		(end 68.199 -51.689)
		(width 0.127)
		(layer "In7.Cu")
		(net "SMA1_SIG_OUT_BF_EN_N")
	)
	(segment
		(start 90.757502 -50.243486)
		(end 90.112088 -50.8889)
		(width 0.127)
		(layer "In7.Cu")
		(net "SMA1_SIG_OUT_BF_EN_N")
	)
	(segment
		(start 79.030576 -50.4825)
		(end 76.1365 -50.4825)
		(width 0.127)
		(layer "In7.Cu")
		(net "SMA1_SIG_OUT_BF_EN_N")
	)
	(segment
		(start 60.387992 -39.116)
		(end 24.1554 -39.116)
		(width 0.127)
		(layer "In7.Cu")
		(net "SMA1_SIG_OUT_BF_EN_N")
	)
	(segment
		(start 90.112088 -50.8889)
		(end 79.436976 -50.8889)
		(width 0.127)
		(layer "In7.Cu")
		(net "SMA1_SIG_OUT_BF_EN_N")
	)
	(segment
		(start 106.940858 -45.916596)
		(end 98.820224 -45.916596)
		(width 0.1016)
		(layer "In7.Cu")
		(net "SMA1_SIG_OUT_BF_EN_N")
	)
	(segment
		(start 98.48596 -46.25086)
		(end 97.144078 -46.25086)
		(width 0.127)
		(layer "In7.Cu")
		(net "SMA1_SIG_OUT_BF_EN_N")
	)
	(segment
		(start 93.151452 -50.243486)
		(end 90.757502 -50.243486)
		(width 0.127)
		(layer "In7.Cu")
		(net "SMA1_SIG_OUT_BF_EN_N")
	)
	(segment
		(start 79.436976 -50.8889)
		(end 79.030576 -50.4825)
		(width 0.127)
		(layer "In7.Cu")
		(net "SMA1_SIG_OUT_BF_EN_N")
	)
	(segment
		(start 76.1365 -50.4825)
		(end 74.93 -51.689)
		(width 0.127)
		(layer "In7.Cu")
		(net "SMA1_SIG_OUT_BF_EN_N")
	)
	(segment
		(start 107.347258 -46.322996)
		(end 106.940858 -45.916596)
		(width 0.1016)
		(layer "In7.Cu")
		(net "SMA1_SIG_OUT_BF_EN_N")
	)
	(segment
		(start 97.144078 -46.25086)
		(end 93.151452 -50.243486)
		(width 0.127)
		(layer "In7.Cu")
		(net "SMA1_SIG_OUT_BF_EN_N")
	)
	(segment
		(start 67.31 -50.8)
		(end 67.31 -46.038008)
		(width 0.127)
		(layer "In7.Cu")
		(net "SMA1_SIG_OUT_BF_EN_N")
	)
	(segment
		(start 24.1554 -39.116)
		(end 23.8506 -39.4208)
		(width 0.127)
		(layer "In7.Cu")
		(net "SMA1_SIG_OUT_BF_EN_N")
	)
	(segment
		(start 68.199 -51.689)
		(end 67.31 -50.8)
		(width 0.127)
		(layer "In7.Cu")
		(net "SMA1_SIG_OUT_BF_EN_N")
	)
	(segment
		(start 67.31 -46.038008)
		(end 60.387992 -39.116)
		(width 0.127)
		(layer "In7.Cu")
		(net "SMA1_SIG_OUT_BF_EN_N")
	)
	(segment
		(start 13.068808 -57.785)
		(end 13.462 -57.785)
		(width 0.11938)
		(layer "F.Cu")
		(net "SMA1_SIG_IN_BF_EN_N")
	)
	(segment
		(start 14.605 -57.531)
		(end 14.605 -58.293)
		(width 0.11938)
		(layer "F.Cu")
		(net "SMA1_SIG_IN_BF_EN_N")
	)
	(segment
		(start 13.462 -57.785)
		(end 13.716 -57.531)
		(width 0.11938)
		(layer "F.Cu")
		(net "SMA1_SIG_IN_BF_EN_N")
	)
	(segment
		(start 14.605 -58.293)
		(end 14.149832 -58.748168)
		(width 0.11938)
		(layer "F.Cu")
		(net "SMA1_SIG_IN_BF_EN_N")
	)
	(segment
		(start 107.84713 -46.823122)
		(end 107.347258 -47.322994)
		(width 0.11938)
		(layer "F.Cu")
		(net "SMA1_SIG_IN_BF_EN_N")
	)
	(segment
		(start 14.149832 -58.748168)
		(end 14.149832 -59.909964)
		(width 0.11938)
		(layer "F.Cu")
		(net "SMA1_SIG_IN_BF_EN_N")
	)
	(segment
		(start 13.716 -57.531)
		(end 14.605 -57.531)
		(width 0.11938)
		(layer "F.Cu")
		(net "SMA1_SIG_IN_BF_EN_N")
	)
	(via
		(at 24.3078 -57.785)
		(size 0.508)
		(drill 0.254)
		(layers "F.Cu" "B.Cu")
		(net "SMA1_SIG_IN_BF_EN_N")
	)
	(via
		(at 107.347258 -47.322994)
		(size 0.4572)
		(drill 0.2032)
		(layers "F.Cu" "B.Cu")
		(net "SMA1_SIG_IN_BF_EN_N")
	)
	(segment
		(start 16.45158 -55.68442)
		(end 14.605 -57.531)
		(width 0.11938)
		(layer "B.Cu")
		(net "SMA1_SIG_IN_BF_EN_N")
	)
	(segment
		(start 19.235674 -55.68442)
		(end 16.45158 -55.68442)
		(width 0.11938)
		(layer "B.Cu")
		(net "SMA1_SIG_IN_BF_EN_N")
	)
	(segment
		(start 20.574254 -57.023)
		(end 19.235674 -55.68442)
		(width 0.11938)
		(layer "B.Cu")
		(net "SMA1_SIG_IN_BF_EN_N")
	)
	(segment
		(start 23.5458 -57.023)
		(end 20.574254 -57.023)
		(width 0.11938)
		(layer "B.Cu")
		(net "SMA1_SIG_IN_BF_EN_N")
	)
	(segment
		(start 24.3078 -57.785)
		(end 23.5458 -57.023)
		(width 0.11938)
		(layer "B.Cu")
		(net "SMA1_SIG_IN_BF_EN_N")
	)
	(segment
		(start 105.1179 -51.816)
		(end 105.664 -51.816)
		(width 0.127)
		(layer "In7.Cu")
		(net "SMA1_SIG_IN_BF_EN_N")
	)
	(segment
		(start 89.7255 -66.6115)
		(end 90.424 -67.31)
		(width 0.127)
		(layer "In7.Cu")
		(net "SMA1_SIG_IN_BF_EN_N")
	)
	(segment
		(start 29.3624 -61.8236)
		(end 57.9374 -61.8236)
		(width 0.127)
		(layer "In7.Cu")
		(net "SMA1_SIG_IN_BF_EN_N")
	)
	(segment
		(start 105.664 -51.816)
		(end 105.918 -51.562)
		(width 0.127)
		(layer "In7.Cu")
		(net "SMA1_SIG_IN_BF_EN_N")
	)
	(segment
		(start 101.9429 -63.367666)
		(end 101.9429 -61.468)
		(width 0.127)
		(layer "In7.Cu")
		(net "SMA1_SIG_IN_BF_EN_N")
	)
	(segment
		(start 90.424 -67.31)
		(end 91.313254 -67.31)
		(width 0.127)
		(layer "In7.Cu")
		(net "SMA1_SIG_IN_BF_EN_N")
	)
	(segment
		(start 65.0621 -61.3537)
		(end 72.3011 -61.3537)
		(width 0.127)
		(layer "In7.Cu")
		(net "SMA1_SIG_IN_BF_EN_N")
	)
	(segment
		(start 91.313254 -67.31)
		(end 91.757754 -66.8655)
		(width 0.127)
		(layer "In7.Cu")
		(net "SMA1_SIG_IN_BF_EN_N")
	)
	(segment
		(start 105.918 -51.562)
		(end 105.918 -50.927)
		(width 0.127)
		(layer "In7.Cu")
		(net "SMA1_SIG_IN_BF_EN_N")
	)
	(segment
		(start 87.884 -66.213482)
		(end 88.282018 -66.6115)
		(width 0.127)
		(layer "In7.Cu")
		(net "SMA1_SIG_IN_BF_EN_N")
	)
	(segment
		(start 24.3078 -57.785)
		(end 25.3238 -57.785)
		(width 0.127)
		(layer "In7.Cu")
		(net "SMA1_SIG_IN_BF_EN_N")
	)
	(segment
		(start 104.902 -52.0319)
		(end 105.1179 -51.816)
		(width 0.127)
		(layer "In7.Cu")
		(net "SMA1_SIG_IN_BF_EN_N")
	)
	(segment
		(start 79.502 -66.1416)
		(end 80.2005 -65.4431)
		(width 0.127)
		(layer "In7.Cu")
		(net "SMA1_SIG_IN_BF_EN_N")
	)
	(segment
		(start 105.918 -50.927)
		(end 106.045 -50.8)
		(width 0.127)
		(layer "In7.Cu")
		(net "SMA1_SIG_IN_BF_EN_N")
	)
	(segment
		(start 106.553 -50.8)
		(end 106.807 -50.546)
		(width 0.127)
		(layer "In7.Cu")
		(net "SMA1_SIG_IN_BF_EN_N")
	)
	(segment
		(start 94.300548 -66.8655)
		(end 94.618048 -67.183)
		(width 0.127)
		(layer "In7.Cu")
		(net "SMA1_SIG_IN_BF_EN_N")
	)
	(segment
		(start 106.045 -50.8)
		(end 106.553 -50.8)
		(width 0.127)
		(layer "In7.Cu")
		(net "SMA1_SIG_IN_BF_EN_N")
	)
	(segment
		(start 57.9374 -61.8236)
		(end 58.6486 -62.5348)
		(width 0.127)
		(layer "In7.Cu")
		(net "SMA1_SIG_IN_BF_EN_N")
	)
	(segment
		(start 103.378 -60.0329)
		(end 103.378 -58.085228)
		(width 0.127)
		(layer "In7.Cu")
		(net "SMA1_SIG_IN_BF_EN_N")
	)
	(segment
		(start 87.485982 -65.1891)
		(end 87.884 -65.587118)
		(width 0.127)
		(layer "In7.Cu")
		(net "SMA1_SIG_IN_BF_EN_N")
	)
	(segment
		(start 58.6486 -62.5348)
		(end 63.881 -62.5348)
		(width 0.127)
		(layer "In7.Cu")
		(net "SMA1_SIG_IN_BF_EN_N")
	)
	(segment
		(start 94.618048 -67.183)
		(end 98.127566 -67.183)
		(width 0.127)
		(layer "In7.Cu")
		(net "SMA1_SIG_IN_BF_EN_N")
	)
	(segment
		(start 77.089 -66.1416)
		(end 79.502 -66.1416)
		(width 0.127)
		(layer "In7.Cu")
		(net "SMA1_SIG_IN_BF_EN_N")
	)
	(segment
		(start 91.757754 -66.8655)
		(end 94.300548 -66.8655)
		(width 0.127)
		(layer "In7.Cu")
		(net "SMA1_SIG_IN_BF_EN_N")
	)
	(segment
		(start 106.807 -50.546)
		(end 106.807 -47.863252)
		(width 0.127)
		(layer "In7.Cu")
		(net "SMA1_SIG_IN_BF_EN_N")
	)
	(segment
		(start 104.902 -56.561228)
		(end 104.902 -52.0319)
		(width 0.127)
		(layer "In7.Cu")
		(net "SMA1_SIG_IN_BF_EN_N")
	)
	(segment
		(start 101.9429 -61.468)
		(end 103.378 -60.0329)
		(width 0.127)
		(layer "In7.Cu")
		(net "SMA1_SIG_IN_BF_EN_N")
	)
	(segment
		(start 98.127566 -67.183)
		(end 101.9429 -63.367666)
		(width 0.127)
		(layer "In7.Cu")
		(net "SMA1_SIG_IN_BF_EN_N")
	)
	(segment
		(start 103.378 -58.085228)
		(end 104.902 -56.561228)
		(width 0.127)
		(layer "In7.Cu")
		(net "SMA1_SIG_IN_BF_EN_N")
	)
	(segment
		(start 87.884 -65.587118)
		(end 87.884 -66.213482)
		(width 0.127)
		(layer "In7.Cu")
		(net "SMA1_SIG_IN_BF_EN_N")
	)
	(segment
		(start 83.202018 -65.1891)
		(end 87.485982 -65.1891)
		(width 0.127)
		(layer "In7.Cu")
		(net "SMA1_SIG_IN_BF_EN_N")
	)
	(segment
		(start 106.807 -47.863252)
		(end 107.347258 -47.322994)
		(width 0.127)
		(layer "In7.Cu")
		(net "SMA1_SIG_IN_BF_EN_N")
	)
	(segment
		(start 82.948018 -65.4431)
		(end 83.202018 -65.1891)
		(width 0.127)
		(layer "In7.Cu")
		(net "SMA1_SIG_IN_BF_EN_N")
	)
	(segment
		(start 25.3238 -57.785)
		(end 29.3624 -61.8236)
		(width 0.127)
		(layer "In7.Cu")
		(net "SMA1_SIG_IN_BF_EN_N")
	)
	(segment
		(start 88.282018 -66.6115)
		(end 89.7255 -66.6115)
		(width 0.127)
		(layer "In7.Cu")
		(net "SMA1_SIG_IN_BF_EN_N")
	)
	(segment
		(start 80.2005 -65.4431)
		(end 82.948018 -65.4431)
		(width 0.127)
		(layer "In7.Cu")
		(net "SMA1_SIG_IN_BF_EN_N")
	)
	(segment
		(start 63.881 -62.5348)
		(end 65.0621 -61.3537)
		(width 0.127)
		(layer "In7.Cu")
		(net "SMA1_SIG_IN_BF_EN_N")
	)
	(segment
		(start 72.3011 -61.3537)
		(end 77.089 -66.1416)
		(width 0.127)
		(layer "In7.Cu")
		(net "SMA1_SIG_IN_BF_EN_N")
	)
	(segment
		(start 8.2804 -38.785292)
		(end 8.2804 -37.7698)
		(width 0.11938)
		(layer "F.Cu")
		(net "SMA1_LED_RED_N")
	)
	(segment
		(start 106.257598 -107.305602)
		(end 105.8672 -107.696)
		(width 0.11938)
		(layer "F.Cu")
		(net "SMA1_LED_RED_N")
	)
	(segment
		(start 106.257598 -103.81234)
		(end 106.257598 -107.305602)
		(width 0.11938)
		(layer "F.Cu")
		(net "SMA1_LED_RED_N")
	)
	(via
		(at 105.8672 -107.696)
		(size 0.4572)
		(drill 0.2032)
		(layers "F.Cu" "B.Cu")
		(net "SMA1_LED_RED_N")
	)
	(via
		(at 8.2804 -37.7698)
		(size 0.508)
		(drill 0.254)
		(layers "F.Cu" "B.Cu")
		(net "SMA1_LED_RED_N")
	)
	(via
		(at 21.717 -106.807)
		(size 0.4572)
		(drill 0.2032)
		(layers "F.Cu" "B.Cu")
		(net "SMA1_LED_RED_N")
	)
	(via
		(at 3.81 -70.866)
		(size 0.508)
		(drill 0.254)
		(layers "F.Cu" "B.Cu")
		(net "SMA1_LED_RED_N")
	)
	(segment
		(start 83.11769 -92.76969)
		(end 83.439 -93.091)
		(width 0.11938)
		(layer "B.Cu")
		(net "SMA1_LED_RED_N")
	)
	(segment
		(start 83.11769 -91.966796)
		(end 83.11769 -92.76969)
		(width 0.11938)
		(layer "B.Cu")
		(net "SMA1_LED_RED_N")
	)
	(segment
		(start 21.717 -106.807)
		(end 21.717 -107.676696)
		(width 0.11938)
		(layer "B.Cu")
		(net "SMA1_LED_RED_N")
	)
	(segment
		(start 22.117304 -108.077)
		(end 60.579 -108.077)
		(width 0.11938)
		(layer "B.Cu")
		(net "SMA1_LED_RED_N")
	)
	(segment
		(start 83.733132 -93.091)
		(end 84.383372 -93.74124)
		(width 0.11938)
		(layer "B.Cu")
		(net "SMA1_LED_RED_N")
	)
	(segment
		(start 93.726 -100.289868)
		(end 99.100132 -105.664)
		(width 0.11938)
		(layer "B.Cu")
		(net "SMA1_LED_RED_N")
	)
	(segment
		(start 63.754 -96.266)
		(end 68.707254 -96.266)
		(width 0.11938)
		(layer "B.Cu")
		(net "SMA1_LED_RED_N")
	)
	(segment
		(start 68.707254 -96.266)
		(end 73.338944 -91.63431)
		(width 0.11938)
		(layer "B.Cu")
		(net "SMA1_LED_RED_N")
	)
	(segment
		(start 90.94724 -93.74124)
		(end 93.726 -96.52)
		(width 0.11938)
		(layer "B.Cu")
		(net "SMA1_LED_RED_N")
	)
	(segment
		(start 99.100132 -105.664)
		(end 102.743 -105.664)
		(width 0.11938)
		(layer "B.Cu")
		(net "SMA1_LED_RED_N")
	)
	(segment
		(start 21.717 -107.676696)
		(end 22.117304 -108.077)
		(width 0.11938)
		(layer "B.Cu")
		(net "SMA1_LED_RED_N")
	)
	(segment
		(start 93.726 -96.52)
		(end 93.726 -100.289868)
		(width 0.11938)
		(layer "B.Cu")
		(net "SMA1_LED_RED_N")
	)
	(segment
		(start 83.439 -93.091)
		(end 83.733132 -93.091)
		(width 0.11938)
		(layer "B.Cu")
		(net "SMA1_LED_RED_N")
	)
	(segment
		(start 104.775 -107.696)
		(end 105.8672 -107.696)
		(width 0.11938)
		(layer "B.Cu")
		(net "SMA1_LED_RED_N")
	)
	(segment
		(start 102.743 -105.664)
		(end 104.775 -107.696)
		(width 0.11938)
		(layer "B.Cu")
		(net "SMA1_LED_RED_N")
	)
	(segment
		(start 82.785204 -91.63431)
		(end 83.11769 -91.966796)
		(width 0.11938)
		(layer "B.Cu")
		(net "SMA1_LED_RED_N")
	)
	(segment
		(start 61.214 -98.806)
		(end 63.754 -96.266)
		(width 0.11938)
		(layer "B.Cu")
		(net "SMA1_LED_RED_N")
	)
	(segment
		(start 73.338944 -91.63431)
		(end 82.785204 -91.63431)
		(width 0.11938)
		(layer "B.Cu")
		(net "SMA1_LED_RED_N")
	)
	(segment
		(start 84.383372 -93.74124)
		(end 90.94724 -93.74124)
		(width 0.11938)
		(layer "B.Cu")
		(net "SMA1_LED_RED_N")
	)
	(segment
		(start 60.579 -108.077)
		(end 61.214 -107.442)
		(width 0.11938)
		(layer "B.Cu")
		(net "SMA1_LED_RED_N")
	)
	(segment
		(start 61.214 -107.442)
		(end 61.214 -98.806)
		(width 0.11938)
		(layer "B.Cu")
		(net "SMA1_LED_RED_N")
	)
	(segment
		(start 7.462012 -70.612)
		(end 4.064 -70.612)
		(width 0.127)
		(layer "In2.Cu")
		(net "SMA1_LED_RED_N")
	)
	(segment
		(start 9.525 -65.597024)
		(end 9.652 -65.724024)
		(width 0.127)
		(layer "In2.Cu")
		(net "SMA1_LED_RED_N")
	)
	(segment
		(start 8.2804 -37.7698)
		(end 9.525 -39.0144)
		(width 0.127)
		(layer "In2.Cu")
		(net "SMA1_LED_RED_N")
	)
	(segment
		(start 4.064 -70.612)
		(end 3.81 -70.866)
		(width 0.127)
		(layer "In2.Cu")
		(net "SMA1_LED_RED_N")
	)
	(segment
		(start 9.525 -39.0144)
		(end 9.525 -65.597024)
		(width 0.127)
		(layer "In2.Cu")
		(net "SMA1_LED_RED_N")
	)
	(segment
		(start 9.652 -65.724024)
		(end 9.652 -68.422012)
		(width 0.127)
		(layer "In2.Cu")
		(net "SMA1_LED_RED_N")
	)
	(segment
		(start 9.652 -68.422012)
		(end 7.462012 -70.612)
		(width 0.127)
		(layer "In2.Cu")
		(net "SMA1_LED_RED_N")
	)
	(segment
		(start 3.429 -89.789)
		(end 2.413 -88.773)
		(width 0.127)
		(layer "In7.Cu")
		(net "SMA1_LED_RED_N")
	)
	(segment
		(start 20.193 -108.331)
		(end 15.94104 -108.331)
		(width 0.127)
		(layer "In7.Cu")
		(net "SMA1_LED_RED_N")
	)
	(segment
		(start 21.717 -106.807)
		(end 20.193 -108.331)
		(width 0.127)
		(layer "In7.Cu")
		(net "SMA1_LED_RED_N")
	)
	(segment
		(start 15.94104 -108.331)
		(end 13.5382 -105.92816)
		(width 0.127)
		(layer "In7.Cu")
		(net "SMA1_LED_RED_N")
	)
	(segment
		(start 9.525 -89.789)
		(end 3.429 -89.789)
		(width 0.127)
		(layer "In7.Cu")
		(net "SMA1_LED_RED_N")
	)
	(segment
		(start 2.413 -73.406)
		(end 2.921 -72.898)
		(width 0.127)
		(layer "In7.Cu")
		(net "SMA1_LED_RED_N")
	)
	(segment
		(start 13.5382 -105.92816)
		(end 13.5382 -93.8022)
		(width 0.127)
		(layer "In7.Cu")
		(net "SMA1_LED_RED_N")
	)
	(segment
		(start 13.5382 -93.8022)
		(end 9.525 -89.789)
		(width 0.127)
		(layer "In7.Cu")
		(net "SMA1_LED_RED_N")
	)
	(segment
		(start 2.413 -88.773)
		(end 2.413 -73.406)
		(width 0.127)
		(layer "In7.Cu")
		(net "SMA1_LED_RED_N")
	)
	(segment
		(start 2.921 -71.755)
		(end 3.81 -70.866)
		(width 0.127)
		(layer "In7.Cu")
		(net "SMA1_LED_RED_N")
	)
	(segment
		(start 2.921 -72.898)
		(end 2.921 -71.755)
		(width 0.127)
		(layer "In7.Cu")
		(net "SMA1_LED_RED_N")
	)
	(segment
		(start 10.5664 -38.785292)
		(end 10.5664 -37.794692)
		(width 0.11938)
		(layer "F.Cu")
		(net "SMA1_LED_GREEN_N")
	)
	(segment
		(start 106.757724 -107.180126)
		(end 107.273598 -107.696)
		(width 0.11938)
		(layer "F.Cu")
		(net "SMA1_LED_GREEN_N")
	)
	(segment
		(start 106.757724 -103.85044)
		(end 106.757724 -107.180126)
		(width 0.11938)
		(layer "F.Cu")
		(net "SMA1_LED_GREEN_N")
	)
	(via
		(at 10.5664 -37.794692)
		(size 0.508)
		(drill 0.254)
		(layers "F.Cu" "B.Cu")
		(net "SMA1_LED_GREEN_N")
	)
	(via
		(at 22.86 -106.807)
		(size 0.4572)
		(drill 0.2032)
		(layers "F.Cu" "B.Cu")
		(net "SMA1_LED_GREEN_N")
	)
	(via
		(at 107.273598 -107.696)
		(size 0.4572)
		(drill 0.2032)
		(layers "F.Cu" "B.Cu")
		(net "SMA1_LED_GREEN_N")
	)
	(via
		(at 2.286 -72.644)
		(size 0.508)
		(drill 0.254)
		(layers "F.Cu" "B.Cu")
		(net "SMA1_LED_GREEN_N")
	)
	(segment
		(start 94.234 -96.32188)
		(end 94.234 -100.269802)
		(width 0.11938)
		(layer "B.Cu")
		(net "SMA1_LED_GREEN_N")
	)
	(segment
		(start 23.770082 -107.569)
		(end 60.081922 -107.569)
		(width 0.11938)
		(layer "B.Cu")
		(net "SMA1_LED_GREEN_N")
	)
	(segment
		(start 91.25712 -93.345)
		(end 94.234 -96.32188)
		(width 0.11938)
		(layer "B.Cu")
		(net "SMA1_LED_GREEN_N")
	)
	(segment
		(start 84.515198 -93.345)
		(end 91.25712 -93.345)
		(width 0.11938)
		(layer "B.Cu")
		(net "SMA1_LED_GREEN_N")
	)
	(segment
		(start 68.473066 -95.885)
		(end 73.097136 -91.26093)
		(width 0.11938)
		(layer "B.Cu")
		(net "SMA1_LED_GREEN_N")
	)
	(segment
		(start 60.579 -107.071922)
		(end 60.579 -98.806)
		(width 0.11938)
		(layer "B.Cu")
		(net "SMA1_LED_GREEN_N")
	)
	(segment
		(start 106.172254 -107.061)
		(end 106.807254 -107.696)
		(width 0.11938)
		(layer "B.Cu")
		(net "SMA1_LED_GREEN_N")
	)
	(segment
		(start 83.887818 -92.71762)
		(end 84.515198 -93.345)
		(width 0.11938)
		(layer "B.Cu")
		(net "SMA1_LED_GREEN_N")
	)
	(segment
		(start 104.902254 -107.061)
		(end 106.172254 -107.061)
		(width 0.11938)
		(layer "B.Cu")
		(net "SMA1_LED_GREEN_N")
	)
	(segment
		(start 82.93989 -91.26093)
		(end 83.49107 -91.81211)
		(width 0.11938)
		(layer "B.Cu")
		(net "SMA1_LED_GREEN_N")
	)
	(segment
		(start 83.49107 -92.615004)
		(end 83.593686 -92.71762)
		(width 0.11938)
		(layer "B.Cu")
		(net "SMA1_LED_GREEN_N")
	)
	(segment
		(start 102.997254 -105.156)
		(end 104.902254 -107.061)
		(width 0.11938)
		(layer "B.Cu")
		(net "SMA1_LED_GREEN_N")
	)
	(segment
		(start 23.008082 -106.807)
		(end 23.770082 -107.569)
		(width 0.11938)
		(layer "B.Cu")
		(net "SMA1_LED_GREEN_N")
	)
	(segment
		(start 73.097136 -91.26093)
		(end 82.93989 -91.26093)
		(width 0.11938)
		(layer "B.Cu")
		(net "SMA1_LED_GREEN_N")
	)
	(segment
		(start 22.86 -106.807)
		(end 23.008082 -106.807)
		(width 0.11938)
		(layer "B.Cu")
		(net "SMA1_LED_GREEN_N")
	)
	(segment
		(start 60.081922 -107.569)
		(end 60.579 -107.071922)
		(width 0.11938)
		(layer "B.Cu")
		(net "SMA1_LED_GREEN_N")
	)
	(segment
		(start 83.49107 -91.81211)
		(end 83.49107 -92.615004)
		(width 0.11938)
		(layer "B.Cu")
		(net "SMA1_LED_GREEN_N")
	)
	(segment
		(start 106.807254 -107.696)
		(end 107.273598 -107.696)
		(width 0.11938)
		(layer "B.Cu")
		(net "SMA1_LED_GREEN_N")
	)
	(segment
		(start 83.593686 -92.71762)
		(end 83.887818 -92.71762)
		(width 0.11938)
		(layer "B.Cu")
		(net "SMA1_LED_GREEN_N")
	)
	(segment
		(start 99.120198 -105.156)
		(end 102.997254 -105.156)
		(width 0.11938)
		(layer "B.Cu")
		(net "SMA1_LED_GREEN_N")
	)
	(segment
		(start 94.234 -100.269802)
		(end 99.120198 -105.156)
		(width 0.11938)
		(layer "B.Cu")
		(net "SMA1_LED_GREEN_N")
	)
	(segment
		(start 63.5 -95.885)
		(end 68.473066 -95.885)
		(width 0.11938)
		(layer "B.Cu")
		(net "SMA1_LED_GREEN_N")
	)
	(segment
		(start 60.579 -98.806)
		(end 63.5 -95.885)
		(width 0.11938)
		(layer "B.Cu")
		(net "SMA1_LED_GREEN_N")
	)
	(segment
		(start 10.668 -67.945)
		(end 10.668 -67.055746)
		(width 0.127)
		(layer "In2.Cu")
		(net "SMA1_LED_GREEN_N")
	)
	(segment
		(start 9.779 -38.729412)
		(end 9.779 -38.582092)
		(width 0.127)
		(layer "In2.Cu")
		(net "SMA1_LED_GREEN_N")
	)
	(segment
		(start 9.779 -38.582092)
		(end 10.5664 -37.794692)
		(width 0.127)
		(layer "In2.Cu")
		(net "SMA1_LED_GREEN_N")
	)
	(segment
		(start 10.668 -67.055746)
		(end 10.922 -66.801746)
		(width 0.127)
		(layer "In2.Cu")
		(net "SMA1_LED_GREEN_N")
	)
	(segment
		(start 9.906 -38.856412)
		(end 9.779 -38.729412)
		(width 0.127)
		(layer "In2.Cu")
		(net "SMA1_LED_GREEN_N")
	)
	(segment
		(start 10.16 -65.278)
		(end 10.16 -62.865)
		(width 0.127)
		(layer "In2.Cu")
		(net "SMA1_LED_GREEN_N")
	)
	(segment
		(start 10.922 -66.801746)
		(end 10.922 -66.04)
		(width 0.127)
		(layer "In2.Cu")
		(net "SMA1_LED_GREEN_N")
	)
	(segment
		(start 2.286 -72.644)
		(end 3.048 -72.644)
		(width 0.127)
		(layer "In2.Cu")
		(net "SMA1_LED_GREEN_N")
	)
	(segment
		(start 3.048 -72.644)
		(end 4.572 -71.12)
		(width 0.127)
		(layer "In2.Cu")
		(net "SMA1_LED_GREEN_N")
	)
	(segment
		(start 9.906 -62.611)
		(end 9.906 -38.856412)
		(width 0.127)
		(layer "In2.Cu")
		(net "SMA1_LED_GREEN_N")
	)
	(segment
		(start 4.572 -71.12)
		(end 7.493 -71.12)
		(width 0.127)
		(layer "In2.Cu")
		(net "SMA1_LED_GREEN_N")
	)
	(segment
		(start 10.16 -62.865)
		(end 9.906 -62.611)
		(width 0.127)
		(layer "In2.Cu")
		(net "SMA1_LED_GREEN_N")
	)
	(segment
		(start 7.493 -71.12)
		(end 10.668 -67.945)
		(width 0.127)
		(layer "In2.Cu")
		(net "SMA1_LED_GREEN_N")
	)
	(segment
		(start 10.922 -66.04)
		(end 10.16 -65.278)
		(width 0.127)
		(layer "In2.Cu")
		(net "SMA1_LED_GREEN_N")
	)
	(segment
		(start 22.86 -106.807)
		(end 20.955 -108.712)
		(width 0.127)
		(layer "In7.Cu")
		(net "SMA1_LED_GREEN_N")
	)
	(segment
		(start 2.032 -72.898)
		(end 2.286 -72.644)
		(width 0.127)
		(layer "In7.Cu")
		(net "SMA1_LED_GREEN_N")
	)
	(segment
		(start 15.529306 -108.712)
		(end 13.1572 -106.339894)
		(width 0.127)
		(layer "In7.Cu")
		(net "SMA1_LED_GREEN_N")
	)
	(segment
		(start 13.1572 -106.339894)
		(end 13.1572 -94.0562)
		(width 0.127)
		(layer "In7.Cu")
		(net "SMA1_LED_GREEN_N")
	)
	(segment
		(start 13.1572 -94.0562)
		(end 9.398 -90.297)
		(width 0.127)
		(layer "In7.Cu")
		(net "SMA1_LED_GREEN_N")
	)
	(segment
		(start 20.955 -108.712)
		(end 15.529306 -108.712)
		(width 0.127)
		(layer "In7.Cu")
		(net "SMA1_LED_GREEN_N")
	)
	(segment
		(start 2.032 -89.027)
		(end 2.032 -72.898)
		(width 0.127)
		(layer "In7.Cu")
		(net "SMA1_LED_GREEN_N")
	)
	(segment
		(start 9.398 -90.297)
		(end 3.302 -90.297)
		(width 0.127)
		(layer "In7.Cu")
		(net "SMA1_LED_GREEN_N")
	)
	(segment
		(start 3.302 -90.297)
		(end 2.032 -89.027)
		(width 0.127)
		(layer "In7.Cu")
		(net "SMA1_LED_GREEN_N")
	)
	(segment
		(start 105.156 -106.426)
		(end 105.757726 -105.824274)
		(width 0.11938)
		(layer "F.Cu")
		(net "SMA1_LED_BLUE_N")
	)
	(segment
		(start 105.757726 -105.824274)
		(end 105.757726 -103.81234)
		(width 0.11938)
		(layer "F.Cu")
		(net "SMA1_LED_BLUE_N")
	)
	(segment
		(start 4.8514 -38.785292)
		(end 4.8514 -37.794692)
		(width 0.11938)
		(layer "F.Cu")
		(net "SMA1_LED_BLUE_N")
	)
	(via
		(at 24.892 -106.68)
		(size 0.4572)
		(drill 0.2032)
		(layers "F.Cu" "B.Cu")
		(net "SMA1_LED_BLUE_N")
	)
	(via
		(at 2.286 -70.866)
		(size 0.508)
		(drill 0.254)
		(layers "F.Cu" "B.Cu")
		(net "SMA1_LED_BLUE_N")
	)
	(via
		(at 105.156 -106.426)
		(size 0.4572)
		(drill 0.2032)
		(layers "F.Cu" "B.Cu")
		(net "SMA1_LED_BLUE_N")
	)
	(via
		(at 4.8514 -37.794692)
		(size 0.508)
		(drill 0.254)
		(layers "F.Cu" "B.Cu")
		(net "SMA1_LED_BLUE_N")
	)
	(segment
		(start 25.527 -106.045)
		(end 24.892 -106.68)
		(width 0.11938)
		(layer "B.Cu")
		(net "SMA1_LED_BLUE_N")
	)
	(segment
		(start 59.944 -98.805746)
		(end 59.944 -106.68762)
		(width 0.11938)
		(layer "B.Cu")
		(net "SMA1_LED_BLUE_N")
	)
	(segment
		(start 59.944 -106.68762)
		(end 59.57062 -107.061)
		(width 0.11938)
		(layer "B.Cu")
		(net "SMA1_LED_BLUE_N")
	)
	(segment
		(start 26.289 -106.045)
		(end 25.527 -106.045)
		(width 0.11938)
		(layer "B.Cu")
		(net "SMA1_LED_BLUE_N")
	)
	(segment
		(start 83.86445 -91.992704)
		(end 83.86445 -91.657424)
		(width 0.11938)
		(layer "B.Cu")
		(net "SMA1_LED_BLUE_N")
	)
	(segment
		(start 103.505 -104.775)
		(end 99.307396 -104.775)
		(width 0.11938)
		(layer "B.Cu")
		(net "SMA1_LED_BLUE_N")
	)
	(segment
		(start 83.86445 -91.657424)
		(end 83.094576 -90.88755)
		(width 0.11938)
		(layer "B.Cu")
		(net "SMA1_LED_BLUE_N")
	)
	(segment
		(start 84.835746 -92.964)
		(end 83.86445 -91.992704)
		(width 0.11938)
		(layer "B.Cu")
		(net "SMA1_LED_BLUE_N")
	)
	(segment
		(start 94.60738 -100.074984)
		(end 94.60738 -96.167194)
		(width 0.11938)
		(layer "B.Cu")
		(net "SMA1_LED_BLUE_N")
	)
	(segment
		(start 83.094576 -90.88755)
		(end 72.94245 -90.88755)
		(width 0.11938)
		(layer "B.Cu")
		(net "SMA1_LED_BLUE_N")
	)
	(segment
		(start 59.57062 -107.061)
		(end 27.305 -107.061)
		(width 0.11938)
		(layer "B.Cu")
		(net "SMA1_LED_BLUE_N")
	)
	(segment
		(start 99.307396 -104.775)
		(end 94.60738 -100.074984)
		(width 0.11938)
		(layer "B.Cu")
		(net "SMA1_LED_BLUE_N")
	)
	(segment
		(start 68.58 -95.25)
		(end 63.499746 -95.25)
		(width 0.11938)
		(layer "B.Cu")
		(net "SMA1_LED_BLUE_N")
	)
	(segment
		(start 91.404186 -92.964)
		(end 84.835746 -92.964)
		(width 0.11938)
		(layer "B.Cu")
		(net "SMA1_LED_BLUE_N")
	)
	(segment
		(start 94.60738 -96.167194)
		(end 91.404186 -92.964)
		(width 0.11938)
		(layer "B.Cu")
		(net "SMA1_LED_BLUE_N")
	)
	(segment
		(start 72.94245 -90.88755)
		(end 68.58 -95.25)
		(width 0.11938)
		(layer "B.Cu")
		(net "SMA1_LED_BLUE_N")
	)
	(segment
		(start 63.499746 -95.25)
		(end 59.944 -98.805746)
		(width 0.11938)
		(layer "B.Cu")
		(net "SMA1_LED_BLUE_N")
	)
	(segment
		(start 105.156 -106.426)
		(end 103.505 -104.775)
		(width 0.11938)
		(layer "B.Cu")
		(net "SMA1_LED_BLUE_N")
	)
	(segment
		(start 27.305 -107.061)
		(end 26.289 -106.045)
		(width 0.11938)
		(layer "B.Cu")
		(net "SMA1_LED_BLUE_N")
	)
	(segment
		(start 6.349746 -69.596)
		(end 4.191 -69.596)
		(width 0.127)
		(layer "In2.Cu")
		(net "SMA1_LED_BLUE_N")
	)
	(segment
		(start 2.921 -70.866)
		(end 2.286 -70.866)
		(width 0.127)
		(layer "In2.Cu")
		(net "SMA1_LED_BLUE_N")
	)
	(segment
		(start 4.8514 -37.794692)
		(end 9.017 -41.960292)
		(width 0.127)
		(layer "In2.Cu")
		(net "SMA1_LED_BLUE_N")
	)
	(segment
		(start 7.175246 -68.7705)
		(end 6.349746 -69.596)
		(width 0.127)
		(layer "In2.Cu")
		(net "SMA1_LED_BLUE_N")
	)
	(segment
		(start 9.271 -67.818)
		(end 8.3185 -68.7705)
		(width 0.127)
		(layer "In2.Cu")
		(net "SMA1_LED_BLUE_N")
	)
	(segment
		(start 8.3185 -68.7705)
		(end 7.175246 -68.7705)
		(width 0.127)
		(layer "In2.Cu")
		(net "SMA1_LED_BLUE_N")
	)
	(segment
		(start 9.271 -65.882012)
		(end 9.271 -67.818)
		(width 0.127)
		(layer "In2.Cu")
		(net "SMA1_LED_BLUE_N")
	)
	(segment
		(start 9.017 -65.628012)
		(end 9.271 -65.882012)
		(width 0.127)
		(layer "In2.Cu")
		(net "SMA1_LED_BLUE_N")
	)
	(segment
		(start 9.017 -41.960292)
		(end 9.017 -65.628012)
		(width 0.127)
		(layer "In2.Cu")
		(net "SMA1_LED_BLUE_N")
	)
	(segment
		(start 4.191 -69.596)
		(end 2.921 -70.866)
		(width 0.127)
		(layer "In2.Cu")
		(net "SMA1_LED_BLUE_N")
	)
	(segment
		(start 1.651 -71.501)
		(end 2.286 -70.866)
		(width 0.127)
		(layer "In7.Cu")
		(net "SMA1_LED_BLUE_N")
	)
	(segment
		(start 12.7762 -94.4372)
		(end 9.144 -90.805)
		(width 0.127)
		(layer "In7.Cu")
		(net "SMA1_LED_BLUE_N")
	)
	(segment
		(start 22.479 -109.093)
		(end 15.20952 -109.093)
		(width 0.127)
		(layer "In7.Cu")
		(net "SMA1_LED_BLUE_N")
	)
	(segment
		(start 24.892 -106.68)
		(end 22.479 -109.093)
		(width 0.127)
		(layer "In7.Cu")
		(net "SMA1_LED_BLUE_N")
	)
	(segment
		(start 3.175 -90.805)
		(end 1.651 -89.281)
		(width 0.127)
		(layer "In7.Cu")
		(net "SMA1_LED_BLUE_N")
	)
	(segment
		(start 15.20952 -109.093)
		(end 12.7762 -106.65968)
		(width 0.127)
		(layer "In7.Cu")
		(net "SMA1_LED_BLUE_N")
	)
	(segment
		(start 12.7762 -106.65968)
		(end 12.7762 -94.4372)
		(width 0.127)
		(layer "In7.Cu")
		(net "SMA1_LED_BLUE_N")
	)
	(segment
		(start 1.651 -89.281)
		(end 1.651 -71.501)
		(width 0.127)
		(layer "In7.Cu")
		(net "SMA1_LED_BLUE_N")
	)
	(segment
		(start 9.144 -90.805)
		(end 3.175 -90.805)
		(width 0.127)
		(layer "In7.Cu")
		(net "SMA1_LED_BLUE_N")
	)
	(segment
		(start 104.257602 -97.282)
		(end 104.257602 -98.98126)
		(width 0.11938)
		(layer "F.Cu")
		(net "GPS_SMA_LED_RED_N")
	)
	(segment
		(start 8.382 -81.0006)
		(end 8.382 -79.883)
		(width 0.11938)
		(layer "F.Cu")
		(net "GPS_SMA_LED_RED_N")
	)
	(via
		(at 104.257602 -97.282)
		(size 0.4572)
		(drill 0.2032)
		(layers "F.Cu" "B.Cu")
		(net "GPS_SMA_LED_RED_N")
	)
	(via
		(at 8.382 -79.883)
		(size 0.508)
		(drill 0.254)
		(layers "F.Cu" "B.Cu")
		(net "GPS_SMA_LED_RED_N")
	)
	(segment
		(start 92.329 -96.40951)
		(end 89.13749 -93.218)
		(width 0.127)
		(layer "In7.Cu")
		(net "GPS_SMA_LED_RED_N")
	)
	(segment
		(start 103.622602 -96.647)
		(end 102.616 -96.647)
		(width 0.127)
		(layer "In7.Cu")
		(net "GPS_SMA_LED_RED_N")
	)
	(segment
		(start 82.21853 -93.218)
		(end 81.346294 -92.345764)
		(width 0.127)
		(layer "In7.Cu")
		(net "GPS_SMA_LED_RED_N")
	)
	(segment
		(start 92.329 -97.75571)
		(end 92.329 -96.40951)
		(width 0.127)
		(layer "In7.Cu")
		(net "GPS_SMA_LED_RED_N")
	)
	(segment
		(start 45.974 -83.058)
		(end 40.4876 -77.5716)
		(width 0.127)
		(layer "In7.Cu")
		(net "GPS_SMA_LED_RED_N")
	)
	(segment
		(start 98.07829 -103.505)
		(end 92.329 -97.75571)
		(width 0.127)
		(layer "In7.Cu")
		(net "GPS_SMA_LED_RED_N")
	)
	(segment
		(start 9.4615 -77.5335)
		(end 9.4615 -78.8035)
		(width 0.127)
		(layer "In7.Cu")
		(net "GPS_SMA_LED_RED_N")
	)
	(segment
		(start 10.668 -76.327)
		(end 9.4615 -77.5335)
		(width 0.127)
		(layer "In7.Cu")
		(net "GPS_SMA_LED_RED_N")
	)
	(segment
		(start 20.32 -75.819)
		(end 17.28597 -75.819)
		(width 0.127)
		(layer "In7.Cu")
		(net "GPS_SMA_LED_RED_N")
	)
	(segment
		(start 16.77797 -76.327)
		(end 10.668 -76.327)
		(width 0.127)
		(layer "In7.Cu")
		(net "GPS_SMA_LED_RED_N")
	)
	(segment
		(start 22.6695 -78.1685)
		(end 20.32 -75.819)
		(width 0.127)
		(layer "In7.Cu")
		(net "GPS_SMA_LED_RED_N")
	)
	(segment
		(start 102.736396 -98.545396)
		(end 102.736396 -102.11435)
		(width 0.127)
		(layer "In7.Cu")
		(net "GPS_SMA_LED_RED_N")
	)
	(segment
		(start 36.012882 -77.5716)
		(end 35.822382 -77.3811)
		(width 0.127)
		(layer "In7.Cu")
		(net "GPS_SMA_LED_RED_N")
	)
	(segment
		(start 51.054 -93.472)
		(end 45.974 -88.392)
		(width 0.127)
		(layer "In7.Cu")
		(net "GPS_SMA_LED_RED_N")
	)
	(segment
		(start 9.4615 -78.8035)
		(end 8.382 -79.883)
		(width 0.127)
		(layer "In7.Cu")
		(net "GPS_SMA_LED_RED_N")
	)
	(segment
		(start 17.28597 -75.819)
		(end 16.77797 -76.327)
		(width 0.127)
		(layer "In7.Cu")
		(net "GPS_SMA_LED_RED_N")
	)
	(segment
		(start 58.546746 -93.472)
		(end 51.054 -93.472)
		(width 0.127)
		(layer "In7.Cu")
		(net "GPS_SMA_LED_RED_N")
	)
	(segment
		(start 40.4876 -77.5716)
		(end 36.012882 -77.5716)
		(width 0.127)
		(layer "In7.Cu")
		(net "GPS_SMA_LED_RED_N")
	)
	(segment
		(start 102.616 -96.647)
		(end 102.362 -96.901)
		(width 0.127)
		(layer "In7.Cu")
		(net "GPS_SMA_LED_RED_N")
	)
	(segment
		(start 59.672982 -92.345764)
		(end 58.546746 -93.472)
		(width 0.127)
		(layer "In7.Cu")
		(net "GPS_SMA_LED_RED_N")
	)
	(segment
		(start 35.822382 -77.3811)
		(end 32.7279 -77.3811)
		(width 0.127)
		(layer "In7.Cu")
		(net "GPS_SMA_LED_RED_N")
	)
	(segment
		(start 81.346294 -92.345764)
		(end 59.672982 -92.345764)
		(width 0.127)
		(layer "In7.Cu")
		(net "GPS_SMA_LED_RED_N")
	)
	(segment
		(start 101.345746 -103.505)
		(end 98.07829 -103.505)
		(width 0.127)
		(layer "In7.Cu")
		(net "GPS_SMA_LED_RED_N")
	)
	(segment
		(start 104.257602 -97.282)
		(end 103.622602 -96.647)
		(width 0.127)
		(layer "In7.Cu")
		(net "GPS_SMA_LED_RED_N")
	)
	(segment
		(start 32.7279 -77.3811)
		(end 32.1818 -76.835)
		(width 0.127)
		(layer "In7.Cu")
		(net "GPS_SMA_LED_RED_N")
	)
	(segment
		(start 27.922982 -78.1685)
		(end 22.6695 -78.1685)
		(width 0.127)
		(layer "In7.Cu")
		(net "GPS_SMA_LED_RED_N")
	)
	(segment
		(start 102.362 -98.171)
		(end 102.736396 -98.545396)
		(width 0.127)
		(layer "In7.Cu")
		(net "GPS_SMA_LED_RED_N")
	)
	(segment
		(start 102.736396 -102.11435)
		(end 101.345746 -103.505)
		(width 0.127)
		(layer "In7.Cu")
		(net "GPS_SMA_LED_RED_N")
	)
	(segment
		(start 102.362 -96.901)
		(end 102.362 -98.171)
		(width 0.127)
		(layer "In7.Cu")
		(net "GPS_SMA_LED_RED_N")
	)
	(segment
		(start 89.13749 -93.218)
		(end 82.21853 -93.218)
		(width 0.127)
		(layer "In7.Cu")
		(net "GPS_SMA_LED_RED_N")
	)
	(segment
		(start 45.974 -88.392)
		(end 45.974 -83.058)
		(width 0.127)
		(layer "In7.Cu")
		(net "GPS_SMA_LED_RED_N")
	)
	(segment
		(start 32.1818 -76.835)
		(end 29.256482 -76.835)
		(width 0.127)
		(layer "In7.Cu")
		(net "GPS_SMA_LED_RED_N")
	)
	(segment
		(start 29.256482 -76.835)
		(end 27.922982 -78.1685)
		(width 0.127)
		(layer "In7.Cu")
		(net "GPS_SMA_LED_RED_N")
	)
	(segment
		(start 103.757476 -98.051874)
		(end 102.987602 -97.282)
		(width 0.11938)
		(layer "F.Cu")
		(net "GPS_SMA_LED_GREEN_N")
	)
	(segment
		(start 10.922 -81.0006)
		(end 10.922 -79.883)
		(width 0.11938)
		(layer "F.Cu")
		(net "GPS_SMA_LED_GREEN_N")
	)
	(segment
		(start 103.757476 -98.94316)
		(end 103.757476 -98.051874)
		(width 0.11938)
		(layer "F.Cu")
		(net "GPS_SMA_LED_GREEN_N")
	)
	(via
		(at 10.922 -79.883)
		(size 0.508)
		(drill 0.254)
		(layers "F.Cu" "B.Cu")
		(net "GPS_SMA_LED_GREEN_N")
	)
	(via
		(at 102.987602 -97.282)
		(size 0.4572)
		(drill 0.2032)
		(layers "F.Cu" "B.Cu")
		(net "GPS_SMA_LED_GREEN_N")
	)
	(segment
		(start 43.18 -81.026)
		(end 43.18 -82.169)
		(width 0.127)
		(layer "In7.Cu")
		(net "GPS_SMA_LED_GREEN_N")
	)
	(segment
		(start 37.4777 -78.5495)
		(end 38.0238 -78.0034)
		(width 0.127)
		(layer "In7.Cu")
		(net "GPS_SMA_LED_GREEN_N")
	)
	(segment
		(start 88.979502 -93.599)
		(end 91.948 -96.567498)
		(width 0.127)
		(layer "In7.Cu")
		(net "GPS_SMA_LED_GREEN_N")
	)
	(segment
		(start 97.920302 -103.886)
		(end 101.599492 -103.886)
		(width 0.127)
		(layer "In7.Cu")
		(net "GPS_SMA_LED_GREEN_N")
	)
	(segment
		(start 17.42694 -77.216)
		(end 21.178012 -77.216)
		(width 0.127)
		(layer "In7.Cu")
		(net "GPS_SMA_LED_GREEN_N")
	)
	(segment
		(start 50.8 -93.853)
		(end 59.182 -93.853)
		(width 0.127)
		(layer "In7.Cu")
		(net "GPS_SMA_LED_GREEN_N")
	)
	(segment
		(start 16.91894 -76.708)
		(end 17.42694 -77.216)
		(width 0.127)
		(layer "In7.Cu")
		(net "GPS_SMA_LED_GREEN_N")
	)
	(segment
		(start 91.948 -96.567498)
		(end 91.948 -97.913698)
		(width 0.127)
		(layer "In7.Cu")
		(net "GPS_SMA_LED_GREEN_N")
	)
	(segment
		(start 103.185214 -102.300278)
		(end 103.185214 -97.479612)
		(width 0.127)
		(layer "In7.Cu")
		(net "GPS_SMA_LED_GREEN_N")
	)
	(segment
		(start 60.308236 -92.726764)
		(end 81.188306 -92.726764)
		(width 0.127)
		(layer "In7.Cu")
		(net "GPS_SMA_LED_GREEN_N")
	)
	(segment
		(start 103.185214 -97.479612)
		(end 102.987602 -97.282)
		(width 0.127)
		(layer "In7.Cu")
		(net "GPS_SMA_LED_GREEN_N")
	)
	(segment
		(start 40.1574 -78.0034)
		(end 43.18 -81.026)
		(width 0.127)
		(layer "In7.Cu")
		(net "GPS_SMA_LED_GREEN_N")
	)
	(segment
		(start 45.466 -88.519)
		(end 50.8 -93.853)
		(width 0.127)
		(layer "In7.Cu")
		(net "GPS_SMA_LED_GREEN_N")
	)
	(segment
		(start 59.182 -93.853)
		(end 60.308236 -92.726764)
		(width 0.127)
		(layer "In7.Cu")
		(net "GPS_SMA_LED_GREEN_N")
	)
	(segment
		(start 45.466 -84.455)
		(end 45.466 -88.519)
		(width 0.127)
		(layer "In7.Cu")
		(net "GPS_SMA_LED_GREEN_N")
	)
	(segment
		(start 101.599492 -103.886)
		(end 103.185214 -102.300278)
		(width 0.127)
		(layer "In7.Cu")
		(net "GPS_SMA_LED_GREEN_N")
	)
	(segment
		(start 38.0238 -78.0034)
		(end 40.1574 -78.0034)
		(width 0.127)
		(layer "In7.Cu")
		(net "GPS_SMA_LED_GREEN_N")
	)
	(segment
		(start 22.511512 -78.5495)
		(end 37.4777 -78.5495)
		(width 0.127)
		(layer "In7.Cu")
		(net "GPS_SMA_LED_GREEN_N")
	)
	(segment
		(start 81.188306 -92.726764)
		(end 82.060542 -93.599)
		(width 0.127)
		(layer "In7.Cu")
		(net "GPS_SMA_LED_GREEN_N")
	)
	(segment
		(start 82.060542 -93.599)
		(end 88.979502 -93.599)
		(width 0.127)
		(layer "In7.Cu")
		(net "GPS_SMA_LED_GREEN_N")
	)
	(segment
		(start 91.948 -97.913698)
		(end 97.920302 -103.886)
		(width 0.127)
		(layer "In7.Cu")
		(net "GPS_SMA_LED_GREEN_N")
	)
	(segment
		(start 14.097 -76.708)
		(end 16.91894 -76.708)
		(width 0.127)
		(layer "In7.Cu")
		(net "GPS_SMA_LED_GREEN_N")
	)
	(segment
		(start 21.178012 -77.216)
		(end 22.511512 -78.5495)
		(width 0.127)
		(layer "In7.Cu")
		(net "GPS_SMA_LED_GREEN_N")
	)
	(segment
		(start 10.922 -79.883)
		(end 14.097 -76.708)
		(width 0.127)
		(layer "In7.Cu")
		(net "GPS_SMA_LED_GREEN_N")
	)
	(segment
		(start 43.18 -82.169)
		(end 45.466 -84.455)
		(width 0.127)
		(layer "In7.Cu")
		(net "GPS_SMA_LED_GREEN_N")
	)
	(segment
		(start 4.572 -81.0006)
		(end 4.572 -79.883)
		(width 0.11938)
		(layer "F.Cu")
		(net "GPS_SMA_LED_BLUE_N")
	)
	(segment
		(start 104.757474 -98.98126)
		(end 104.757474 -98.052128)
		(width 0.11938)
		(layer "F.Cu")
		(net "GPS_SMA_LED_BLUE_N")
	)
	(segment
		(start 104.757474 -98.052128)
		(end 105.527602 -97.282)
		(width 0.11938)
		(layer "F.Cu")
		(net "GPS_SMA_LED_BLUE_N")
	)
	(via
		(at 105.527602 -97.282)
		(size 0.4572)
		(drill 0.2032)
		(layers "F.Cu" "B.Cu")
		(net "GPS_SMA_LED_BLUE_N")
	)
	(via
		(at 4.572 -79.883)
		(size 0.508)
		(drill 0.254)
		(layers "F.Cu" "B.Cu")
		(net "GPS_SMA_LED_BLUE_N")
	)
	(segment
		(start 102.362 -96.266)
		(end 101.727 -96.901)
		(width 0.127)
		(layer "In7.Cu")
		(net "GPS_SMA_LED_BLUE_N")
	)
	(segment
		(start 46.482 -88.265)
		(end 46.482 -82.931)
		(width 0.127)
		(layer "In7.Cu")
		(net "GPS_SMA_LED_BLUE_N")
	)
	(segment
		(start 101.727 -98.298)
		(end 102.108 -98.679)
		(width 0.127)
		(layer "In7.Cu")
		(net "GPS_SMA_LED_BLUE_N")
	)
	(segment
		(start 92.837 -96.378522)
		(end 89.295478 -92.837)
		(width 0.127)
		(layer "In7.Cu")
		(net "GPS_SMA_LED_BLUE_N")
	)
	(segment
		(start 8.89 -75.946)
		(end 7.112 -77.724)
		(width 0.127)
		(layer "In7.Cu")
		(net "GPS_SMA_LED_BLUE_N")
	)
	(segment
		(start 57.912 -92.964)
		(end 51.181 -92.964)
		(width 0.127)
		(layer "In7.Cu")
		(net "GPS_SMA_LED_BLUE_N")
	)
	(segment
		(start 22.76856 -76.2635)
		(end 21.399246 -76.2635)
		(width 0.127)
		(layer "In7.Cu")
		(net "GPS_SMA_LED_BLUE_N")
	)
	(segment
		(start 101.727 -96.901)
		(end 101.727 -98.298)
		(width 0.127)
		(layer "In7.Cu")
		(net "GPS_SMA_LED_BLUE_N")
	)
	(segment
		(start 36.14547 -77.1652)
		(end 35.98037 -77.0001)
		(width 0.127)
		(layer "In7.Cu")
		(net "GPS_SMA_LED_BLUE_N")
	)
	(segment
		(start 51.181 -92.964)
		(end 46.482 -88.265)
		(width 0.127)
		(layer "In7.Cu")
		(net "GPS_SMA_LED_BLUE_N")
	)
	(segment
		(start 32.885888 -77.0001)
		(end 32.339788 -76.454)
		(width 0.127)
		(layer "In7.Cu")
		(net "GPS_SMA_LED_BLUE_N")
	)
	(segment
		(start 17.127982 -75.438)
		(end 16.619982 -75.946)
		(width 0.127)
		(layer "In7.Cu")
		(net "GPS_SMA_LED_BLUE_N")
	)
	(segment
		(start 100.838 -103.124)
		(end 98.236278 -103.124)
		(width 0.127)
		(layer "In7.Cu")
		(net "GPS_SMA_LED_BLUE_N")
	)
	(segment
		(start 81.504282 -91.964764)
		(end 58.911236 -91.964764)
		(width 0.127)
		(layer "In7.Cu")
		(net "GPS_SMA_LED_BLUE_N")
	)
	(segment
		(start 35.98037 -77.0001)
		(end 32.885888 -77.0001)
		(width 0.127)
		(layer "In7.Cu")
		(net "GPS_SMA_LED_BLUE_N")
	)
	(segment
		(start 32.339788 -76.454)
		(end 29.311346 -76.454)
		(width 0.127)
		(layer "In7.Cu")
		(net "GPS_SMA_LED_BLUE_N")
	)
	(segment
		(start 82.376518 -92.837)
		(end 81.504282 -91.964764)
		(width 0.127)
		(layer "In7.Cu")
		(net "GPS_SMA_LED_BLUE_N")
	)
	(segment
		(start 4.572 -79.248)
		(end 4.572 -79.883)
		(width 0.127)
		(layer "In7.Cu")
		(net "GPS_SMA_LED_BLUE_N")
	)
	(segment
		(start 20.573746 -75.438)
		(end 17.127982 -75.438)
		(width 0.127)
		(layer "In7.Cu")
		(net "GPS_SMA_LED_BLUE_N")
	)
	(segment
		(start 92.837 -97.724722)
		(end 92.837 -96.378522)
		(width 0.127)
		(layer "In7.Cu")
		(net "GPS_SMA_LED_BLUE_N")
	)
	(segment
		(start 98.236278 -103.124)
		(end 92.837 -97.724722)
		(width 0.127)
		(layer "In7.Cu")
		(net "GPS_SMA_LED_BLUE_N")
	)
	(segment
		(start 7.112 -77.724)
		(end 6.096 -77.724)
		(width 0.127)
		(layer "In7.Cu")
		(net "GPS_SMA_LED_BLUE_N")
	)
	(segment
		(start 21.399246 -76.2635)
		(end 20.573746 -75.438)
		(width 0.127)
		(layer "In7.Cu")
		(net "GPS_SMA_LED_BLUE_N")
	)
	(segment
		(start 23.72106 -77.216)
		(end 22.76856 -76.2635)
		(width 0.127)
		(layer "In7.Cu")
		(net "GPS_SMA_LED_BLUE_N")
	)
	(segment
		(start 89.295478 -92.837)
		(end 82.376518 -92.837)
		(width 0.127)
		(layer "In7.Cu")
		(net "GPS_SMA_LED_BLUE_N")
	)
	(segment
		(start 6.096 -77.724)
		(end 4.572 -79.248)
		(width 0.127)
		(layer "In7.Cu")
		(net "GPS_SMA_LED_BLUE_N")
	)
	(segment
		(start 28.803346 -75.946)
		(end 25.781 -75.946)
		(width 0.127)
		(layer "In7.Cu")
		(net "GPS_SMA_LED_BLUE_N")
	)
	(segment
		(start 105.527602 -97.282)
		(end 104.511602 -96.266)
		(width 0.127)
		(layer "In7.Cu")
		(net "GPS_SMA_LED_BLUE_N")
	)
	(segment
		(start 102.108 -98.679)
		(end 102.108 -101.854)
		(width 0.127)
		(layer "In7.Cu")
		(net "GPS_SMA_LED_BLUE_N")
	)
	(segment
		(start 29.311346 -76.454)
		(end 28.803346 -75.946)
		(width 0.127)
		(layer "In7.Cu")
		(net "GPS_SMA_LED_BLUE_N")
	)
	(segment
		(start 104.511602 -96.266)
		(end 102.362 -96.266)
		(width 0.127)
		(layer "In7.Cu")
		(net "GPS_SMA_LED_BLUE_N")
	)
	(segment
		(start 16.619982 -75.946)
		(end 8.89 -75.946)
		(width 0.127)
		(layer "In7.Cu")
		(net "GPS_SMA_LED_BLUE_N")
	)
	(segment
		(start 24.511 -77.216)
		(end 23.72106 -77.216)
		(width 0.127)
		(layer "In7.Cu")
		(net "GPS_SMA_LED_BLUE_N")
	)
	(segment
		(start 25.781 -75.946)
		(end 24.511 -77.216)
		(width 0.127)
		(layer "In7.Cu")
		(net "GPS_SMA_LED_BLUE_N")
	)
	(segment
		(start 46.482 -82.931)
		(end 40.7162 -77.1652)
		(width 0.127)
		(layer "In7.Cu")
		(net "GPS_SMA_LED_BLUE_N")
	)
	(segment
		(start 102.108 -101.854)
		(end 100.838 -103.124)
		(width 0.127)
		(layer "In7.Cu")
		(net "GPS_SMA_LED_BLUE_N")
	)
	(segment
		(start 58.911236 -91.964764)
		(end 57.912 -92.964)
		(width 0.127)
		(layer "In7.Cu")
		(net "GPS_SMA_LED_BLUE_N")
	)
	(segment
		(start 40.7162 -77.1652)
		(end 36.14547 -77.1652)
		(width 0.127)
		(layer "In7.Cu")
		(net "GPS_SMA_LED_BLUE_N")
	)
	(segment
		(start 22.098 -70.358)
		(end 21.6154 -70.8406)
		(width 0.381)
		(layer "F.Cu")
		(net "XP1R8V_ICP10100")
	)
	(segment
		(start 19.544792 -64.135)
		(end 18.6944 -64.135)
		(width 0.381)
		(layer "F.Cu")
		(net "XP1R8V_ICP10100")
	)
	(segment
		(start 18.1356 -58.2676)
		(end 19.2532 -58.2676)
		(width 0.381)
		(layer "F.Cu")
		(net "XP1R8V_ICP10100")
	)
	(segment
		(start 22.098 -68.9356)
		(end 22.098 -70.358)
		(width 0.381)
		(layer "F.Cu")
		(net "XP1R8V_ICP10100")
	)
	(segment
		(start 21.6154 -70.8406)
		(end 20.484592 -70.8406)
		(width 0.381)
		(layer "F.Cu")
		(net "XP1R8V_ICP10100")
	)
	(segment
		(start 19.2532 -58.2676)
		(end 19.87804 -57.64276)
		(width 0.381)
		(layer "F.Cu")
		(net "XP1R8V_ICP10100")
	)
	(segment
		(start 16.318992 -66.3956)
		(end 16.318992 -65.532)
		(width 0.381)
		(layer "F.Cu")
		(net "XP1R8V_ICP10100")
	)
	(segment
		(start 17.4244 -69.596)
		(end 17.385792 -69.557392)
		(width 0.381)
		(layer "F.Cu")
		(net "XP1R8V_ICP10100")
	)
	(segment
		(start 22.1234 -68.9102)
		(end 22.098 -68.9356)
		(width 0.381)
		(layer "F.Cu")
		(net "XP1R8V_ICP10100")
	)
	(segment
		(start 18.1356 -58.2676)
		(end 18.1356 -59.1566)
		(width 0.381)
		(layer "F.Cu")
		(net "XP1R8V_ICP10100")
	)
	(segment
		(start 19.87804 -57.64276)
		(end 19.87804 -57.0611)
		(width 0.381)
		(layer "F.Cu")
		(net "XP1R8V_ICP10100")
	)
	(segment
		(start 17.385792 -69.557392)
		(end 17.385792 -68.8086)
		(width 0.381)
		(layer "F.Cu")
		(net "XP1R8V_ICP10100")
	)
	(via
		(at 22.1234 -68.9102)
		(size 0.4572)
		(drill 0.2032)
		(layers "F.Cu" "B.Cu")
		(net "XP1R8V_ICP10100")
	)
	(via
		(at 16.318992 -65.532)
		(size 0.508)
		(drill 0.254)
		(layers "F.Cu" "B.Cu")
		(net "XP1R8V_ICP10100")
	)
	(via
		(at 18.6944 -64.135)
		(size 0.4572)
		(drill 0.2032)
		(layers "F.Cu" "B.Cu")
		(net "XP1R8V_ICP10100")
	)
	(via
		(at 17.4244 -69.596)
		(size 0.4572)
		(drill 0.2032)
		(layers "F.Cu" "B.Cu")
		(net "XP1R8V_ICP10100")
	)
	(via
		(at 22.0726 -67.8688)
		(size 0.508)
		(drill 0.254)
		(layers "F.Cu" "B.Cu")
		(net "XP1R8V_ICP10100")
	)
	(via
		(at 18.1356 -59.1566)
		(size 0.508)
		(drill 0.254)
		(layers "F.Cu" "B.Cu")
		(net "XP1R8V_ICP10100")
	)
	(segment
		(start 18.8976 -63.9318)
		(end 18.6944 -64.135)
		(width 0.381)
		(layer "In7.Cu")
		(net "XP1R8V_ICP10100")
	)
	(segment
		(start 18.1356 -59.1566)
		(end 18.8976 -59.9186)
		(width 0.381)
		(layer "In7.Cu")
		(net "XP1R8V_ICP10100")
	)
	(segment
		(start 18.8976 -59.9186)
		(end 18.8976 -63.9318)
		(width 0.381)
		(layer "In7.Cu")
		(net "XP1R8V_ICP10100")
	)
	(segment
		(start 87.807292 -63.7286)
		(end 88.6714 -63.7286)
		(width 0.381)
		(layer "F.Cu")
		(net "VDD_BNO085")
	)
	(segment
		(start 88.6714 -62.915292)
		(end 88.6714 -63.7286)
		(width 0.381)
		(layer "F.Cu")
		(net "VDD_BNO085")
	)
	(segment
		(start 86.355936 -61.088016)
		(end 86.355936 -62.225936)
		(width 0.254)
		(layer "F.Cu")
		(net "VDD_BNO085")
	)
	(segment
		(start 88.2015 -60.5155)
		(end 87.678768 -60.515754)
		(width 0.254)
		(layer "F.Cu")
		(net "VDD_BNO085")
	)
	(segment
		(start 88.519 -60.833)
		(end 88.2015 -60.5155)
		(width 0.254)
		(layer "F.Cu")
		(net "VDD_BNO085")
	)
	(segment
		(start 87.678768 -60.515754)
		(end 87.668608 -60.52566)
		(width 0.254)
		(layer "F.Cu")
		(net "VDD_BNO085")
	)
	(via
		(at 87.0966 -62.6872)
		(size 0.4572)
		(drill 0.2032)
		(layers "F.Cu" "B.Cu")
		(net "VDD_BNO085")
	)
	(segment
		(start 89.154 -59.243722)
		(end 88.711278 -59.243722)
		(width 0.11938)
		(layer "F.Cu")
		(net "UNNAMED_9_BNO080LGA28_I29_XOUT3")
	)
	(segment
		(start 91.857322 -59.599322)
		(end 92.372942 -59.599322)
		(width 0.11938)
		(layer "F.Cu")
		(net "UNNAMED_9_BNO080LGA28_I29_XOUT3")
	)
	(segment
		(start 90.678 -59.243722)
		(end 89.154 -59.243722)
		(width 0.11938)
		(layer "F.Cu")
		(net "UNNAMED_9_BNO080LGA28_I29_XOUT3")
	)
	(segment
		(start 90.678 -59.243722)
		(end 91.501722 -59.243722)
		(width 0.11938)
		(layer "F.Cu")
		(net "UNNAMED_9_BNO080LGA28_I29_XOUT3")
	)
	(segment
		(start 88.711278 -59.243722)
		(end 88.429338 -59.525662)
		(width 0.11938)
		(layer "F.Cu")
		(net "UNNAMED_9_BNO080LGA28_I29_XOUT3")
	)
	(segment
		(start 91.501722 -59.243722)
		(end 91.857322 -59.599322)
		(width 0.11938)
		(layer "F.Cu")
		(net "UNNAMED_9_BNO080LGA28_I29_XOUT3")
	)
	(segment
		(start 88.429338 -59.525662)
		(end 87.668608 -59.525662)
		(width 0.11938)
		(layer "F.Cu")
		(net "UNNAMED_9_BNO080LGA28_I29_XOUT3")
	)
	(via
		(at 89.154 -59.243722)
		(size 0.508)
		(drill 0.254)
		(layers "F.Cu" "B.Cu")
		(net "UNNAMED_9_BNO080LGA28_I29_XOUT3")
	)
	(segment
		(start 88.138 -59.2836)
		(end 89.114122 -59.2836)
		(width 0.11938)
		(layer "B.Cu")
		(net "UNNAMED_9_BNO080LGA28_I29_XOUT3")
	)
	(segment
		(start 89.114122 -59.2836)
		(end 89.154 -59.243722)
		(width 0.11938)
		(layer "B.Cu")
		(net "UNNAMED_9_BNO080LGA28_I29_XOUT3")
	)
	(segment
		(start 84.1756 -61.7728)
		(end 85.0392 -61.7728)
		(width 0.11938)
		(layer "F.Cu")
		(net "UNNAMED_9_BNO080LGA28_I29_PS1")
	)
	(segment
		(start 83.2612 -62.6872)
		(end 84.1756 -61.7728)
		(width 0.11938)
		(layer "F.Cu")
		(net "UNNAMED_9_BNO080LGA28_I29_PS1")
	)
	(segment
		(start 83.439 -63.2968)
		(end 83.2612 -63.119)
		(width 0.11938)
		(layer "F.Cu")
		(net "UNNAMED_9_BNO080LGA28_I29_PS1")
	)
	(segment
		(start 85.355938 -61.456062)
		(end 85.355938 -61.088016)
		(width 0.11938)
		(layer "F.Cu")
		(net "UNNAMED_9_BNO080LGA28_I29_PS1")
	)
	(segment
		(start 85.0392 -61.7728)
		(end 85.355938 -61.456062)
		(width 0.11938)
		(layer "F.Cu")
		(net "UNNAMED_9_BNO080LGA28_I29_PS1")
	)
	(segment
		(start 83.2612 -63.119)
		(end 83.2612 -62.6872)
		(width 0.11938)
		(layer "F.Cu")
		(net "UNNAMED_9_BNO080LGA28_I29_PS1")
	)
	(segment
		(start 83.439 -63.7794)
		(end 83.439 -63.2968)
		(width 0.11938)
		(layer "F.Cu")
		(net "UNNAMED_9_BNO080LGA28_I29_PS1")
	)
	(via
		(at 83.2612 -62.6872)
		(size 0.4572)
		(drill 0.2032)
		(layers "F.Cu" "B.Cu")
		(net "UNNAMED_9_BNO080LGA28_I29_PS1")
	)
	(segment
		(start 82.6008 -64.4652)
		(end 82.6008 -62.4332)
		(width 0.11938)
		(layer "F.Cu")
		(net "UNNAMED_9_BNO080LGA28_I29_PS0")
	)
	(segment
		(start 84.008468 -61.025532)
		(end 84.543392 -61.025532)
		(width 0.11938)
		(layer "F.Cu")
		(net "UNNAMED_9_BNO080LGA28_I29_PS0")
	)
	(segment
		(start 81.3054 -65.2526)
		(end 81.8134 -65.2526)
		(width 0.11938)
		(layer "F.Cu")
		(net "UNNAMED_9_BNO080LGA28_I29_PS0")
	)
	(segment
		(start 81.8134 -65.2526)
		(end 82.3722 -64.6938)
		(width 0.11938)
		(layer "F.Cu")
		(net "UNNAMED_9_BNO080LGA28_I29_PS0")
	)
	(segment
		(start 82.6008 -62.4332)
		(end 84.008468 -61.025532)
		(width 0.11938)
		(layer "F.Cu")
		(net "UNNAMED_9_BNO080LGA28_I29_PS0")
	)
	(segment
		(start 82.3722 -64.6938)
		(end 82.6008 -64.4652)
		(width 0.11938)
		(layer "F.Cu")
		(net "UNNAMED_9_BNO080LGA28_I29_PS0")
	)
	(via
		(at 82.3722 -64.6938)
		(size 0.4572)
		(drill 0.2032)
		(layers "F.Cu" "B.Cu")
		(net "UNNAMED_9_BNO080LGA28_I29_PS0")
	)
	(segment
		(start 86.355936 -55.113936)
		(end 86.355936 -56.463184)
		(width 0.11938)
		(layer "F.Cu")
		(net "UNNAMED_9_BNO080LGA28_I29_HCS")
	)
	(segment
		(start 85.979 -54.229)
		(end 85.979 -54.737)
		(width 0.11938)
		(layer "F.Cu")
		(net "UNNAMED_9_BNO080LGA28_I29_HCS")
	)
	(segment
		(start 85.979 -54.737)
		(end 86.355936 -55.113936)
		(width 0.11938)
		(layer "F.Cu")
		(net "UNNAMED_9_BNO080LGA28_I29_HCS")
	)
	(segment
		(start 82.296 -59.944)
		(end 82.296 -60.833)
		(width 0.11938)
		(layer "F.Cu")
		(net "UNNAMED_9_BNO080LGA28_I29_CLKSE")
	)
	(segment
		(start 84.543392 -59.025536)
		(end 84.083398 -59.025536)
		(width 0.11938)
		(layer "F.Cu")
		(net "UNNAMED_9_BNO080LGA28_I29_CLKSE")
	)
	(segment
		(start 84.083398 -59.025536)
		(end 83.164934 -59.944)
		(width 0.11938)
		(layer "F.Cu")
		(net "UNNAMED_9_BNO080LGA28_I29_CLKSE")
	)
	(segment
		(start 83.164934 -59.944)
		(end 82.296 -59.944)
		(width 0.11938)
		(layer "F.Cu")
		(net "UNNAMED_9_BNO080LGA28_I29_CLKSE")
	)
	(segment
		(start 81.3054 -62.9666)
		(end 81.3054 -61.8236)
		(width 0.11938)
		(layer "F.Cu")
		(net "UNNAMED_9_BNO080LGA28_I29_CLKSE")
	)
	(segment
		(start 82.296 -60.833)
		(end 81.3054 -61.8236)
		(width 0.11938)
		(layer "F.Cu")
		(net "UNNAMED_9_BNO080LGA28_I29_CLKSE")
	)
	(via
		(at 82.296 -59.944)
		(size 0.4572)
		(drill 0.2032)
		(layers "F.Cu" "B.Cu")
		(net "UNNAMED_9_BNO080LGA28_I29_CLKSE")
	)
	(segment
		(start 84.111338 -59.525662)
		(end 83.439 -60.198)
		(width 0.11938)
		(layer "F.Cu")
		(net "UNNAMED_9_BNO080LGA28_I29_CAP")
	)
	(segment
		(start 82.042 -63.373)
		(end 81.3054 -64.1096)
		(width 0.11938)
		(layer "F.Cu")
		(net "UNNAMED_9_BNO080LGA28_I29_CAP")
	)
	(segment
		(start 83.439 -60.61583)
		(end 83.35137 -60.61583)
		(width 0.11938)
		(layer "F.Cu")
		(net "UNNAMED_9_BNO080LGA28_I29_CAP")
	)
	(segment
		(start 83.35137 -60.61583)
		(end 82.042 -61.9252)
		(width 0.11938)
		(layer "F.Cu")
		(net "UNNAMED_9_BNO080LGA28_I29_CAP")
	)
	(segment
		(start 82.042 -61.9252)
		(end 82.042 -63.373)
		(width 0.11938)
		(layer "F.Cu")
		(net "UNNAMED_9_BNO080LGA28_I29_CAP")
	)
	(segment
		(start 84.543392 -59.525662)
		(end 84.111338 -59.525662)
		(width 0.11938)
		(layer "F.Cu")
		(net "UNNAMED_9_BNO080LGA28_I29_CAP")
	)
	(segment
		(start 83.439 -60.198)
		(end 83.439 -60.61583)
		(width 0.11938)
		(layer "F.Cu")
		(net "UNNAMED_9_BNO080LGA28_I29_CAP")
	)
	(via
		(at 83.439 -60.61583)
		(size 0.4572)
		(drill 0.2032)
		(layers "F.Cu" "B.Cu")
		(net "UNNAMED_9_BNO080LGA28_I29_CAP")
	)
	(segment
		(start 20.302728 -66.776346)
		(end 20.302728 -66.814446)
		(width 0.11938)
		(layer "F.Cu")
		(net "UNNAMED_8_ICP10100LGA10_I24_R_4")
	)
	(segment
		(start 21.1328 -66.1162)
		(end 20.962874 -66.1162)
		(width 0.11938)
		(layer "F.Cu")
		(net "UNNAMED_8_ICP10100LGA10_I24_R_4")
	)
	(segment
		(start 20.962874 -66.1162)
		(end 20.302728 -66.776346)
		(width 0.11938)
		(layer "F.Cu")
		(net "UNNAMED_8_ICP10100LGA10_I24_R_4")
	)
	(segment
		(start 21.209 -66.04)
		(end 21.1328 -66.1162)
		(width 0.11938)
		(layer "F.Cu")
		(net "UNNAMED_8_ICP10100LGA10_I24_R_4")
	)
	(segment
		(start 21.209 -65.1764)
		(end 21.209 -66.04)
		(width 0.11938)
		(layer "F.Cu")
		(net "UNNAMED_8_ICP10100LGA10_I24_R_4")
	)
	(via
		(at 21.1328 -66.1162)
		(size 0.508)
		(drill 0.254)
		(layers "F.Cu" "B.Cu")
		(net "UNNAMED_8_ICP10100LGA10_I24_R_4")
	)
	(segment
		(start 19.802856 -66.0654)
		(end 19.802856 -66.814446)
		(width 0.11938)
		(layer "F.Cu")
		(net "UNNAMED_8_ICP10100LGA10_I24_R_3")
	)
	(segment
		(start 19.802856 -65.459864)
		(end 19.802856 -66.0654)
		(width 0.11938)
		(layer "F.Cu")
		(net "UNNAMED_8_ICP10100LGA10_I24_R_3")
	)
	(segment
		(start 19.544792 -65.2018)
		(end 19.802856 -65.459864)
		(width 0.11938)
		(layer "F.Cu")
		(net "UNNAMED_8_ICP10100LGA10_I24_R_3")
	)
	(via
		(at 19.802856 -66.0654)
		(size 0.4572)
		(drill 0.2032)
		(layers "F.Cu" "B.Cu")
		(net "UNNAMED_8_ICP10100LGA10_I24_R_3")
	)
	(segment
		(start 17.614392 -66.6242)
		(end 17.385792 -66.3956)
		(width 0.11938)
		(layer "F.Cu")
		(net "UNNAMED_8_ICP10100LGA10_I24_R_2")
	)
	(segment
		(start 19.277838 -67.089274)
		(end 18.812764 -66.6242)
		(width 0.11938)
		(layer "F.Cu")
		(net "UNNAMED_8_ICP10100LGA10_I24_R_2")
	)
	(segment
		(start 17.385792 -65.748408)
		(end 17.653 -65.4812)
		(width 0.11938)
		(layer "F.Cu")
		(net "UNNAMED_8_ICP10100LGA10_I24_R_2")
	)
	(segment
		(start 18.812764 -66.6242)
		(end 17.614392 -66.6242)
		(width 0.11938)
		(layer "F.Cu")
		(net "UNNAMED_8_ICP10100LGA10_I24_R_2")
	)
	(segment
		(start 17.385792 -66.3956)
		(end 17.385792 -65.748408)
		(width 0.11938)
		(layer "F.Cu")
		(net "UNNAMED_8_ICP10100LGA10_I24_R_2")
	)
	(via
		(at 17.653 -65.4812)
		(size 0.508)
		(drill 0.254)
		(layers "F.Cu" "B.Cu")
		(net "UNNAMED_8_ICP10100LGA10_I24_R_2")
	)
	(segment
		(start 19.024346 -68.707)
		(end 19.277838 -68.453508)
		(width 0.11938)
		(layer "F.Cu")
		(net "UNNAMED_8_ICP10100LGA10_I24_R_1")
	)
	(segment
		(start 18.415 -68.707)
		(end 19.024346 -68.707)
		(width 0.11938)
		(layer "F.Cu")
		(net "UNNAMED_8_ICP10100LGA10_I24_R_1")
	)
	(segment
		(start 18.288 -68.9356)
		(end 18.288 -69.596)
		(width 0.11938)
		(layer "F.Cu")
		(net "UNNAMED_8_ICP10100LGA10_I24_R_1")
	)
	(segment
		(start 18.288 -68.834)
		(end 18.415 -68.707)
		(width 0.11938)
		(layer "F.Cu")
		(net "UNNAMED_8_ICP10100LGA10_I24_R_1")
	)
	(segment
		(start 18.288 -68.9356)
		(end 18.288 -68.834)
		(width 0.11938)
		(layer "F.Cu")
		(net "UNNAMED_8_ICP10100LGA10_I24_R_1")
	)
	(segment
		(start 17.316196 -70.339204)
		(end 16.7894 -70.866)
		(width 0.11938)
		(layer "F.Cu")
		(net "UNNAMED_8_ICP10100LGA10_I24_R_1")
	)
	(segment
		(start 17.544796 -70.339204)
		(end 17.316196 -70.339204)
		(width 0.11938)
		(layer "F.Cu")
		(net "UNNAMED_8_ICP10100LGA10_I24_R_1")
	)
	(segment
		(start 18.288 -69.596)
		(end 17.544796 -70.339204)
		(width 0.11938)
		(layer "F.Cu")
		(net "UNNAMED_8_ICP10100LGA10_I24_R_1")
	)
	(segment
		(start 19.277838 -68.453508)
		(end 19.277838 -68.089526)
		(width 0.11938)
		(layer "F.Cu")
		(net "UNNAMED_8_ICP10100LGA10_I24_R_1")
	)
	(via
		(at 18.288 -68.9356)
		(size 0.4572)
		(drill 0.2032)
		(layers "F.Cu" "B.Cu")
		(net "UNNAMED_8_ICP10100LGA10_I24_R_1")
	)
	(segment
		(start 20.828 -69.3928)
		(end 20.302728 -68.867528)
		(width 0.11938)
		(layer "F.Cu")
		(net "UNNAMED_8_ICP10100LGA10_I24_RES")
	)
	(segment
		(start 20.302728 -68.867528)
		(end 20.302728 -68.364354)
		(width 0.11938)
		(layer "F.Cu")
		(net "UNNAMED_8_ICP10100LGA10_I24_RES")
	)
	(segment
		(start 20.955 -69.3928)
		(end 20.828 -69.3928)
		(width 0.11938)
		(layer "F.Cu")
		(net "UNNAMED_8_ICP10100LGA10_I24_RES")
	)
	(via
		(at 20.955 -69.3928)
		(size 0.4572)
		(drill 0.2032)
		(layers "F.Cu" "B.Cu")
		(net "UNNAMED_8_ICP10100LGA10_I24_RES")
	)
	(segment
		(start 20.9804 -70.0278)
		(end 20.9804 -69.4182)
		(width 0.11938)
		(layer "B.Cu")
		(net "UNNAMED_8_ICP10100LGA10_I24_RES")
	)
	(segment
		(start 21.7932 -70.8406)
		(end 20.9804 -70.0278)
		(width 0.11938)
		(layer "B.Cu")
		(net "UNNAMED_8_ICP10100LGA10_I24_RES")
	)
	(segment
		(start 20.9804 -69.4182)
		(end 20.955 -69.3928)
		(width 0.11938)
		(layer "B.Cu")
		(net "UNNAMED_8_ICP10100LGA10_I24_RES")
	)
	(segment
		(start 153.1366 -56.515)
		(end 153.1366 -57.658)
		(width 0.4572)
		(layer "F.Cu")
		(net "VDD3V3_SHT31A")
	)
	(segment
		(start 152.896062 -54.453028)
		(end 152.896062 -55.588662)
		(width 0.254)
		(layer "F.Cu")
		(net "VDD3V3_SHT31A")
	)
	(segment
		(start 152.896062 -55.588662)
		(end 152.896062 -56.274462)
		(width 0.254)
		(layer "F.Cu")
		(net "VDD3V3_SHT31A")
	)
	(segment
		(start 152.896062 -56.274462)
		(end 153.1366 -56.515)
		(width 0.254)
		(layer "F.Cu")
		(net "VDD3V3_SHT31A")
	)
	(segment
		(start 153.2382 -57.7596)
		(end 153.1366 -57.658)
		(width 0.4572)
		(layer "F.Cu")
		(net "VDD3V3_SHT31A")
	)
	(segment
		(start 153.2382 -59.0296)
		(end 153.2382 -57.7596)
		(width 0.4572)
		(layer "F.Cu")
		(net "VDD3V3_SHT31A")
	)
	(via
		(at 152.896062 -55.588662)
		(size 0.508)
		(drill 0.254)
		(layers "F.Cu" "B.Cu")
		(net "VDD3V3_SHT31A")
	)
	(segment
		(start 112.26165 -74.300334)
		(end 112.26165 -75.44435)
		(width 0.11938)
		(layer "F.Cu")
		(net "UNNAMED_515_NCP45560IMNTWGHDFN1")
	)
	(segment
		(start 112.26165 -75.44435)
		(end 112.141 -75.565)
		(width 0.11938)
		(layer "F.Cu")
		(net "UNNAMED_515_NCP45560IMNTWGHDFN1")
	)
	(segment
		(start 112.649 -76.073)
		(end 112.141 -75.565)
		(width 0.11938)
		(layer "F.Cu")
		(net "UNNAMED_515_NCP45560IMNTWGHDFN1")
	)
	(segment
		(start 114.9096 -76.073)
		(end 112.649 -76.073)
		(width 0.11938)
		(layer "F.Cu")
		(net "UNNAMED_515_NCP45560IMNTWGHDFN1")
	)
	(via
		(at 112.141 -75.565)
		(size 0.4572)
		(drill 0.2032)
		(layers "F.Cu" "B.Cu")
		(net "UNNAMED_515_NCP45560IMNTWGHDFN1")
	)
	(segment
		(start 110.8964 -75.565)
		(end 112.141 -75.565)
		(width 0.11938)
		(layer "B.Cu")
		(net "UNNAMED_515_NCP45560IMNTWGHDFN1")
	)
	(segment
		(start 156.04998 -108.599732)
		(end 154.793696 -108.599732)
		(width 0.11938)
		(layer "F.Cu")
		(net "UNNAMED_14_OPTICAL_I139_A")
	)
	(via
		(at 154.793696 -108.599732)
		(size 0.508)
		(drill 0.254)
		(layers "F.Cu" "B.Cu")
		(net "UNNAMED_14_OPTICAL_I139_A")
	)
	(segment
		(start 155.164028 -108.2294)
		(end 155.956 -108.2294)
		(width 0.11938)
		(layer "B.Cu")
		(net "UNNAMED_14_OPTICAL_I139_A")
	)
	(segment
		(start 154.793696 -108.599732)
		(end 155.164028 -108.2294)
		(width 0.11938)
		(layer "B.Cu")
		(net "UNNAMED_14_OPTICAL_I139_A")
	)
	(via
		(at 67.183 -54.356)
		(size 0.762)
		(drill 0.381)
		(layers "F.Cu" "B.Cu")
		(net "UNNAMED_527_RESISTOR_I206_1")
	)
	(segment
		(start 67.37604 -54.80304)
		(end 67.183 -54.61)
		(width 0.11938)
		(layer "B.Cu")
		(net "UNNAMED_527_RESISTOR_I206_1")
	)
	(segment
		(start 68.072 -57.277)
		(end 68.072 -59.944)
		(width 0.11938)
		(layer "B.Cu")
		(net "UNNAMED_527_RESISTOR_I206_1")
	)
	(segment
		(start 67.37604 -55.7149)
		(end 67.37604 -56.58104)
		(width 0.11938)
		(layer "B.Cu")
		(net "UNNAMED_527_RESISTOR_I206_1")
	)
	(segment
		(start 67.691 -60.325)
		(end 67.0814 -60.325)
		(width 0.11938)
		(layer "B.Cu")
		(net "UNNAMED_527_RESISTOR_I206_1")
	)
	(segment
		(start 68.072 -59.944)
		(end 67.691 -60.325)
		(width 0.11938)
		(layer "B.Cu")
		(net "UNNAMED_527_RESISTOR_I206_1")
	)
	(segment
		(start 67.37604 -55.7149)
		(end 67.37604 -54.80304)
		(width 0.11938)
		(layer "B.Cu")
		(net "UNNAMED_527_RESISTOR_I206_1")
	)
	(segment
		(start 67.37604 -56.58104)
		(end 68.072 -57.277)
		(width 0.11938)
		(layer "B.Cu")
		(net "UNNAMED_527_RESISTOR_I206_1")
	)
	(segment
		(start 67.183 -54.61)
		(end 67.183 -54.356)
		(width 0.11938)
		(layer "B.Cu")
		(net "UNNAMED_527_RESISTOR_I206_1")
	)
	(segment
		(start 21.463 -55.372)
		(end 21.157184 -55.372)
		(width 0.11938)
		(layer "F.Cu")
		(net "SMA_ANALOG_TUNING_IN")
	)
	(segment
		(start 21.157184 -55.372)
		(end 20.4216 -54.636416)
		(width 0.11938)
		(layer "F.Cu")
		(net "SMA_ANALOG_TUNING_IN")
	)
	(via
		(at 21.463 -55.372)
		(size 0.508)
		(drill 0.254)
		(layers "F.Cu" "B.Cu")
		(net "SMA_ANALOG_TUNING_IN")
	)
	(via
		(at 24.3586 -70.8406)
		(size 0.508)
		(drill 0.254)
		(layers "F.Cu" "B.Cu")
		(net "SMA_ANALOG_TUNING_IN")
	)
	(segment
		(start 23.0632 -70.8406)
		(end 24.3586 -70.8406)
		(width 0.11938)
		(layer "B.Cu")
		(net "SMA_ANALOG_TUNING_IN")
	)
	(segment
		(start 20.9804 -61.4934)
		(end 20.9804 -59.7408)
		(width 0.127)
		(layer "In7.Cu")
		(net "SMA_ANALOG_TUNING_IN")
	)
	(segment
		(start 22.098 -64.2112)
		(end 22.098 -62.611)
		(width 0.127)
		(layer "In7.Cu")
		(net "SMA_ANALOG_TUNING_IN")
	)
	(segment
		(start 24.3586 -70.8406)
		(end 24.003 -70.485)
		(width 0.127)
		(layer "In7.Cu")
		(net "SMA_ANALOG_TUNING_IN")
	)
	(segment
		(start 21.5011 -58.773314)
		(end 21.5011 -58.320686)
		(width 0.127)
		(layer "In7.Cu")
		(net "SMA_ANALOG_TUNING_IN")
	)
	(segment
		(start 22.098 -62.611)
		(end 20.9804 -61.4934)
		(width 0.127)
		(layer "In7.Cu")
		(net "SMA_ANALOG_TUNING_IN")
	)
	(segment
		(start 21.463 -59.2582)
		(end 21.463 -58.811414)
		(width 0.127)
		(layer "In7.Cu")
		(net "SMA_ANALOG_TUNING_IN")
	)
	(segment
		(start 20.9804 -59.7408)
		(end 21.463 -59.2582)
		(width 0.127)
		(layer "In7.Cu")
		(net "SMA_ANALOG_TUNING_IN")
	)
	(segment
		(start 21.463 -58.811414)
		(end 21.5011 -58.773314)
		(width 0.127)
		(layer "In7.Cu")
		(net "SMA_ANALOG_TUNING_IN")
	)
	(segment
		(start 21.463 -58.282586)
		(end 21.463 -55.372)
		(width 0.127)
		(layer "In7.Cu")
		(net "SMA_ANALOG_TUNING_IN")
	)
	(segment
		(start 21.5011 -58.320686)
		(end 21.463 -58.282586)
		(width 0.127)
		(layer "In7.Cu")
		(net "SMA_ANALOG_TUNING_IN")
	)
	(segment
		(start 24.003 -70.485)
		(end 24.003 -66.1162)
		(width 0.127)
		(layer "In7.Cu")
		(net "SMA_ANALOG_TUNING_IN")
	)
	(segment
		(start 24.003 -66.1162)
		(end 22.098 -64.2112)
		(width 0.127)
		(layer "In7.Cu")
		(net "SMA_ANALOG_TUNING_IN")
	)
	(segment
		(start 151.638254 -56.007)
		(end 150.914862 -56.007)
		(width 0.11938)
		(layer "F.Cu")
		(net "R_SHT3X_RST_N")
	)
	(segment
		(start 152.395936 -54.453028)
		(end 152.395936 -55.249318)
		(width 0.11938)
		(layer "F.Cu")
		(net "R_SHT3X_RST_N")
	)
	(segment
		(start 150.914862 -58.014108)
		(end 150.914862 -59.182)
		(width 0.11938)
		(layer "F.Cu")
		(net "R_SHT3X_RST_N")
	)
	(segment
		(start 150.914862 -59.182)
		(end 150.914862 -60.363862)
		(width 0.11938)
		(layer "F.Cu")
		(net "R_SHT3X_RST_N")
	)
	(segment
		(start 150.914862 -56.8706)
		(end 150.914862 -58.014108)
		(width 0.11938)
		(layer "F.Cu")
		(net "R_SHT3X_RST_N")
	)
	(segment
		(start 150.914862 -60.363862)
		(end 151.257 -60.706)
		(width 0.11938)
		(layer "F.Cu")
		(net "R_SHT3X_RST_N")
	)
	(segment
		(start 152.395936 -55.249318)
		(end 151.638254 -56.007)
		(width 0.11938)
		(layer "F.Cu")
		(net "R_SHT3X_RST_N")
	)
	(segment
		(start 150.914862 -56.007)
		(end 150.914862 -56.8706)
		(width 0.11938)
		(layer "F.Cu")
		(net "R_SHT3X_RST_N")
	)
	(via
		(at 150.914862 -56.007)
		(size 0.4572)
		(drill 0.2032)
		(layers "F.Cu" "B.Cu")
		(net "R_SHT3X_RST_N")
	)
	(segment
		(start 152.395936 -51.134264)
		(end 152.7048 -50.8254)
		(width 0.11938)
		(layer "F.Cu")
		(net "R_SHT3X_ALERT_N")
	)
	(segment
		(start 152.883108 -49.54651)
		(end 152.883108 -50.8254)
		(width 0.11938)
		(layer "F.Cu")
		(net "R_SHT3X_ALERT_N")
	)
	(segment
		(start 152.7048 -50.8254)
		(end 152.883108 -50.8254)
		(width 0.11938)
		(layer "F.Cu")
		(net "R_SHT3X_ALERT_N")
	)
	(segment
		(start 152.395936 -51.922172)
		(end 152.395936 -51.134264)
		(width 0.11938)
		(layer "F.Cu")
		(net "R_SHT3X_ALERT_N")
	)
	(via
		(at 152.883108 -50.8254)
		(size 0.4572)
		(drill 0.2032)
		(layers "F.Cu" "B.Cu")
		(net "R_SHT3X_ALERT_N")
	)
	(segment
		(start 149.098 -47.040292)
		(end 149.098 -46.736)
		(width 0.127)
		(layer "In2.Cu")
		(net "R_SHT3X_ALERT_N")
	)
	(segment
		(start 152.883108 -50.8254)
		(end 149.098 -47.040292)
		(width 0.127)
		(layer "In2.Cu")
		(net "R_SHT3X_ALERT_N")
	)
	(segment
		(start 87.668608 -56.095392)
		(end 87.668608 -56.525668)
		(width 0.11938)
		(layer "F.Cu")
		(net "R_BNO080_I2C_SDA")
	)
	(segment
		(start 87.86622 -55.89778)
		(end 87.668608 -56.095392)
		(width 0.11938)
		(layer "F.Cu")
		(net "R_BNO080_I2C_SDA")
	)
	(segment
		(start 87.86622 -55.118)
		(end 87.86622 -55.89778)
		(width 0.11938)
		(layer "F.Cu")
		(net "R_BNO080_I2C_SDA")
	)
	(via
		(at 87.86622 -55.118)
		(size 0.4572)
		(drill 0.2032)
		(layers "F.Cu" "B.Cu")
		(net "R_BNO080_I2C_SDA")
	)
	(segment
		(start 87.86622 -55.118)
		(end 87.61222 -55.372)
		(width 0.11938)
		(layer "B.Cu")
		(net "R_BNO080_I2C_SDA")
	)
	(segment
		(start 87.249 -55.372)
		(end 86.8426 -55.7784)
		(width 0.11938)
		(layer "B.Cu")
		(net "R_BNO080_I2C_SDA")
	)
	(segment
		(start 86.8426 -55.7784)
		(end 86.8426 -56.134)
		(width 0.11938)
		(layer "B.Cu")
		(net "R_BNO080_I2C_SDA")
	)
	(segment
		(start 87.61222 -55.372)
		(end 87.249 -55.372)
		(width 0.11938)
		(layer "B.Cu")
		(net "R_BNO080_I2C_SDA")
	)
	(segment
		(start 87.376 -53.848)
		(end 87.376 -54.61)
		(width 0.11938)
		(layer "F.Cu")
		(net "R_BNO080_I2C_SCL")
	)
	(segment
		(start 87.376 -54.61)
		(end 86.856062 -55.129938)
		(width 0.11938)
		(layer "F.Cu")
		(net "R_BNO080_I2C_SCL")
	)
	(segment
		(start 86.856062 -55.129938)
		(end 86.856062 -56.463184)
		(width 0.11938)
		(layer "F.Cu")
		(net "R_BNO080_I2C_SCL")
	)
	(via
		(at 87.376 -53.848)
		(size 0.508)
		(drill 0.254)
		(layers "F.Cu" "B.Cu")
		(net "R_BNO080_I2C_SCL")
	)
	(segment
		(start 87.376 -54.3814)
		(end 87.376 -53.848)
		(width 0.11938)
		(layer "B.Cu")
		(net "R_BNO080_I2C_SCL")
	)
	(segment
		(start 85.6234 -56.134)
		(end 87.376 -54.3814)
		(width 0.11938)
		(layer "B.Cu")
		(net "R_BNO080_I2C_SCL")
	)
	(segment
		(start 89.4842 -44.45)
		(end 89.598754 -44.335446)
		(width 0.11938)
		(layer "F.Cu")
		(net "RSVD_DBG_USB_MUX_SEL")
	)
	(segment
		(start 109.847126 -48.823118)
		(end 110.346998 -49.32299)
		(width 0.11938)
		(layer "F.Cu")
		(net "RSVD_DBG_USB_MUX_SEL")
	)
	(segment
		(start 89.598754 -44.335446)
		(end 90.2716 -44.335446)
		(width 0.11938)
		(layer "F.Cu")
		(net "RSVD_DBG_USB_MUX_SEL")
	)
	(via
		(at 110.346998 -49.32299)
		(size 0.4572)
		(drill 0.2032)
		(layers "F.Cu" "B.Cu")
		(net "RSVD_DBG_USB_MUX_SEL")
	)
	(via
		(at 80.772 -68.199)
		(size 0.4572)
		(drill 0.2032)
		(layers "F.Cu" "B.Cu")
		(net "RSVD_DBG_USB_MUX_SEL")
	)
	(via
		(at 89.4842 -44.45)
		(size 0.4572)
		(drill 0.2032)
		(layers "F.Cu" "B.Cu")
		(net "RSVD_DBG_USB_MUX_SEL")
	)
	(segment
		(start 83.82 -53.594)
		(end 86.389972 -51.024028)
		(width 0.127)
		(layer "In2.Cu")
		(net "RSVD_DBG_USB_MUX_SEL")
	)
	(segment
		(start 86.389972 -51.024028)
		(end 86.389972 -45.563028)
		(width 0.127)
		(layer "In2.Cu")
		(net "RSVD_DBG_USB_MUX_SEL")
	)
	(segment
		(start 82.1055 -55.3085)
		(end 83.3755 -55.3085)
		(width 0.127)
		(layer "In2.Cu")
		(net "RSVD_DBG_USB_MUX_SEL")
	)
	(segment
		(start 87.0585 -44.8945)
		(end 89.0397 -44.8945)
		(width 0.127)
		(layer "In2.Cu")
		(net "RSVD_DBG_USB_MUX_SEL")
	)
	(segment
		(start 80.772 -68.199)
		(end 80.772 -68.02882)
		(width 0.127)
		(layer "In2.Cu")
		(net "RSVD_DBG_USB_MUX_SEL")
	)
	(segment
		(start 80.645 -65.900808)
		(end 80.645 -56.769)
		(width 0.127)
		(layer "In2.Cu")
		(net "RSVD_DBG_USB_MUX_SEL")
	)
	(segment
		(start 80.4545 -67.711066)
		(end 80.4545 -66.091308)
		(width 0.127)
		(layer "In2.Cu")
		(net "RSVD_DBG_USB_MUX_SEL")
	)
	(segment
		(start 83.3755 -55.3085)
		(end 83.82 -54.864)
		(width 0.127)
		(layer "In2.Cu")
		(net "RSVD_DBG_USB_MUX_SEL")
	)
	(segment
		(start 86.389972 -45.563028)
		(end 87.0585 -44.8945)
		(width 0.127)
		(layer "In2.Cu")
		(net "RSVD_DBG_USB_MUX_SEL")
	)
	(segment
		(start 83.82 -54.864)
		(end 83.82 -53.594)
		(width 0.127)
		(layer "In2.Cu")
		(net "RSVD_DBG_USB_MUX_SEL")
	)
	(segment
		(start 80.4545 -66.091308)
		(end 80.645 -65.900808)
		(width 0.127)
		(layer "In2.Cu")
		(net "RSVD_DBG_USB_MUX_SEL")
	)
	(segment
		(start 89.0397 -44.8945)
		(end 89.4842 -44.45)
		(width 0.127)
		(layer "In2.Cu")
		(net "RSVD_DBG_USB_MUX_SEL")
	)
	(segment
		(start 80.645 -56.769)
		(end 82.1055 -55.3085)
		(width 0.127)
		(layer "In2.Cu")
		(net "RSVD_DBG_USB_MUX_SEL")
	)
	(segment
		(start 80.772 -68.02882)
		(end 80.4545 -67.711066)
		(width 0.127)
		(layer "In2.Cu")
		(net "RSVD_DBG_USB_MUX_SEL")
	)
	(segment
		(start 108.712 -56.388)
		(end 108.9025 -56.1975)
		(width 0.127)
		(layer "In7.Cu")
		(net "RSVD_DBG_USB_MUX_SEL")
	)
	(segment
		(start 100.774246 -69.9135)
		(end 101.981 -69.9135)
		(width 0.127)
		(layer "In7.Cu")
		(net "RSVD_DBG_USB_MUX_SEL")
	)
	(segment
		(start 108.9025 -54.1655)
		(end 109.347 -53.721)
		(width 0.127)
		(layer "In7.Cu")
		(net "RSVD_DBG_USB_MUX_SEL")
	)
	(segment
		(start 109.347 -49.784)
		(end 109.80801 -49.32299)
		(width 0.127)
		(layer "In7.Cu")
		(net "RSVD_DBG_USB_MUX_SEL")
	)
	(segment
		(start 99.4791 -71.636382)
		(end 99.4791 -71.208646)
		(width 0.127)
		(layer "In7.Cu")
		(net "RSVD_DBG_USB_MUX_SEL")
	)
	(segment
		(start 109.80801 -49.32299)
		(end 110.346998 -49.32299)
		(width 0.127)
		(layer "In7.Cu")
		(net "RSVD_DBG_USB_MUX_SEL")
	)
	(segment
		(start 99.4791 -71.208646)
		(end 100.774246 -69.9135)
		(width 0.127)
		(layer "In7.Cu")
		(net "RSVD_DBG_USB_MUX_SEL")
	)
	(segment
		(start 108.9025 -56.1975)
		(end 108.9025 -54.1655)
		(width 0.127)
		(layer "In7.Cu")
		(net "RSVD_DBG_USB_MUX_SEL")
	)
	(segment
		(start 99.144582 -71.9709)
		(end 99.4791 -71.636382)
		(width 0.127)
		(layer "In7.Cu")
		(net "RSVD_DBG_USB_MUX_SEL")
	)
	(segment
		(start 88.7476 -70.3326)
		(end 90.424 -72.009)
		(width 0.127)
		(layer "In7.Cu")
		(net "RSVD_DBG_USB_MUX_SEL")
	)
	(segment
		(start 101.981 -69.9135)
		(end 102.997 -68.8975)
		(width 0.127)
		(layer "In7.Cu")
		(net "RSVD_DBG_USB_MUX_SEL")
	)
	(segment
		(start 102.997 -68.8975)
		(end 104.7115 -68.8975)
		(width 0.127)
		(layer "In7.Cu")
		(net "RSVD_DBG_USB_MUX_SEL")
	)
	(segment
		(start 104.7115 -68.8975)
		(end 107.6706 -65.9384)
		(width 0.127)
		(layer "In7.Cu")
		(net "RSVD_DBG_USB_MUX_SEL")
	)
	(segment
		(start 109.347 -53.721)
		(end 109.347 -49.784)
		(width 0.127)
		(layer "In7.Cu")
		(net "RSVD_DBG_USB_MUX_SEL")
	)
	(segment
		(start 107.6706 -61.3664)
		(end 108.712 -60.325)
		(width 0.127)
		(layer "In7.Cu")
		(net "RSVD_DBG_USB_MUX_SEL")
	)
	(segment
		(start 108.712 -60.325)
		(end 108.712 -56.388)
		(width 0.127)
		(layer "In7.Cu")
		(net "RSVD_DBG_USB_MUX_SEL")
	)
	(segment
		(start 82.9056 -70.3326)
		(end 88.7476 -70.3326)
		(width 0.127)
		(layer "In7.Cu")
		(net "RSVD_DBG_USB_MUX_SEL")
	)
	(segment
		(start 95.885 -72.009)
		(end 95.9231 -71.9709)
		(width 0.127)
		(layer "In7.Cu")
		(net "RSVD_DBG_USB_MUX_SEL")
	)
	(segment
		(start 95.9231 -71.9709)
		(end 99.144582 -71.9709)
		(width 0.127)
		(layer "In7.Cu")
		(net "RSVD_DBG_USB_MUX_SEL")
	)
	(segment
		(start 80.772 -68.199)
		(end 82.9056 -70.3326)
		(width 0.127)
		(layer "In7.Cu")
		(net "RSVD_DBG_USB_MUX_SEL")
	)
	(segment
		(start 90.424 -72.009)
		(end 95.885 -72.009)
		(width 0.127)
		(layer "In7.Cu")
		(net "RSVD_DBG_USB_MUX_SEL")
	)
	(segment
		(start 107.6706 -65.9384)
		(end 107.6706 -61.3664)
		(width 0.127)
		(layer "In7.Cu")
		(net "RSVD_DBG_USB_MUX_SEL")
	)
	(segment
		(start 111.847122 -38.823138)
		(end 112.346994 -38.323266)
		(width 0.11938)
		(layer "F.Cu")
		(net "IO_L24P_35")
	)
	(via
		(at 112.346994 -38.323266)
		(size 0.4572)
		(drill 0.2032)
		(layers "F.Cu" "B.Cu")
		(net "IO_L24P_35")
	)
	(segment
		(start 118.125494 -31.982918)
		(end 113.890806 -31.982918)
		(width 0.127)
		(layer "In2.Cu")
		(net "IO_L24P_35")
	)
	(segment
		(start 113.890806 -31.982918)
		(end 111.887 -33.986724)
		(width 0.127)
		(layer "In2.Cu")
		(net "IO_L24P_35")
	)
	(segment
		(start 119.6848 -30.423612)
		(end 118.125494 -31.982918)
		(width 0.127)
		(layer "In2.Cu")
		(net "IO_L24P_35")
	)
	(segment
		(start 111.887 -33.986724)
		(end 111.887 -37.863272)
		(width 0.127)
		(layer "In2.Cu")
		(net "IO_L24P_35")
	)
	(segment
		(start 119.6848 -29.3878)
		(end 119.6848 -30.423612)
		(width 0.127)
		(layer "In2.Cu")
		(net "IO_L24P_35")
	)
	(segment
		(start 111.887 -37.863272)
		(end 112.346994 -38.323266)
		(width 0.127)
		(layer "In2.Cu")
		(net "IO_L24P_35")
	)
	(segment
		(start 116.847112 -41.823132)
		(end 117.346984 -41.32326)
		(width 0.11938)
		(layer "F.Cu")
		(net "IO_L24P_34")
	)
	(segment
		(start 110.847124 -37.82314)
		(end 111.346996 -37.323268)
		(width 0.11938)
		(layer "F.Cu")
		(net "IO_L24N_35")
	)
	(via
		(at 111.346996 -37.323268)
		(size 0.4572)
		(drill 0.2032)
		(layers "F.Cu" "B.Cu")
		(net "IO_L24N_35")
	)
	(segment
		(start 110.871 -33.02)
		(end 109.22 -31.369)
		(width 0.127)
		(layer "In2.Cu")
		(net "IO_L24N_35")
	)
	(segment
		(start 111.346996 -37.323268)
		(end 110.871 -36.847272)
		(width 0.1016)
		(layer "In2.Cu")
		(net "IO_L24N_35")
	)
	(segment
		(start 109.22 -31.369)
		(end 108.966 -31.369)
		(width 0.127)
		(layer "In2.Cu")
		(net "IO_L24N_35")
	)
	(segment
		(start 110.871 -36.847272)
		(end 110.871 -33.02)
		(width 0.1016)
		(layer "In2.Cu")
		(net "IO_L24N_35")
	)
	(segment
		(start 110.346998 -38.323266)
		(end 109.847126 -38.823138)
		(width 0.11938)
		(layer "F.Cu")
		(net "IO_L23P_35")
	)
	(via
		(at 110.346998 -38.323266)
		(size 0.4572)
		(drill 0.2032)
		(layers "F.Cu" "B.Cu")
		(net "IO_L23P_35")
	)
	(segment
		(start 110.332266 -38.323266)
		(end 109.22 -37.211)
		(width 0.127)
		(layer "In2.Cu")
		(net "IO_L23P_35")
	)
	(segment
		(start 108.585 -32.512)
		(end 106.553 -32.512)
		(width 0.127)
		(layer "In2.Cu")
		(net "IO_L23P_35")
	)
	(segment
		(start 109.22 -37.211)
		(end 109.22 -33.147)
		(width 0.127)
		(layer "In2.Cu")
		(net "IO_L23P_35")
	)
	(segment
		(start 106.553 -32.512)
		(end 105.41 -31.369)
		(width 0.127)
		(layer "In2.Cu")
		(net "IO_L23P_35")
	)
	(segment
		(start 110.346998 -38.323266)
		(end 110.332266 -38.323266)
		(width 0.127)
		(layer "In2.Cu")
		(net "IO_L23P_35")
	)
	(segment
		(start 109.22 -33.147)
		(end 108.585 -32.512)
		(width 0.127)
		(layer "In2.Cu")
		(net "IO_L23P_35")
	)
	(segment
		(start 117.84711 -40.823134)
		(end 118.346982 -40.323262)
		(width 0.11938)
		(layer "F.Cu")
		(net "IO_L23P_34")
	)
	(via
		(at 118.346982 -40.323262)
		(size 0.4572)
		(drill 0.2032)
		(layers "F.Cu" "B.Cu")
		(net "IO_L23P_34")
	)
	(segment
		(start 127.0635 -38.6715)
		(end 127.889 -37.846)
		(width 0.127)
		(layer "In7.Cu")
		(net "IO_L23P_34")
	)
	(segment
		(start 125.32233 -40.7162)
		(end 126.09703 -39.9415)
		(width 0.127)
		(layer "In7.Cu")
		(net "IO_L23P_34")
	)
	(segment
		(start 118.346982 -40.323262)
		(end 118.56212 -40.5384)
		(width 0.127)
		(layer "In7.Cu")
		(net "IO_L23P_34")
	)
	(segment
		(start 126.52756 -39.9415)
		(end 127.0635 -39.40556)
		(width 0.127)
		(layer "In7.Cu")
		(net "IO_L23P_34")
	)
	(segment
		(start 121.3358 -40.7162)
		(end 125.32233 -40.7162)
		(width 0.127)
		(layer "In7.Cu")
		(net "IO_L23P_34")
	)
	(segment
		(start 118.56212 -40.5384)
		(end 121.158 -40.5384)
		(width 0.127)
		(layer "In7.Cu")
		(net "IO_L23P_34")
	)
	(segment
		(start 126.09703 -39.9415)
		(end 126.52756 -39.9415)
		(width 0.127)
		(layer "In7.Cu")
		(net "IO_L23P_34")
	)
	(segment
		(start 121.158 -40.5384)
		(end 121.3358 -40.7162)
		(width 0.127)
		(layer "In7.Cu")
		(net "IO_L23P_34")
	)
	(segment
		(start 127.0635 -39.40556)
		(end 127.0635 -38.6715)
		(width 0.127)
		(layer "In7.Cu")
		(net "IO_L23P_34")
	)
	(segment
		(start 110.346998 -37.323268)
		(end 109.847126 -37.82314)
		(width 0.11938)
		(layer "F.Cu")
		(net "IO_L23N_35")
	)
	(via
		(at 110.346998 -37.323268)
		(size 0.4572)
		(drill 0.2032)
		(layers "F.Cu" "B.Cu")
		(net "IO_L23N_35")
	)
	(segment
		(start 106.299 -29.718)
		(end 106.299 -31.496)
		(width 0.127)
		(layer "In2.Cu")
		(net "IO_L23N_35")
	)
	(segment
		(start 109.728 -36.70427)
		(end 110.346998 -37.323268)
		(width 0.127)
		(layer "In2.Cu")
		(net "IO_L23N_35")
	)
	(segment
		(start 106.934 -32.131)
		(end 108.712 -32.131)
		(width 0.127)
		(layer "In2.Cu")
		(net "IO_L23N_35")
	)
	(segment
		(start 108.712 -32.131)
		(end 109.728 -33.147)
		(width 0.127)
		(layer "In2.Cu")
		(net "IO_L23N_35")
	)
	(segment
		(start 109.728 -33.147)
		(end 109.728 -36.70427)
		(width 0.127)
		(layer "In2.Cu")
		(net "IO_L23N_35")
	)
	(segment
		(start 106.299 -31.496)
		(end 106.934 -32.131)
		(width 0.127)
		(layer "In2.Cu")
		(net "IO_L23N_35")
	)
	(segment
		(start 112.395 -34.275014)
		(end 111.847122 -34.822892)
		(width 0.11938)
		(layer "F.Cu")
		(net "IO_L22P_35")
	)
	(segment
		(start 113.313972 -32.355028)
		(end 112.395 -33.274)
		(width 0.11938)
		(layer "F.Cu")
		(net "IO_L22P_35")
	)
	(segment
		(start 121.924572 -32.355028)
		(end 113.313972 -32.355028)
		(width 0.11938)
		(layer "F.Cu")
		(net "IO_L22P_35")
	)
	(segment
		(start 112.395 -33.274)
		(end 112.395 -34.275014)
		(width 0.11938)
		(layer "F.Cu")
		(net "IO_L22P_35")
	)
	(segment
		(start 122.3264 -31.9532)
		(end 121.924572 -32.355028)
		(width 0.11938)
		(layer "F.Cu")
		(net "IO_L22P_35")
	)
	(segment
		(start 110.847124 -34.822892)
		(end 111.346996 -34.32302)
		(width 0.11938)
		(layer "F.Cu")
		(net "IO_L22N_35")
	)
	(via
		(at 111.346996 -34.32302)
		(size 0.4572)
		(drill 0.2032)
		(layers "F.Cu" "B.Cu")
		(net "IO_L22N_35")
	)
	(segment
		(start 111.346996 -33.941004)
		(end 111.887 -33.401)
		(width 0.127)
		(layer "In2.Cu")
		(net "IO_L22N_35")
	)
	(segment
		(start 113.143792 -31.601918)
		(end 117.623082 -31.601918)
		(width 0.127)
		(layer "In2.Cu")
		(net "IO_L22N_35")
	)
	(segment
		(start 117.623082 -31.601918)
		(end 118.491 -30.734)
		(width 0.127)
		(layer "In2.Cu")
		(net "IO_L22N_35")
	)
	(segment
		(start 111.887 -32.85871)
		(end 113.143792 -31.601918)
		(width 0.127)
		(layer "In2.Cu")
		(net "IO_L22N_35")
	)
	(segment
		(start 118.491 -30.734)
		(end 118.491 -28.0416)
		(width 0.127)
		(layer "In2.Cu")
		(net "IO_L22N_35")
	)
	(segment
		(start 111.346996 -34.32302)
		(end 111.346996 -33.941004)
		(width 0.127)
		(layer "In2.Cu")
		(net "IO_L22N_35")
	)
	(segment
		(start 111.887 -33.401)
		(end 111.887 -32.85871)
		(width 0.127)
		(layer "In2.Cu")
		(net "IO_L22N_35")
	)
	(segment
		(start 122.575066 -40.823134)
		(end 119.847106 -40.823134)
		(width 0.11938)
		(layer "F.Cu")
		(net "IO_L22N_34")
	)
	(segment
		(start 124.714 -39.116)
		(end 124.2822 -39.116)
		(width 0.11938)
		(layer "F.Cu")
		(net "IO_L22N_34")
	)
	(segment
		(start 124.2822 -39.116)
		(end 122.575066 -40.823134)
		(width 0.11938)
		(layer "F.Cu")
		(net "IO_L22N_34")
	)
	(segment
		(start 111.847122 -37.82314)
		(end 112.346994 -37.323268)
		(width 0.11938)
		(layer "F.Cu")
		(net "IO_L21P_35")
	)
	(via
		(at 112.346994 -37.323268)
		(size 0.4572)
		(drill 0.2032)
		(layers "F.Cu" "B.Cu")
		(net "IO_L21P_35")
	)
	(segment
		(start 112.862106 -37.83838)
		(end 112.346994 -37.323268)
		(width 0.1016)
		(layer "In2.Cu")
		(net "IO_L21P_35")
	)
	(segment
		(start 119.1006 -32.6644)
		(end 116.22532 -32.6644)
		(width 0.127)
		(layer "In2.Cu")
		(net "IO_L21P_35")
	)
	(segment
		(start 115.83416 -37.52088)
		(end 115.51666 -37.83838)
		(width 0.1016)
		(layer "In2.Cu")
		(net "IO_L21P_35")
	)
	(segment
		(start 121.1072 -30.6578)
		(end 119.1006 -32.6644)
		(width 0.127)
		(layer "In2.Cu")
		(net "IO_L21P_35")
	)
	(segment
		(start 115.51666 -37.83838)
		(end 112.862106 -37.83838)
		(width 0.1016)
		(layer "In2.Cu")
		(net "IO_L21P_35")
	)
	(segment
		(start 115.83416 -33.05556)
		(end 115.83416 -37.52088)
		(width 0.1016)
		(layer "In2.Cu")
		(net "IO_L21P_35")
	)
	(segment
		(start 116.22532 -32.6644)
		(end 115.83416 -33.05556)
		(width 0.1016)
		(layer "In2.Cu")
		(net "IO_L21P_35")
	)
	(segment
		(start 115.847114 -41.823132)
		(end 116.346986 -41.32326)
		(width 0.11938)
		(layer "F.Cu")
		(net "IO_L21P_34")
	)
	(via
		(at 116.346986 -41.32326)
		(size 0.4572)
		(drill 0.2032)
		(layers "F.Cu" "B.Cu")
		(net "IO_L21P_34")
	)
	(segment
		(start 116.776246 -40.894)
		(end 120.8532 -40.894)
		(width 0.127)
		(layer "In7.Cu")
		(net "IO_L21P_34")
	)
	(segment
		(start 121.1072 -41.148)
		(end 125.429518 -41.148)
		(width 0.127)
		(layer "In7.Cu")
		(net "IO_L21P_34")
	)
	(segment
		(start 126.3015 -40.8305)
		(end 127.762 -39.37)
		(width 0.127)
		(layer "In7.Cu")
		(net "IO_L21P_34")
	)
	(segment
		(start 125.747018 -40.8305)
		(end 126.3015 -40.8305)
		(width 0.127)
		(layer "In7.Cu")
		(net "IO_L21P_34")
	)
	(segment
		(start 120.8532 -40.894)
		(end 121.1072 -41.148)
		(width 0.127)
		(layer "In7.Cu")
		(net "IO_L21P_34")
	)
	(segment
		(start 125.429518 -41.148)
		(end 125.747018 -40.8305)
		(width 0.127)
		(layer "In7.Cu")
		(net "IO_L21P_34")
	)
	(segment
		(start 116.346986 -41.32326)
		(end 116.776246 -40.894)
		(width 0.127)
		(layer "In7.Cu")
		(net "IO_L21P_34")
	)
	(segment
		(start 111.847122 -36.823142)
		(end 112.346994 -36.32327)
		(width 0.11938)
		(layer "F.Cu")
		(net "IO_L21N_35")
	)
	(via
		(at 112.346994 -36.32327)
		(size 0.4572)
		(drill 0.2032)
		(layers "F.Cu" "B.Cu")
		(net "IO_L21N_35")
	)
	(segment
		(start 118.3132 -32.3342)
		(end 122.6312 -28.0162)
		(width 0.127)
		(layer "In2.Cu")
		(net "IO_L21N_35")
	)
	(segment
		(start 112.727994 -33.63468)
		(end 114.028474 -32.3342)
		(width 0.127)
		(layer "In2.Cu")
		(net "IO_L21N_35")
	)
	(segment
		(start 112.727994 -35.94227)
		(end 112.727994 -33.63468)
		(width 0.1016)
		(layer "In2.Cu")
		(net "IO_L21N_35")
	)
	(segment
		(start 114.028474 -32.3342)
		(end 118.3132 -32.3342)
		(width 0.127)
		(layer "In2.Cu")
		(net "IO_L21N_35")
	)
	(segment
		(start 112.346994 -36.32327)
		(end 112.727994 -35.94227)
		(width 0.1016)
		(layer "In2.Cu")
		(net "IO_L21N_35")
	)
	(segment
		(start 122.682 -33.782)
		(end 121.539 -32.639)
		(width 0.11938)
		(layer "F.Cu")
		(net "IO_L20P_35")
	)
	(segment
		(start 113.665 -32.639)
		(end 112.84712 -33.45688)
		(width 0.11938)
		(layer "F.Cu")
		(net "IO_L20P_35")
	)
	(segment
		(start 112.84712 -33.45688)
		(end 112.84712 -33.822894)
		(width 0.11938)
		(layer "F.Cu")
		(net "IO_L20P_35")
	)
	(segment
		(start 121.539 -32.639)
		(end 113.665 -32.639)
		(width 0.11938)
		(layer "F.Cu")
		(net "IO_L20P_35")
	)
	(segment
		(start 111.847122 -33.822894)
		(end 111.847122 -32.980122)
		(width 0.11938)
		(layer "F.Cu")
		(net "IO_L20N_35")
	)
	(segment
		(start 111.506 -32.639)
		(end 108.458 -32.639)
		(width 0.11938)
		(layer "F.Cu")
		(net "IO_L20N_35")
	)
	(segment
		(start 111.847122 -32.980122)
		(end 111.506 -32.639)
		(width 0.11938)
		(layer "F.Cu")
		(net "IO_L20N_35")
	)
	(segment
		(start 108.458 -32.639)
		(end 107.188 -31.369)
		(width 0.11938)
		(layer "F.Cu")
		(net "IO_L20N_35")
	)
	(segment
		(start 153.049986 -107.100116)
		(end 153.049986 -106.045)
		(width 0.11938)
		(layer "F.Cu")
		(net "FPGA_USR_LED1")
	)
	(segment
		(start 97.831148 -45.823124)
		(end 98.846894 -45.823124)
		(width 0.11938)
		(layer "F.Cu")
		(net "FPGA_USR_LED1")
	)
	(segment
		(start 97.314512 -45.306488)
		(end 97.831148 -45.823124)
		(width 0.11938)
		(layer "F.Cu")
		(net "FPGA_USR_LED1")
	)
	(via
		(at 153.049986 -106.045)
		(size 0.508)
		(drill 0.254)
		(layers "F.Cu" "B.Cu")
		(net "FPGA_USR_LED1")
	)
	(via
		(at 97.314512 -45.306488)
		(size 0.4572)
		(drill 0.2032)
		(layers "F.Cu" "B.Cu")
		(net "FPGA_USR_LED1")
	)
	(segment
		(start 90.812112 -63.9191)
		(end 89.76868 -63.9191)
		(width 0.127)
		(layer "In2.Cu")
		(net "FPGA_USR_LED1")
	)
	(segment
		(start 122.839988 -98.552)
		(end 112.679988 -88.392)
		(width 0.127)
		(layer "In2.Cu")
		(net "FPGA_USR_LED1")
	)
	(segment
		(start 112.679988 -88.392)
		(end 111.76 -88.392)
		(width 0.127)
		(layer "In2.Cu")
		(net "FPGA_USR_LED1")
	)
	(segment
		(start 94.091252 -67.19824)
		(end 90.812112 -63.9191)
		(width 0.127)
		(layer "In2.Cu")
		(net "FPGA_USR_LED1")
	)
	(segment
		(start 149.605746 -107.95)
		(end 136.779 -107.95)
		(width 0.127)
		(layer "In2.Cu")
		(net "FPGA_USR_LED1")
	)
	(segment
		(start 87.9221 -62.07252)
		(end 87.9221 -56.0959)
		(width 0.127)
		(layer "In2.Cu")
		(net "FPGA_USR_LED1")
	)
	(segment
		(start 108.585 -82.804)
		(end 106.388916 -80.607916)
		(width 0.127)
		(layer "In2.Cu")
		(net "FPGA_USR_LED1")
	)
	(segment
		(start 111.76 -88.392)
		(end 108.585 -85.217)
		(width 0.127)
		(layer "In2.Cu")
		(net "FPGA_USR_LED1")
	)
	(segment
		(start 88.519 -55.499)
		(end 88.519 -53.086)
		(width 0.127)
		(layer "In2.Cu")
		(net "FPGA_USR_LED1")
	)
	(segment
		(start 136.779 -107.95)
		(end 135.3185 -106.4895)
		(width 0.127)
		(layer "In2.Cu")
		(net "FPGA_USR_LED1")
	)
	(segment
		(start 108.585 -85.217)
		(end 108.585 -82.804)
		(width 0.127)
		(layer "In2.Cu")
		(net "FPGA_USR_LED1")
	)
	(segment
		(start 96.0501 -67.19824)
		(end 94.091252 -67.19824)
		(width 0.127)
		(layer "In2.Cu")
		(net "FPGA_USR_LED1")
	)
	(segment
		(start 93.294962 -50.546)
		(end 97.314512 -46.52645)
		(width 0.127)
		(layer "In2.Cu")
		(net "FPGA_USR_LED1")
	)
	(segment
		(start 128.778 -98.552)
		(end 122.839988 -98.552)
		(width 0.127)
		(layer "In2.Cu")
		(net "FPGA_USR_LED1")
	)
	(segment
		(start 134.90956 -102.5525)
		(end 132.7785 -102.5525)
		(width 0.127)
		(layer "In2.Cu")
		(net "FPGA_USR_LED1")
	)
	(segment
		(start 87.9221 -56.0959)
		(end 88.519 -55.499)
		(width 0.127)
		(layer "In2.Cu")
		(net "FPGA_USR_LED1")
	)
	(segment
		(start 105.309416 -75.284584)
		(end 103.478584 -75.284584)
		(width 0.127)
		(layer "In2.Cu")
		(net "FPGA_USR_LED1")
	)
	(segment
		(start 91.059 -50.546)
		(end 93.294962 -50.546)
		(width 0.127)
		(layer "In2.Cu")
		(net "FPGA_USR_LED1")
	)
	(segment
		(start 106.388916 -76.364084)
		(end 105.309416 -75.284584)
		(width 0.127)
		(layer "In2.Cu")
		(net "FPGA_USR_LED1")
	)
	(segment
		(start 151.510746 -106.045)
		(end 149.605746 -107.95)
		(width 0.127)
		(layer "In2.Cu")
		(net "FPGA_USR_LED1")
	)
	(segment
		(start 135.3185 -106.4895)
		(end 135.3185 -102.96144)
		(width 0.127)
		(layer "In2.Cu")
		(net "FPGA_USR_LED1")
	)
	(segment
		(start 89.76868 -63.9191)
		(end 87.9221 -62.07252)
		(width 0.127)
		(layer "In2.Cu")
		(net "FPGA_USR_LED1")
	)
	(segment
		(start 102.5017 -74.3077)
		(end 102.5017 -69.989446)
		(width 0.127)
		(layer "In2.Cu")
		(net "FPGA_USR_LED1")
	)
	(segment
		(start 98.06686 -69.215)
		(end 96.0501 -67.19824)
		(width 0.127)
		(layer "In2.Cu")
		(net "FPGA_USR_LED1")
	)
	(segment
		(start 97.314512 -46.52645)
		(end 97.314512 -45.306488)
		(width 0.127)
		(layer "In2.Cu")
		(net "FPGA_USR_LED1")
	)
	(segment
		(start 132.7785 -102.5525)
		(end 128.778 -98.552)
		(width 0.127)
		(layer "In2.Cu")
		(net "FPGA_USR_LED1")
	)
	(segment
		(start 88.519 -53.086)
		(end 91.059 -50.546)
		(width 0.127)
		(layer "In2.Cu")
		(net "FPGA_USR_LED1")
	)
	(segment
		(start 103.478584 -75.284584)
		(end 102.5017 -74.3077)
		(width 0.127)
		(layer "In2.Cu")
		(net "FPGA_USR_LED1")
	)
	(segment
		(start 153.049986 -106.045)
		(end 151.510746 -106.045)
		(width 0.127)
		(layer "In2.Cu")
		(net "FPGA_USR_LED1")
	)
	(segment
		(start 102.5017 -69.989446)
		(end 101.727254 -69.215)
		(width 0.127)
		(layer "In2.Cu")
		(net "FPGA_USR_LED1")
	)
	(segment
		(start 101.727254 -69.215)
		(end 98.06686 -69.215)
		(width 0.127)
		(layer "In2.Cu")
		(net "FPGA_USR_LED1")
	)
	(segment
		(start 106.388916 -80.607916)
		(end 106.388916 -76.364084)
		(width 0.127)
		(layer "In2.Cu")
		(net "FPGA_USR_LED1")
	)
	(segment
		(start 135.3185 -102.96144)
		(end 134.90956 -102.5525)
		(width 0.127)
		(layer "In2.Cu")
		(net "FPGA_USR_LED1")
	)
	(segment
		(start 156.04998 -107.100116)
		(end 156.04998 -106.045)
		(width 0.11938)
		(layer "F.Cu")
		(net "FPGA_USR_LED0")
	)
	(segment
		(start 98.846894 -46.823122)
		(end 98.347022 -47.322994)
		(width 0.11938)
		(layer "F.Cu")
		(net "FPGA_USR_LED0")
	)
	(via
		(at 156.04998 -106.045)
		(size 0.508)
		(drill 0.254)
		(layers "F.Cu" "B.Cu")
		(net "FPGA_USR_LED0")
	)
	(via
		(at 98.347022 -47.322994)
		(size 0.4572)
		(drill 0.2032)
		(layers "F.Cu" "B.Cu")
		(net "FPGA_USR_LED0")
	)
	(segment
		(start 151.85009 -104.521)
		(end 151.46909 -104.14)
		(width 0.127)
		(layer "In2.Cu")
		(net "FPGA_USR_LED0")
	)
	(segment
		(start 129.032 -91.44)
		(end 127.508 -92.964)
		(width 0.127)
		(layer "In2.Cu")
		(net "FPGA_USR_LED0")
	)
	(segment
		(start 156.04998 -106.045)
		(end 156.04998 -105.12298)
		(width 0.127)
		(layer "In2.Cu")
		(net "FPGA_USR_LED0")
	)
	(segment
		(start 102.362 -68.072)
		(end 98.596196 -68.072)
		(width 0.127)
		(layer "In2.Cu")
		(net "FPGA_USR_LED0")
	)
	(segment
		(start 142.113 -104.775)
		(end 142.113 -105.791)
		(width 0.127)
		(layer "In2.Cu")
		(net "FPGA_USR_LED0")
	)
	(segment
		(start 106.3371 -74.683112)
		(end 104.5337 -72.879712)
		(width 0.127)
		(layer "In2.Cu")
		(net "FPGA_USR_LED0")
	)
	(segment
		(start 98.135186 -47.322994)
		(end 98.347022 -47.322994)
		(width 0.127)
		(layer "In2.Cu")
		(net "FPGA_USR_LED0")
	)
	(segment
		(start 155.448 -104.521)
		(end 151.85009 -104.521)
		(width 0.127)
		(layer "In2.Cu")
		(net "FPGA_USR_LED0")
	)
	(segment
		(start 136.271 -95.534988)
		(end 132.176012 -91.44)
		(width 0.127)
		(layer "In2.Cu")
		(net "FPGA_USR_LED0")
	)
	(segment
		(start 104.5337 -70.2437)
		(end 102.362 -68.072)
		(width 0.127)
		(layer "In2.Cu")
		(net "FPGA_USR_LED0")
	)
	(segment
		(start 90.8685 -53.561488)
		(end 92.131388 -52.2986)
		(width 0.127)
		(layer "In2.Cu")
		(net "FPGA_USR_LED0")
	)
	(segment
		(start 93.472 -61.849)
		(end 93.98 -61.341)
		(width 0.127)
		(layer "In2.Cu")
		(net "FPGA_USR_LED0")
	)
	(segment
		(start 132.176012 -91.44)
		(end 129.032 -91.44)
		(width 0.127)
		(layer "In2.Cu")
		(net "FPGA_USR_LED0")
	)
	(segment
		(start 115.57 -89.346024)
		(end 115.57 -88.06561)
		(width 0.127)
		(layer "In2.Cu")
		(net "FPGA_USR_LED0")
	)
	(segment
		(start 110.744 -81.026)
		(end 109.347 -81.026)
		(width 0.127)
		(layer "In2.Cu")
		(net "FPGA_USR_LED0")
	)
	(segment
		(start 94.59976 -66.05524)
		(end 93.472 -64.92748)
		(width 0.127)
		(layer "In2.Cu")
		(net "FPGA_USR_LED0")
	)
	(segment
		(start 127.508 -92.964)
		(end 122.27306 -92.964)
		(width 0.127)
		(layer "In2.Cu")
		(net "FPGA_USR_LED0")
	)
	(segment
		(start 98.596196 -68.072)
		(end 96.579436 -66.05524)
		(width 0.127)
		(layer "In2.Cu")
		(net "FPGA_USR_LED0")
	)
	(segment
		(start 121.00306 -91.694)
		(end 117.917976 -91.694)
		(width 0.127)
		(layer "In2.Cu")
		(net "FPGA_USR_LED0")
	)
	(segment
		(start 156.04998 -105.12298)
		(end 155.448 -104.521)
		(width 0.127)
		(layer "In2.Cu")
		(net "FPGA_USR_LED0")
	)
	(segment
		(start 142.748 -104.14)
		(end 142.113 -104.775)
		(width 0.127)
		(layer "In2.Cu")
		(net "FPGA_USR_LED0")
	)
	(segment
		(start 141.097 -106.807)
		(end 138.557 -106.807)
		(width 0.127)
		(layer "In2.Cu")
		(net "FPGA_USR_LED0")
	)
	(segment
		(start 109.347 -81.026)
		(end 107.95 -79.629)
		(width 0.127)
		(layer "In2.Cu")
		(net "FPGA_USR_LED0")
	)
	(segment
		(start 91.44 -57.785)
		(end 90.8685 -57.2135)
		(width 0.127)
		(layer "In2.Cu")
		(net "FPGA_USR_LED0")
	)
	(segment
		(start 113.665 -83.947)
		(end 110.744 -81.026)
		(width 0.127)
		(layer "In2.Cu")
		(net "FPGA_USR_LED0")
	)
	(segment
		(start 90.8685 -57.2135)
		(end 90.8685 -53.561488)
		(width 0.127)
		(layer "In2.Cu")
		(net "FPGA_USR_LED0")
	)
	(segment
		(start 93.15958 -52.2986)
		(end 98.135186 -47.322994)
		(width 0.127)
		(layer "In2.Cu")
		(net "FPGA_USR_LED0")
	)
	(segment
		(start 104.5337 -72.879712)
		(end 104.5337 -70.2437)
		(width 0.127)
		(layer "In2.Cu")
		(net "FPGA_USR_LED0")
	)
	(segment
		(start 115.57 -88.06561)
		(end 113.665 -86.16061)
		(width 0.127)
		(layer "In2.Cu")
		(net "FPGA_USR_LED0")
	)
	(segment
		(start 151.46909 -104.14)
		(end 142.748 -104.14)
		(width 0.127)
		(layer "In2.Cu")
		(net "FPGA_USR_LED0")
	)
	(segment
		(start 93.472 -64.92748)
		(end 93.472 -61.849)
		(width 0.127)
		(layer "In2.Cu")
		(net "FPGA_USR_LED0")
	)
	(segment
		(start 137.6045 -105.8545)
		(end 137.6045 -103.1875)
		(width 0.127)
		(layer "In2.Cu")
		(net "FPGA_USR_LED0")
	)
	(segment
		(start 138.557 -106.807)
		(end 137.6045 -105.8545)
		(width 0.127)
		(layer "In2.Cu")
		(net "FPGA_USR_LED0")
	)
	(segment
		(start 93.98 -58.42)
		(end 93.345 -57.785)
		(width 0.127)
		(layer "In2.Cu")
		(net "FPGA_USR_LED0")
	)
	(segment
		(start 107.95 -79.629)
		(end 107.95 -76.308204)
		(width 0.127)
		(layer "In2.Cu")
		(net "FPGA_USR_LED0")
	)
	(segment
		(start 107.95 -76.308204)
		(end 106.3371 -74.695304)
		(width 0.127)
		(layer "In2.Cu")
		(net "FPGA_USR_LED0")
	)
	(segment
		(start 137.6045 -103.1875)
		(end 136.271 -101.854)
		(width 0.127)
		(layer "In2.Cu")
		(net "FPGA_USR_LED0")
	)
	(segment
		(start 93.98 -61.341)
		(end 93.98 -58.42)
		(width 0.127)
		(layer "In2.Cu")
		(net "FPGA_USR_LED0")
	)
	(segment
		(start 92.131388 -52.2986)
		(end 93.15958 -52.2986)
		(width 0.127)
		(layer "In2.Cu")
		(net "FPGA_USR_LED0")
	)
	(segment
		(start 117.917976 -91.694)
		(end 115.57 -89.346024)
		(width 0.127)
		(layer "In2.Cu")
		(net "FPGA_USR_LED0")
	)
	(segment
		(start 122.27306 -92.964)
		(end 121.00306 -91.694)
		(width 0.127)
		(layer "In2.Cu")
		(net "FPGA_USR_LED0")
	)
	(segment
		(start 113.665 -86.16061)
		(end 113.665 -83.947)
		(width 0.127)
		(layer "In2.Cu")
		(net "FPGA_USR_LED0")
	)
	(segment
		(start 96.579436 -66.05524)
		(end 94.59976 -66.05524)
		(width 0.127)
		(layer "In2.Cu")
		(net "FPGA_USR_LED0")
	)
	(segment
		(start 93.345 -57.785)
		(end 91.44 -57.785)
		(width 0.127)
		(layer "In2.Cu")
		(net "FPGA_USR_LED0")
	)
	(segment
		(start 136.271 -101.854)
		(end 136.271 -95.534988)
		(width 0.127)
		(layer "In2.Cu")
		(net "FPGA_USR_LED0")
	)
	(segment
		(start 142.113 -105.791)
		(end 141.097 -106.807)
		(width 0.127)
		(layer "In2.Cu")
		(net "FPGA_USR_LED0")
	)
	(segment
		(start 106.3371 -74.695304)
		(end 106.3371 -74.683112)
		(width 0.127)
		(layer "In2.Cu")
		(net "FPGA_USR_LED0")
	)
	(segment
		(start 149.848062 -59.182)
		(end 149.848062 -60.0964)
		(width 0.11938)
		(layer "F.Cu")
		(net "FPGA_OUT_SHT3X_RST_N")
	)
	(segment
		(start 105.847134 -51.823112)
		(end 105.347262 -52.322984)
		(width 0.11938)
		(layer "F.Cu")
		(net "FPGA_OUT_SHT3X_RST_N")
	)
	(via
		(at 105.347262 -52.322984)
		(size 0.4572)
		(drill 0.2032)
		(layers "F.Cu" "B.Cu")
		(net "FPGA_OUT_SHT3X_RST_N")
	)
	(via
		(at 149.848062 -60.0964)
		(size 0.4572)
		(drill 0.2032)
		(layers "F.Cu" "B.Cu")
		(net "FPGA_OUT_SHT3X_RST_N")
	)
	(via
		(at 148.082 -75.438)
		(size 0.508)
		(drill 0.254)
		(layers "F.Cu" "B.Cu")
		(net "FPGA_OUT_SHT3X_RST_N")
	)
	(segment
		(start 132.925566 -79.121)
		(end 129.286 -82.760566)
		(width 0.127)
		(layer "In2.Cu")
		(net "FPGA_OUT_SHT3X_RST_N")
	)
	(segment
		(start 114.935 -82.181446)
		(end 114.935 -80.772)
		(width 0.127)
		(layer "In2.Cu")
		(net "FPGA_OUT_SHT3X_RST_N")
	)
	(segment
		(start 109.474 -72.686418)
		(end 109.474 -71.373746)
		(width 0.127)
		(layer "In2.Cu")
		(net "FPGA_OUT_SHT3X_RST_N")
	)
	(segment
		(start 144.399 -79.121)
		(end 132.925566 -79.121)
		(width 0.127)
		(layer "In2.Cu")
		(net "FPGA_OUT_SHT3X_RST_N")
	)
	(segment
		(start 116.332 -83.578446)
		(end 114.935 -82.181446)
		(width 0.127)
		(layer "In2.Cu")
		(net "FPGA_OUT_SHT3X_RST_N")
	)
	(segment
		(start 120.522746 -90.424)
		(end 116.332 -86.233254)
		(width 0.127)
		(layer "In2.Cu")
		(net "FPGA_OUT_SHT3X_RST_N")
	)
	(segment
		(start 125.222254 -90.424)
		(end 120.522746 -90.424)
		(width 0.127)
		(layer "In2.Cu")
		(net "FPGA_OUT_SHT3X_RST_N")
	)
	(segment
		(start 112.0775 -76.471018)
		(end 110.5662 -74.959718)
		(width 0.127)
		(layer "In2.Cu")
		(net "FPGA_OUT_SHT3X_RST_N")
	)
	(segment
		(start 114.935 -80.772)
		(end 114.6175 -80.4545)
		(width 0.127)
		(layer "In2.Cu")
		(net "FPGA_OUT_SHT3X_RST_N")
	)
	(segment
		(start 104.6226 -65.087246)
		(end 104.6226 -58.098436)
		(width 0.127)
		(layer "In2.Cu")
		(net "FPGA_OUT_SHT3X_RST_N")
	)
	(segment
		(start 112.522 -77.343)
		(end 112.0775 -76.8985)
		(width 0.127)
		(layer "In2.Cu")
		(net "FPGA_OUT_SHT3X_RST_N")
	)
	(segment
		(start 129.286 -84.535518)
		(end 127.5715 -86.250018)
		(width 0.127)
		(layer "In2.Cu")
		(net "FPGA_OUT_SHT3X_RST_N")
	)
	(segment
		(start 110.5662 -73.778618)
		(end 109.474 -72.686418)
		(width 0.127)
		(layer "In2.Cu")
		(net "FPGA_OUT_SHT3X_RST_N")
	)
	(segment
		(start 127.5715 -88.074754)
		(end 125.222254 -90.424)
		(width 0.127)
		(layer "In2.Cu")
		(net "FPGA_OUT_SHT3X_RST_N")
	)
	(segment
		(start 110.5662 -74.959718)
		(end 110.5662 -73.778618)
		(width 0.127)
		(layer "In2.Cu")
		(net "FPGA_OUT_SHT3X_RST_N")
	)
	(segment
		(start 114.6175 -80.4545)
		(end 113.474246 -80.4545)
		(width 0.127)
		(layer "In2.Cu")
		(net "FPGA_OUT_SHT3X_RST_N")
	)
	(segment
		(start 113.474246 -80.4545)
		(end 112.522 -79.502254)
		(width 0.127)
		(layer "In2.Cu")
		(net "FPGA_OUT_SHT3X_RST_N")
	)
	(segment
		(start 105.766362 -52.742084)
		(end 105.347262 -52.322984)
		(width 0.127)
		(layer "In2.Cu")
		(net "FPGA_OUT_SHT3X_RST_N")
	)
	(segment
		(start 112.0775 -76.8985)
		(end 112.0775 -76.471018)
		(width 0.127)
		(layer "In2.Cu")
		(net "FPGA_OUT_SHT3X_RST_N")
	)
	(segment
		(start 109.474 -71.373746)
		(end 107.569 -69.468746)
		(width 0.127)
		(layer "In2.Cu")
		(net "FPGA_OUT_SHT3X_RST_N")
	)
	(segment
		(start 116.332 -86.233254)
		(end 116.332 -83.578446)
		(width 0.127)
		(layer "In2.Cu")
		(net "FPGA_OUT_SHT3X_RST_N")
	)
	(segment
		(start 148.082 -75.438)
		(end 144.399 -79.121)
		(width 0.127)
		(layer "In2.Cu")
		(net "FPGA_OUT_SHT3X_RST_N")
	)
	(segment
		(start 107.569 -69.468746)
		(end 107.569 -68.033646)
		(width 0.127)
		(layer "In2.Cu")
		(net "FPGA_OUT_SHT3X_RST_N")
	)
	(segment
		(start 127.5715 -86.250018)
		(end 127.5715 -88.074754)
		(width 0.127)
		(layer "In2.Cu")
		(net "FPGA_OUT_SHT3X_RST_N")
	)
	(segment
		(start 105.766362 -56.954674)
		(end 105.766362 -52.742084)
		(width 0.127)
		(layer "In2.Cu")
		(net "FPGA_OUT_SHT3X_RST_N")
	)
	(segment
		(start 107.569 -68.033646)
		(end 104.6226 -65.087246)
		(width 0.127)
		(layer "In2.Cu")
		(net "FPGA_OUT_SHT3X_RST_N")
	)
	(segment
		(start 104.6226 -58.098436)
		(end 105.766362 -56.954674)
		(width 0.127)
		(layer "In2.Cu")
		(net "FPGA_OUT_SHT3X_RST_N")
	)
	(segment
		(start 112.522 -79.502254)
		(end 112.522 -77.343)
		(width 0.127)
		(layer "In2.Cu")
		(net "FPGA_OUT_SHT3X_RST_N")
	)
	(segment
		(start 129.286 -82.760566)
		(end 129.286 -84.535518)
		(width 0.127)
		(layer "In2.Cu")
		(net "FPGA_OUT_SHT3X_RST_N")
	)
	(segment
		(start 149.848062 -60.464192)
		(end 149.848062 -60.0964)
		(width 0.127)
		(layer "In7.Cu")
		(net "FPGA_OUT_SHT3X_RST_N")
	)
	(segment
		(start 148.6027 -74.9173)
		(end 148.6027 -64.638174)
		(width 0.127)
		(layer "In7.Cu")
		(net "FPGA_OUT_SHT3X_RST_N")
	)
	(segment
		(start 148.784056 -61.528198)
		(end 149.848062 -60.464192)
		(width 0.127)
		(layer "In7.Cu")
		(net "FPGA_OUT_SHT3X_RST_N")
	)
	(segment
		(start 148.082 -75.438)
		(end 148.6027 -74.9173)
		(width 0.127)
		(layer "In7.Cu")
		(net "FPGA_OUT_SHT3X_RST_N")
	)
	(segment
		(start 148.784056 -64.456818)
		(end 148.784056 -61.528198)
		(width 0.127)
		(layer "In7.Cu")
		(net "FPGA_OUT_SHT3X_RST_N")
	)
	(segment
		(start 148.6027 -64.638174)
		(end 148.784056 -64.456818)
		(width 0.127)
		(layer "In7.Cu")
		(net "FPGA_OUT_SHT3X_RST_N")
	)
	(segment
		(start 114.847116 -48.823118)
		(end 115.346988 -49.32299)
		(width 0.11938)
		(layer "F.Cu")
		(net "FPGA_OUT_PCA9546_RST_N")
	)
	(via
		(at 115.346988 -49.32299)
		(size 0.4572)
		(drill 0.2032)
		(layers "F.Cu" "B.Cu")
		(net "FPGA_OUT_PCA9546_RST_N")
	)
	(via
		(at 91.725496 -88.868504)
		(size 0.4572)
		(drill 0.2032)
		(layers "F.Cu" "B.Cu")
		(net "FPGA_OUT_PCA9546_RST_N")
	)
	(segment
		(start 91.504008 -89.027)
		(end 91.662504 -88.868504)
		(width 0.11938)
		(layer "B.Cu")
		(net "FPGA_OUT_PCA9546_RST_N")
	)
	(segment
		(start 82.7024 -88.798146)
		(end 82.931254 -89.027)
		(width 0.11938)
		(layer "B.Cu")
		(net "FPGA_OUT_PCA9546_RST_N")
	)
	(segment
		(start 82.7024 -88.265)
		(end 82.7024 -88.798146)
		(width 0.11938)
		(layer "B.Cu")
		(net "FPGA_OUT_PCA9546_RST_N")
	)
	(segment
		(start 91.662504 -88.868504)
		(end 91.725496 -88.868504)
		(width 0.11938)
		(layer "B.Cu")
		(net "FPGA_OUT_PCA9546_RST_N")
	)
	(segment
		(start 82.931254 -89.027)
		(end 91.504008 -89.027)
		(width 0.11938)
		(layer "B.Cu")
		(net "FPGA_OUT_PCA9546_RST_N")
	)
	(segment
		(start 117.729 -58.166254)
		(end 116.8654 -57.302654)
		(width 0.127)
		(layer "In7.Cu")
		(net "FPGA_OUT_PCA9546_RST_N")
	)
	(segment
		(start 118.8339 -66.0019)
		(end 118.8339 -63.081154)
		(width 0.127)
		(layer "In7.Cu")
		(net "FPGA_OUT_PCA9546_RST_N")
	)
	(segment
		(start 116.078254 -49.784)
		(end 115.617244 -49.32299)
		(width 0.127)
		(layer "In7.Cu")
		(net "FPGA_OUT_PCA9546_RST_N")
	)
	(segment
		(start 95.885 -87.376)
		(end 98.471482 -87.376)
		(width 0.127)
		(layer "In7.Cu")
		(net "FPGA_OUT_PCA9546_RST_N")
	)
	(segment
		(start 116.586 -49.784)
		(end 116.078254 -49.784)
		(width 0.127)
		(layer "In7.Cu")
		(net "FPGA_OUT_PCA9546_RST_N")
	)
	(segment
		(start 108.123482 -86.233)
		(end 113.457482 -80.899)
		(width 0.127)
		(layer "In7.Cu")
		(net "FPGA_OUT_PCA9546_RST_N")
	)
	(segment
		(start 104.376982 -86.4235)
		(end 104.567482 -86.233)
		(width 0.127)
		(layer "In7.Cu")
		(net "FPGA_OUT_PCA9546_RST_N")
	)
	(segment
		(start 116.6495 -78.757018)
		(end 116.880132 -78.526386)
		(width 0.127)
		(layer "In7.Cu")
		(net "FPGA_OUT_PCA9546_RST_N")
	)
	(segment
		(start 116.880132 -77.510132)
		(end 116.205 -76.835)
		(width 0.127)
		(layer "In7.Cu")
		(net "FPGA_OUT_PCA9546_RST_N")
	)
	(segment
		(start 116.6495 -79.525368)
		(end 116.6495 -78.757018)
		(width 0.127)
		(layer "In7.Cu")
		(net "FPGA_OUT_PCA9546_RST_N")
	)
	(segment
		(start 116.205 -71.882)
		(end 118.4402 -69.6468)
		(width 0.127)
		(layer "In7.Cu")
		(net "FPGA_OUT_PCA9546_RST_N")
	)
	(segment
		(start 118.9482 -69.6468)
		(end 119.761 -68.834)
		(width 0.127)
		(layer "In7.Cu")
		(net "FPGA_OUT_PCA9546_RST_N")
	)
	(segment
		(start 116.8654 -50.0634)
		(end 116.586 -49.784)
		(width 0.127)
		(layer "In7.Cu")
		(net "FPGA_OUT_PCA9546_RST_N")
	)
	(segment
		(start 119.761 -66.929)
		(end 118.8339 -66.0019)
		(width 0.127)
		(layer "In7.Cu")
		(net "FPGA_OUT_PCA9546_RST_N")
	)
	(segment
		(start 115.617244 -49.32299)
		(end 115.346988 -49.32299)
		(width 0.127)
		(layer "In7.Cu")
		(net "FPGA_OUT_PCA9546_RST_N")
	)
	(segment
		(start 116.205 -76.835)
		(end 116.205 -71.882)
		(width 0.127)
		(layer "In7.Cu")
		(net "FPGA_OUT_PCA9546_RST_N")
	)
	(segment
		(start 115.275868 -80.899)
		(end 116.6495 -79.525368)
		(width 0.127)
		(layer "In7.Cu")
		(net "FPGA_OUT_PCA9546_RST_N")
	)
	(segment
		(start 116.880132 -78.526386)
		(end 116.880132 -77.510132)
		(width 0.127)
		(layer "In7.Cu")
		(net "FPGA_OUT_PCA9546_RST_N")
	)
	(segment
		(start 93.345 -89.916)
		(end 95.885 -87.376)
		(width 0.127)
		(layer "In7.Cu")
		(net "FPGA_OUT_PCA9546_RST_N")
	)
	(segment
		(start 119.761 -68.834)
		(end 119.761 -66.929)
		(width 0.127)
		(layer "In7.Cu")
		(net "FPGA_OUT_PCA9546_RST_N")
	)
	(segment
		(start 118.4402 -69.6468)
		(end 118.9482 -69.6468)
		(width 0.127)
		(layer "In7.Cu")
		(net "FPGA_OUT_PCA9546_RST_N")
	)
	(segment
		(start 113.457482 -80.899)
		(end 115.275868 -80.899)
		(width 0.127)
		(layer "In7.Cu")
		(net "FPGA_OUT_PCA9546_RST_N")
	)
	(segment
		(start 92.772992 -89.916)
		(end 93.345 -89.916)
		(width 0.127)
		(layer "In7.Cu")
		(net "FPGA_OUT_PCA9546_RST_N")
	)
	(segment
		(start 98.471482 -87.376)
		(end 99.423982 -86.4235)
		(width 0.127)
		(layer "In7.Cu")
		(net "FPGA_OUT_PCA9546_RST_N")
	)
	(segment
		(start 91.725496 -88.868504)
		(end 92.772992 -89.916)
		(width 0.127)
		(layer "In7.Cu")
		(net "FPGA_OUT_PCA9546_RST_N")
	)
	(segment
		(start 104.567482 -86.233)
		(end 108.123482 -86.233)
		(width 0.127)
		(layer "In7.Cu")
		(net "FPGA_OUT_PCA9546_RST_N")
	)
	(segment
		(start 117.729 -61.976254)
		(end 117.729 -58.166254)
		(width 0.127)
		(layer "In7.Cu")
		(net "FPGA_OUT_PCA9546_RST_N")
	)
	(segment
		(start 118.8339 -63.081154)
		(end 117.729 -61.976254)
		(width 0.127)
		(layer "In7.Cu")
		(net "FPGA_OUT_PCA9546_RST_N")
	)
	(segment
		(start 99.423982 -86.4235)
		(end 104.376982 -86.4235)
		(width 0.127)
		(layer "In7.Cu")
		(net "FPGA_OUT_PCA9546_RST_N")
	)
	(segment
		(start 116.8654 -57.302654)
		(end 116.8654 -50.0634)
		(width 0.127)
		(layer "In7.Cu")
		(net "FPGA_OUT_PCA9546_RST_N")
	)
	(segment
		(start 49.910238 -19.431508)
		(end 49.910238 -16.884142)
		(width 0.11938)
		(layer "F.Cu")
		(net "FPGA_OUT_I2C_BUFFER_EN")
	)
	(segment
		(start 49.910238 -16.884142)
		(end 50.74158 -16.0528)
		(width 0.11938)
		(layer "F.Cu")
		(net "FPGA_OUT_I2C_BUFFER_EN")
	)
	(segment
		(start 107.84713 -48.823118)
		(end 107.347258 -49.32299)
		(width 0.11938)
		(layer "F.Cu")
		(net "FPGA_OUT_I2C_BUFFER_EN")
	)
	(via
		(at 49.910238 -19.431508)
		(size 0.4572)
		(drill 0.2032)
		(layers "F.Cu" "B.Cu")
		(net "FPGA_OUT_I2C_BUFFER_EN")
	)
	(via
		(at 107.347258 -49.32299)
		(size 0.4572)
		(drill 0.2032)
		(layers "F.Cu" "B.Cu")
		(net "FPGA_OUT_I2C_BUFFER_EN")
	)
	(segment
		(start 101.17836 -44.87164)
		(end 100.838 -45.212)
		(width 0.11938)
		(layer "B.Cu")
		(net "FPGA_OUT_I2C_BUFFER_EN")
	)
	(segment
		(start 103.54564 -44.87164)
		(end 101.17836 -44.87164)
		(width 0.11938)
		(layer "B.Cu")
		(net "FPGA_OUT_I2C_BUFFER_EN")
	)
	(segment
		(start 103.83012 -46.70552)
		(end 103.83012 -45.15612)
		(width 0.11938)
		(layer "B.Cu")
		(net "FPGA_OUT_I2C_BUFFER_EN")
	)
	(segment
		(start 90.0176 -43.6118)
		(end 83.744054 -43.6118)
		(width 0.11938)
		(layer "B.Cu")
		(net "FPGA_OUT_I2C_BUFFER_EN")
	)
	(segment
		(start 100.838 -45.593)
		(end 100.617782 -45.813218)
		(width 0.11938)
		(layer "B.Cu")
		(net "FPGA_OUT_I2C_BUFFER_EN")
	)
	(segment
		(start 105.918 -47.1932)
		(end 105.6132 -46.8884)
		(width 0.11938)
		(layer "B.Cu")
		(net "FPGA_OUT_I2C_BUFFER_EN")
	)
	(segment
		(start 95.868236 -46.609)
		(end 93.0148 -46.609)
		(width 0.11938)
		(layer "B.Cu")
		(net "FPGA_OUT_I2C_BUFFER_EN")
	)
	(segment
		(start 100.838 -45.212)
		(end 100.838 -45.593)
		(width 0.11938)
		(layer "B.Cu")
		(net "FPGA_OUT_I2C_BUFFER_EN")
	)
	(segment
		(start 105.6132 -46.8884)
		(end 104.013 -46.8884)
		(width 0.11938)
		(layer "B.Cu")
		(net "FPGA_OUT_I2C_BUFFER_EN")
	)
	(segment
		(start 107.347258 -49.32299)
		(end 106.817668 -48.7934)
		(width 0.11938)
		(layer "B.Cu")
		(net "FPGA_OUT_I2C_BUFFER_EN")
	)
	(segment
		(start 103.83012 -45.15612)
		(end 103.54564 -44.87164)
		(width 0.11938)
		(layer "B.Cu")
		(net "FPGA_OUT_I2C_BUFFER_EN")
	)
	(segment
		(start 105.918 -48.5902)
		(end 105.918 -47.1932)
		(width 0.11938)
		(layer "B.Cu")
		(net "FPGA_OUT_I2C_BUFFER_EN")
	)
	(segment
		(start 80.010254 -39.878)
		(end 68.50634 -39.878)
		(width 0.11938)
		(layer "B.Cu")
		(net "FPGA_OUT_I2C_BUFFER_EN")
	)
	(segment
		(start 96.664018 -45.813218)
		(end 95.868236 -46.609)
		(width 0.11938)
		(layer "B.Cu")
		(net "FPGA_OUT_I2C_BUFFER_EN")
	)
	(segment
		(start 83.744054 -43.6118)
		(end 80.010254 -39.878)
		(width 0.11938)
		(layer "B.Cu")
		(net "FPGA_OUT_I2C_BUFFER_EN")
	)
	(segment
		(start 106.817668 -48.7934)
		(end 106.1212 -48.7934)
		(width 0.11938)
		(layer "B.Cu")
		(net "FPGA_OUT_I2C_BUFFER_EN")
	)
	(segment
		(start 93.0148 -46.609)
		(end 90.0176 -43.6118)
		(width 0.11938)
		(layer "B.Cu")
		(net "FPGA_OUT_I2C_BUFFER_EN")
	)
	(segment
		(start 49.910238 -21.281898)
		(end 49.910238 -19.431508)
		(width 0.11938)
		(layer "B.Cu")
		(net "FPGA_OUT_I2C_BUFFER_EN")
	)
	(segment
		(start 104.013 -46.8884)
		(end 103.83012 -46.70552)
		(width 0.11938)
		(layer "B.Cu")
		(net "FPGA_OUT_I2C_BUFFER_EN")
	)
	(segment
		(start 106.1212 -48.7934)
		(end 105.918 -48.5902)
		(width 0.11938)
		(layer "B.Cu")
		(net "FPGA_OUT_I2C_BUFFER_EN")
	)
	(segment
		(start 100.617782 -45.813218)
		(end 96.664018 -45.813218)
		(width 0.11938)
		(layer "B.Cu")
		(net "FPGA_OUT_I2C_BUFFER_EN")
	)
	(segment
		(start 68.50634 -39.878)
		(end 49.910238 -21.281898)
		(width 0.11938)
		(layer "B.Cu")
		(net "FPGA_OUT_I2C_BUFFER_EN")
	)
	(segment
		(start 80.2386 -58.3946)
		(end 79.2226 -58.3946)
		(width 0.11938)
		(layer "F.Cu")
		(net "FPGA_OUT_BNO080_RST_N")
	)
	(segment
		(start 106.847132 -49.823116)
		(end 106.34726 -50.322988)
		(width 0.11938)
		(layer "F.Cu")
		(net "FPGA_OUT_BNO080_RST_N")
	)
	(via
		(at 79.248 -65.151)
		(size 0.508)
		(drill 0.254)
		(layers "F.Cu" "B.Cu")
		(net "FPGA_OUT_BNO080_RST_N")
	)
	(via
		(at 106.34726 -50.322988)
		(size 0.4572)
		(drill 0.2032)
		(layers "F.Cu" "B.Cu")
		(net "FPGA_OUT_BNO080_RST_N")
	)
	(via
		(at 79.2226 -58.3946)
		(size 0.508)
		(drill 0.254)
		(layers "F.Cu" "B.Cu")
		(net "FPGA_OUT_BNO080_RST_N")
	)
	(segment
		(start 80.137 -59.3598)
		(end 79.2226 -58.4454)
		(width 0.127)
		(layer "In2.Cu")
		(net "FPGA_OUT_BNO080_RST_N")
	)
	(segment
		(start 79.2226 -58.4454)
		(end 79.2226 -58.3946)
		(width 0.127)
		(layer "In2.Cu")
		(net "FPGA_OUT_BNO080_RST_N")
	)
	(segment
		(start 80.137 -64.262)
		(end 80.137 -59.3598)
		(width 0.127)
		(layer "In2.Cu")
		(net "FPGA_OUT_BNO080_RST_N")
	)
	(segment
		(start 79.248 -65.151)
		(end 80.137 -64.262)
		(width 0.127)
		(layer "In2.Cu")
		(net "FPGA_OUT_BNO080_RST_N")
	)
	(segment
		(start 105.50144 -50.83556)
		(end 106.014012 -50.322988)
		(width 0.127)
		(layer "In7.Cu")
		(net "FPGA_OUT_BNO080_RST_N")
	)
	(segment
		(start 96.283526 -66.675)
		(end 97.686876 -65.27165)
		(width 0.127)
		(layer "In7.Cu")
		(net "FPGA_OUT_BNO080_RST_N")
	)
	(segment
		(start 102.4255 -60.0075)
		(end 102.4255 -57.421272)
		(width 0.127)
		(layer "In7.Cu")
		(net "FPGA_OUT_BNO080_RST_N")
	)
	(segment
		(start 92.03182 -65.405)
		(end 92.98432 -66.3575)
		(width 0.127)
		(layer "In7.Cu")
		(net "FPGA_OUT_BNO080_RST_N")
	)
	(segment
		(start 106.014012 -50.322988)
		(end 106.34726 -50.322988)
		(width 0.127)
		(layer "In7.Cu")
		(net "FPGA_OUT_BNO080_RST_N")
	)
	(segment
		(start 83.132168 -64.6811)
		(end 87.696548 -64.6811)
		(width 0.127)
		(layer "In7.Cu")
		(net "FPGA_OUT_BNO080_RST_N")
	)
	(segment
		(start 101.6 -62.992)
		(end 101.6 -60.833)
		(width 0.127)
		(layer "In7.Cu")
		(net "FPGA_OUT_BNO080_RST_N")
	)
	(segment
		(start 103.928164 -55.918608)
		(end 103.928164 -51.019456)
		(width 0.127)
		(layer "In7.Cu")
		(net "FPGA_OUT_BNO080_RST_N")
	)
	(segment
		(start 79.248 -65.151)
		(end 80.4672 -63.9318)
		(width 0.127)
		(layer "In7.Cu")
		(net "FPGA_OUT_BNO080_RST_N")
	)
	(segment
		(start 87.696548 -64.6811)
		(end 88.420448 -65.405)
		(width 0.127)
		(layer "In7.Cu")
		(net "FPGA_OUT_BNO080_RST_N")
	)
	(segment
		(start 101.6 -60.833)
		(end 102.4255 -60.0075)
		(width 0.127)
		(layer "In7.Cu")
		(net "FPGA_OUT_BNO080_RST_N")
	)
	(segment
		(start 104.11206 -50.83556)
		(end 105.50144 -50.83556)
		(width 0.127)
		(layer "In7.Cu")
		(net "FPGA_OUT_BNO080_RST_N")
	)
	(segment
		(start 92.98432 -66.3575)
		(end 94.511114 -66.3575)
		(width 0.127)
		(layer "In7.Cu")
		(net "FPGA_OUT_BNO080_RST_N")
	)
	(segment
		(start 102.4255 -57.421272)
		(end 103.928164 -55.918608)
		(width 0.127)
		(layer "In7.Cu")
		(net "FPGA_OUT_BNO080_RST_N")
	)
	(segment
		(start 88.420448 -65.405)
		(end 92.03182 -65.405)
		(width 0.127)
		(layer "In7.Cu")
		(net "FPGA_OUT_BNO080_RST_N")
	)
	(segment
		(start 94.828614 -66.675)
		(end 96.283526 -66.675)
		(width 0.127)
		(layer "In7.Cu")
		(net "FPGA_OUT_BNO080_RST_N")
	)
	(segment
		(start 94.511114 -66.3575)
		(end 94.828614 -66.675)
		(width 0.127)
		(layer "In7.Cu")
		(net "FPGA_OUT_BNO080_RST_N")
	)
	(segment
		(start 103.928164 -51.019456)
		(end 104.11206 -50.83556)
		(width 0.127)
		(layer "In7.Cu")
		(net "FPGA_OUT_BNO080_RST_N")
	)
	(segment
		(start 97.686876 -65.27165)
		(end 99.32035 -65.27165)
		(width 0.127)
		(layer "In7.Cu")
		(net "FPGA_OUT_BNO080_RST_N")
	)
	(segment
		(start 82.382868 -63.9318)
		(end 83.132168 -64.6811)
		(width 0.127)
		(layer "In7.Cu")
		(net "FPGA_OUT_BNO080_RST_N")
	)
	(segment
		(start 80.4672 -63.9318)
		(end 82.382868 -63.9318)
		(width 0.127)
		(layer "In7.Cu")
		(net "FPGA_OUT_BNO080_RST_N")
	)
	(segment
		(start 99.32035 -65.27165)
		(end 101.6 -62.992)
		(width 0.127)
		(layer "In7.Cu")
		(net "FPGA_OUT_BNO080_RST_N")
	)
	(segment
		(start 108.847128 -47.82312)
		(end 108.347256 -48.322992)
		(width 0.11938)
		(layer "F.Cu")
		(net "FPGA_OUT_BNO080_BOOT_N")
	)
	(via
		(at 85.979 -65.786)
		(size 0.508)
		(drill 0.254)
		(layers "F.Cu" "B.Cu")
		(net "FPGA_OUT_BNO080_BOOT_N")
	)
	(via
		(at 108.347256 -48.322992)
		(size 0.4572)
		(drill 0.2032)
		(layers "F.Cu" "B.Cu")
		(net "FPGA_OUT_BNO080_BOOT_N")
	)
	(segment
		(start 85.979 -65.786)
		(end 85.979 -65.2018)
		(width 0.11938)
		(layer "B.Cu")
		(net "FPGA_OUT_BNO080_BOOT_N")
	)
	(segment
		(start 85.979 -65.2018)
		(end 85.6234 -64.8462)
		(width 0.11938)
		(layer "B.Cu")
		(net "FPGA_OUT_BNO080_BOOT_N")
	)
	(segment
		(start 85.6234 -64.8462)
		(end 84.709 -64.8462)
		(width 0.11938)
		(layer "B.Cu")
		(net "FPGA_OUT_BNO080_BOOT_N")
	)
	(segment
		(start 86.487 -66.294)
		(end 86.487 -67.564)
		(width 0.127)
		(layer "In7.Cu")
		(net "FPGA_OUT_BNO080_BOOT_N")
	)
	(segment
		(start 106.045 -52.832)
		(end 106.7435 -52.832)
		(width 0.127)
		(layer "In7.Cu")
		(net "FPGA_OUT_BNO080_BOOT_N")
	)
	(segment
		(start 102.20706 -64.516)
		(end 103.0605 -63.66256)
		(width 0.127)
		(layer "In7.Cu")
		(net "FPGA_OUT_BNO080_BOOT_N")
	)
	(segment
		(start 106.8705 -52.705)
		(end 106.8705 -51.1175)
		(width 0.127)
		(layer "In7.Cu")
		(net "FPGA_OUT_BNO080_BOOT_N")
	)
	(segment
		(start 103.0605 -61.341)
		(end 103.886 -60.5155)
		(width 0.127)
		(layer "In7.Cu")
		(net "FPGA_OUT_BNO080_BOOT_N")
	)
	(segment
		(start 101.5365 -64.516)
		(end 102.20706 -64.516)
		(width 0.127)
		(layer "In7.Cu")
		(net "FPGA_OUT_BNO080_BOOT_N")
	)
	(segment
		(start 85.979 -65.786)
		(end 86.487 -66.294)
		(width 0.127)
		(layer "In7.Cu")
		(net "FPGA_OUT_BNO080_BOOT_N")
	)
	(segment
		(start 86.487 -67.564)
		(end 87.0585 -68.1355)
		(width 0.127)
		(layer "In7.Cu")
		(net "FPGA_OUT_BNO080_BOOT_N")
	)
	(segment
		(start 106.7435 -52.832)
		(end 106.8705 -52.705)
		(width 0.127)
		(layer "In7.Cu")
		(net "FPGA_OUT_BNO080_BOOT_N")
	)
	(segment
		(start 107.902248 -50.419)
		(end 107.902248 -48.768)
		(width 0.127)
		(layer "In7.Cu")
		(net "FPGA_OUT_BNO080_BOOT_N")
	)
	(segment
		(start 103.886 -60.5155)
		(end 103.886 -58.295794)
		(width 0.127)
		(layer "In7.Cu")
		(net "FPGA_OUT_BNO080_BOOT_N")
	)
	(segment
		(start 94.407482 -67.691)
		(end 98.3615 -67.691)
		(width 0.127)
		(layer "In7.Cu")
		(net "FPGA_OUT_BNO080_BOOT_N")
	)
	(segment
		(start 107.521248 -50.8)
		(end 107.902248 -50.419)
		(width 0.127)
		(layer "In7.Cu")
		(net "FPGA_OUT_BNO080_BOOT_N")
	)
	(segment
		(start 105.918 -52.959)
		(end 106.045 -52.832)
		(width 0.127)
		(layer "In7.Cu")
		(net "FPGA_OUT_BNO080_BOOT_N")
	)
	(segment
		(start 87.0585 -68.1355)
		(end 89.73058 -68.1355)
		(width 0.127)
		(layer "In7.Cu")
		(net "FPGA_OUT_BNO080_BOOT_N")
	)
	(segment
		(start 98.3615 -67.691)
		(end 101.5365 -64.516)
		(width 0.127)
		(layer "In7.Cu")
		(net "FPGA_OUT_BNO080_BOOT_N")
	)
	(segment
		(start 105.918 -56.263794)
		(end 105.918 -52.959)
		(width 0.127)
		(layer "In7.Cu")
		(net "FPGA_OUT_BNO080_BOOT_N")
	)
	(segment
		(start 91.52382 -67.818)
		(end 91.96832 -67.3735)
		(width 0.127)
		(layer "In7.Cu")
		(net "FPGA_OUT_BNO080_BOOT_N")
	)
	(segment
		(start 91.96832 -67.3735)
		(end 94.089982 -67.3735)
		(width 0.127)
		(layer "In7.Cu")
		(net "FPGA_OUT_BNO080_BOOT_N")
	)
	(segment
		(start 90.04808 -67.818)
		(end 91.52382 -67.818)
		(width 0.127)
		(layer "In7.Cu")
		(net "FPGA_OUT_BNO080_BOOT_N")
	)
	(segment
		(start 107.902248 -48.768)
		(end 108.347256 -48.322992)
		(width 0.127)
		(layer "In7.Cu")
		(net "FPGA_OUT_BNO080_BOOT_N")
	)
	(segment
		(start 94.089982 -67.3735)
		(end 94.407482 -67.691)
		(width 0.127)
		(layer "In7.Cu")
		(net "FPGA_OUT_BNO080_BOOT_N")
	)
	(segment
		(start 107.188 -50.8)
		(end 107.521248 -50.8)
		(width 0.127)
		(layer "In7.Cu")
		(net "FPGA_OUT_BNO080_BOOT_N")
	)
	(segment
		(start 103.886 -58.295794)
		(end 105.918 -56.263794)
		(width 0.127)
		(layer "In7.Cu")
		(net "FPGA_OUT_BNO080_BOOT_N")
	)
	(segment
		(start 103.0605 -63.66256)
		(end 103.0605 -61.341)
		(width 0.127)
		(layer "In7.Cu")
		(net "FPGA_OUT_BNO080_BOOT_N")
	)
	(segment
		(start 89.73058 -68.1355)
		(end 90.04808 -67.818)
		(width 0.127)
		(layer "In7.Cu")
		(net "FPGA_OUT_BNO080_BOOT_N")
	)
	(segment
		(start 106.8705 -51.1175)
		(end 107.188 -50.8)
		(width 0.127)
		(layer "In7.Cu")
		(net "FPGA_OUT_BNO080_BOOT_N")
	)
	(segment
		(start 106.847132 -51.823112)
		(end 106.34726 -52.322984)
		(width 0.11938)
		(layer "F.Cu")
		(net "FPGA_IN_SHT3X_ALERT_N")
	)
	(segment
		(start 152.883108 -46.887892)
		(end 152.883108 -48.47971)
		(width 0.11938)
		(layer "F.Cu")
		(net "FPGA_IN_SHT3X_ALERT_N")
	)
	(segment
		(start 153.035 -46.482)
		(end 153.035 -46.736)
		(width 0.11938)
		(layer "F.Cu")
		(net "FPGA_IN_SHT3X_ALERT_N")
	)
	(segment
		(start 153.035 -46.736)
		(end 152.883108 -46.887892)
		(width 0.11938)
		(layer "F.Cu")
		(net "FPGA_IN_SHT3X_ALERT_N")
	)
	(via
		(at 153.035 -46.482)
		(size 0.508)
		(drill 0.254)
		(layers "F.Cu" "B.Cu")
		(net "FPGA_IN_SHT3X_ALERT_N")
	)
	(via
		(at 130.937 -51.054)
		(size 0.508)
		(drill 0.254)
		(layers "F.Cu" "B.Cu")
		(net "FPGA_IN_SHT3X_ALERT_N")
	)
	(via
		(at 106.34726 -52.322984)
		(size 0.4572)
		(drill 0.2032)
		(layers "F.Cu" "B.Cu")
		(net "FPGA_IN_SHT3X_ALERT_N")
	)
	(segment
		(start 117.729 -64.262)
		(end 117.983 -64.008)
		(width 0.11938)
		(layer "B.Cu")
		(net "FPGA_IN_SHT3X_ALERT_N")
	)
	(segment
		(start 109.093 -56.017414)
		(end 109.797596 -56.72201)
		(width 0.11938)
		(layer "B.Cu")
		(net "FPGA_IN_SHT3X_ALERT_N")
	)
	(segment
		(start 117.983 -58.674)
		(end 118.999 -57.658)
		(width 0.11938)
		(layer "B.Cu")
		(net "FPGA_IN_SHT3X_ALERT_N")
	)
	(segment
		(start 126.111 -55.626)
		(end 128.905 -52.832)
		(width 0.11938)
		(layer "B.Cu")
		(net "FPGA_IN_SHT3X_ALERT_N")
	)
	(segment
		(start 128.905 -52.043076)
		(end 129.894076 -51.054)
		(width 0.11938)
		(layer "B.Cu")
		(net "FPGA_IN_SHT3X_ALERT_N")
	)
	(segment
		(start 109.797596 -63.950596)
		(end 110.109 -64.262)
		(width 0.11938)
		(layer "B.Cu")
		(net "FPGA_IN_SHT3X_ALERT_N")
	)
	(segment
		(start 118.999 -57.658)
		(end 121.619264 -57.658)
		(width 0.11938)
		(layer "B.Cu")
		(net "FPGA_IN_SHT3X_ALERT_N")
	)
	(segment
		(start 123.651264 -55.626)
		(end 126.111 -55.626)
		(width 0.11938)
		(layer "B.Cu")
		(net "FPGA_IN_SHT3X_ALERT_N")
	)
	(segment
		(start 153.035 -46.736)
		(end 152.883108 -46.887892)
		(width 0.11938)
		(layer "B.Cu")
		(net "FPGA_IN_SHT3X_ALERT_N")
	)
	(segment
		(start 152.883108 -46.887892)
		(end 152.883108 -48.47971)
		(width 0.11938)
		(layer "B.Cu")
		(net "FPGA_IN_SHT3X_ALERT_N")
	)
	(segment
		(start 106.858816 -52.83454)
		(end 108.58754 -52.83454)
		(width 0.11938)
		(layer "B.Cu")
		(net "FPGA_IN_SHT3X_ALERT_N")
	)
	(segment
		(start 128.905 -52.832)
		(end 128.905 -52.043076)
		(width 0.11938)
		(layer "B.Cu")
		(net "FPGA_IN_SHT3X_ALERT_N")
	)
	(segment
		(start 106.34726 -52.322984)
		(end 106.858816 -52.83454)
		(width 0.11938)
		(layer "B.Cu")
		(net "FPGA_IN_SHT3X_ALERT_N")
	)
	(segment
		(start 121.619264 -57.658)
		(end 123.651264 -55.626)
		(width 0.11938)
		(layer "B.Cu")
		(net "FPGA_IN_SHT3X_ALERT_N")
	)
	(segment
		(start 108.58754 -52.83454)
		(end 109.093 -53.34)
		(width 0.11938)
		(layer "B.Cu")
		(net "FPGA_IN_SHT3X_ALERT_N")
	)
	(segment
		(start 109.797596 -56.72201)
		(end 109.797596 -63.950596)
		(width 0.11938)
		(layer "B.Cu")
		(net "FPGA_IN_SHT3X_ALERT_N")
	)
	(segment
		(start 153.035 -46.482)
		(end 153.035 -46.736)
		(width 0.11938)
		(layer "B.Cu")
		(net "FPGA_IN_SHT3X_ALERT_N")
	)
	(segment
		(start 110.109 -64.262)
		(end 117.729 -64.262)
		(width 0.11938)
		(layer "B.Cu")
		(net "FPGA_IN_SHT3X_ALERT_N")
	)
	(segment
		(start 109.093 -53.34)
		(end 109.093 -56.017414)
		(width 0.11938)
		(layer "B.Cu")
		(net "FPGA_IN_SHT3X_ALERT_N")
	)
	(segment
		(start 129.894076 -51.054)
		(end 130.937 -51.054)
		(width 0.11938)
		(layer "B.Cu")
		(net "FPGA_IN_SHT3X_ALERT_N")
	)
	(segment
		(start 117.983 -64.008)
		(end 117.983 -58.674)
		(width 0.11938)
		(layer "B.Cu")
		(net "FPGA_IN_SHT3X_ALERT_N")
	)
	(segment
		(start 139.827 -40.132)
		(end 147.701 -40.132)
		(width 0.127)
		(layer "In7.Cu")
		(net "FPGA_IN_SHT3X_ALERT_N")
	)
	(segment
		(start 149.225 -41.656)
		(end 149.225 -45.212)
		(width 0.127)
		(layer "In7.Cu")
		(net "FPGA_IN_SHT3X_ALERT_N")
	)
	(segment
		(start 150.241 -46.228)
		(end 152.781 -46.228)
		(width 0.127)
		(layer "In7.Cu")
		(net "FPGA_IN_SHT3X_ALERT_N")
	)
	(segment
		(start 130.937 -50.8)
		(end 131.191 -50.546)
		(width 0.127)
		(layer "In7.Cu")
		(net "FPGA_IN_SHT3X_ALERT_N")
	)
	(segment
		(start 152.781 -46.228)
		(end 153.035 -46.482)
		(width 0.127)
		(layer "In7.Cu")
		(net "FPGA_IN_SHT3X_ALERT_N")
	)
	(segment
		(start 137.033 -41.529)
		(end 138.43 -41.529)
		(width 0.127)
		(layer "In7.Cu")
		(net "FPGA_IN_SHT3X_ALERT_N")
	)
	(segment
		(start 147.701 -40.132)
		(end 149.225 -41.656)
		(width 0.127)
		(layer "In7.Cu")
		(net "FPGA_IN_SHT3X_ALERT_N")
	)
	(segment
		(start 131.191 -50.546)
		(end 131.191 -47.371)
		(width 0.127)
		(layer "In7.Cu")
		(net "FPGA_IN_SHT3X_ALERT_N")
	)
	(segment
		(start 138.43 -41.529)
		(end 139.827 -40.132)
		(width 0.127)
		(layer "In7.Cu")
		(net "FPGA_IN_SHT3X_ALERT_N")
	)
	(segment
		(start 131.191 -47.371)
		(end 137.033 -41.529)
		(width 0.127)
		(layer "In7.Cu")
		(net "FPGA_IN_SHT3X_ALERT_N")
	)
	(segment
		(start 130.937 -51.054)
		(end 130.937 -50.8)
		(width 0.127)
		(layer "In7.Cu")
		(net "FPGA_IN_SHT3X_ALERT_N")
	)
	(segment
		(start 149.225 -45.212)
		(end 150.241 -46.228)
		(width 0.127)
		(layer "In7.Cu")
		(net "FPGA_IN_SHT3X_ALERT_N")
	)
	(segment
		(start 109.847126 -47.82312)
		(end 110.346998 -48.322992)
		(width 0.11938)
		(layer "F.Cu")
		(net "FPGA_IN_MAC_USB_OC_N")
	)
	(via
		(at 64.8716 -73.6854)
		(size 0.508)
		(drill 0.254)
		(layers "F.Cu" "B.Cu")
		(net "FPGA_IN_MAC_USB_OC_N")
	)
	(via
		(at 110.346998 -48.322992)
		(size 0.4572)
		(drill 0.2032)
		(layers "F.Cu" "B.Cu")
		(net "FPGA_IN_MAC_USB_OC_N")
	)
	(segment
		(start 66.0146 -60.325)
		(end 64.7954 -60.325)
		(width 0.11938)
		(layer "B.Cu")
		(net "FPGA_IN_MAC_USB_OC_N")
	)
	(segment
		(start 64.7954 -62.6364)
		(end 64.7954 -60.325)
		(width 0.11938)
		(layer "B.Cu")
		(net "FPGA_IN_MAC_USB_OC_N")
	)
	(segment
		(start 64.008 -70.3326)
		(end 64.008 -63.4238)
		(width 0.11938)
		(layer "B.Cu")
		(net "FPGA_IN_MAC_USB_OC_N")
	)
	(segment
		(start 64.8716 -73.6854)
		(end 64.8716 -71.1962)
		(width 0.11938)
		(layer "B.Cu")
		(net "FPGA_IN_MAC_USB_OC_N")
	)
	(segment
		(start 64.008 -63.4238)
		(end 64.7954 -62.6364)
		(width 0.11938)
		(layer "B.Cu")
		(net "FPGA_IN_MAC_USB_OC_N")
	)
	(segment
		(start 64.8716 -71.1962)
		(end 64.008 -70.3326)
		(width 0.11938)
		(layer "B.Cu")
		(net "FPGA_IN_MAC_USB_OC_N")
	)
	(segment
		(start 107.7595 -56.3245)
		(end 107.7595 -54.2925)
		(width 0.127)
		(layer "In7.Cu")
		(net "FPGA_IN_MAC_USB_OC_N")
	)
	(segment
		(start 107.7595 -54.2925)
		(end 107.95 -54.102)
		(width 0.127)
		(layer "In7.Cu")
		(net "FPGA_IN_MAC_USB_OC_N")
	)
	(segment
		(start 88.8365 -69.6595)
		(end 89.916 -70.739)
		(width 0.127)
		(layer "In7.Cu")
		(net "FPGA_IN_MAC_USB_OC_N")
	)
	(segment
		(start 107.569 -56.515)
		(end 107.7595 -56.3245)
		(width 0.127)
		(layer "In7.Cu")
		(net "FPGA_IN_MAC_USB_OC_N")
	)
	(segment
		(start 89.916 -70.739)
		(end 91.923362 -70.739)
		(width 0.127)
		(layer "In7.Cu")
		(net "FPGA_IN_MAC_USB_OC_N")
	)
	(segment
		(start 108.145834 -59.250834)
		(end 107.569 -58.674)
		(width 0.127)
		(layer "In7.Cu")
		(net "FPGA_IN_MAC_USB_OC_N")
	)
	(segment
		(start 108.486956 -54.102)
		(end 108.994956 -53.594)
		(width 0.127)
		(layer "In7.Cu")
		(net "FPGA_IN_MAC_USB_OC_N")
	)
	(segment
		(start 93.750638 -70.739)
		(end 99.23018 -70.739)
		(width 0.127)
		(layer "In7.Cu")
		(net "FPGA_IN_MAC_USB_OC_N")
	)
	(segment
		(start 93.179138 -70.1675)
		(end 93.750638 -70.739)
		(width 0.127)
		(layer "In7.Cu")
		(net "FPGA_IN_MAC_USB_OC_N")
	)
	(segment
		(start 80.01 -68.453)
		(end 80.01 -68.072)
		(width 0.127)
		(layer "In7.Cu")
		(net "FPGA_IN_MAC_USB_OC_N")
	)
	(segment
		(start 106.41076 -64.59474)
		(end 106.41076 -61.92774)
		(width 0.127)
		(layer "In7.Cu")
		(net "FPGA_IN_MAC_USB_OC_N")
	)
	(segment
		(start 80.01 -68.072)
		(end 80.518 -67.564)
		(width 0.127)
		(layer "In7.Cu")
		(net "FPGA_IN_MAC_USB_OC_N")
	)
	(segment
		(start 107.569 -58.674)
		(end 107.569 -56.515)
		(width 0.127)
		(layer "In7.Cu")
		(net "FPGA_IN_MAC_USB_OC_N")
	)
	(segment
		(start 100.75418 -69.215)
		(end 101.7905 -69.215)
		(width 0.127)
		(layer "In7.Cu")
		(net "FPGA_IN_MAC_USB_OC_N")
	)
	(segment
		(start 67.945 -70.612)
		(end 77.851 -70.612)
		(width 0.127)
		(layer "In7.Cu")
		(net "FPGA_IN_MAC_USB_OC_N")
	)
	(segment
		(start 80.909414 -67.564)
		(end 83.004914 -69.6595)
		(width 0.127)
		(layer "In7.Cu")
		(net "FPGA_IN_MAC_USB_OC_N")
	)
	(segment
		(start 91.923362 -70.739)
		(end 92.494862 -70.1675)
		(width 0.127)
		(layer "In7.Cu")
		(net "FPGA_IN_MAC_USB_OC_N")
	)
	(segment
		(start 101.7905 -69.215)
		(end 106.41076 -64.59474)
		(width 0.127)
		(layer "In7.Cu")
		(net "FPGA_IN_MAC_USB_OC_N")
	)
	(segment
		(start 64.8716 -73.6854)
		(end 67.945 -70.612)
		(width 0.127)
		(layer "In7.Cu")
		(net "FPGA_IN_MAC_USB_OC_N")
	)
	(segment
		(start 99.23018 -70.739)
		(end 100.75418 -69.215)
		(width 0.127)
		(layer "In7.Cu")
		(net "FPGA_IN_MAC_USB_OC_N")
	)
	(segment
		(start 108.994956 -49.675034)
		(end 110.346998 -48.322992)
		(width 0.127)
		(layer "In7.Cu")
		(net "FPGA_IN_MAC_USB_OC_N")
	)
	(segment
		(start 77.851 -70.612)
		(end 80.01 -68.453)
		(width 0.127)
		(layer "In7.Cu")
		(net "FPGA_IN_MAC_USB_OC_N")
	)
	(segment
		(start 108.994956 -53.594)
		(end 108.994956 -49.675034)
		(width 0.127)
		(layer "In7.Cu")
		(net "FPGA_IN_MAC_USB_OC_N")
	)
	(segment
		(start 80.518 -67.564)
		(end 80.909414 -67.564)
		(width 0.127)
		(layer "In7.Cu")
		(net "FPGA_IN_MAC_USB_OC_N")
	)
	(segment
		(start 92.494862 -70.1675)
		(end 93.179138 -70.1675)
		(width 0.127)
		(layer "In7.Cu")
		(net "FPGA_IN_MAC_USB_OC_N")
	)
	(segment
		(start 83.004914 -69.6595)
		(end 88.8365 -69.6595)
		(width 0.127)
		(layer "In7.Cu")
		(net "FPGA_IN_MAC_USB_OC_N")
	)
	(segment
		(start 108.145834 -60.192666)
		(end 108.145834 -59.250834)
		(width 0.127)
		(layer "In7.Cu")
		(net "FPGA_IN_MAC_USB_OC_N")
	)
	(segment
		(start 107.95 -54.102)
		(end 108.486956 -54.102)
		(width 0.127)
		(layer "In7.Cu")
		(net "FPGA_IN_MAC_USB_OC_N")
	)
	(segment
		(start 106.41076 -61.92774)
		(end 108.145834 -60.192666)
		(width 0.127)
		(layer "In7.Cu")
		(net "FPGA_IN_MAC_USB_OC_N")
	)
	(segment
		(start 124.0536 -42.545)
		(end 124.0536 -41.402)
		(width 0.11938)
		(layer "F.Cu")
		(net "FPGA_IN_MAC_BITEOUT")
	)
	(segment
		(start 119.26824 -41.402)
		(end 120.65 -41.402)
		(width 0.11938)
		(layer "F.Cu")
		(net "FPGA_IN_MAC_BITEOUT")
	)
	(segment
		(start 118.847108 -41.823132)
		(end 119.26824 -41.402)
		(width 0.11938)
		(layer "F.Cu")
		(net "FPGA_IN_MAC_BITEOUT")
	)
	(segment
		(start 120.65 -41.402)
		(end 124.0536 -41.402)
		(width 0.11938)
		(layer "F.Cu")
		(net "FPGA_IN_MAC_BITEOUT")
	)
	(via
		(at 120.65 -41.402)
		(size 0.4572)
		(drill 0.2032)
		(layers "F.Cu" "B.Cu")
		(net "FPGA_IN_MAC_BITEOUT")
	)
	(segment
		(start 81.28 -43.053)
		(end 80.4164 -43.053)
		(width 0.11938)
		(layer "F.Cu")
		(net "FPGA_IN_MAC_ALARM_OUT_N")
	)
	(segment
		(start 80.4164 -43.053)
		(end 80.4164 -41.783)
		(width 0.11938)
		(layer "F.Cu")
		(net "FPGA_IN_MAC_ALARM_OUT_N")
	)
	(segment
		(start 81.407 -43.18)
		(end 81.28 -43.053)
		(width 0.11938)
		(layer "F.Cu")
		(net "FPGA_IN_MAC_ALARM_OUT_N")
	)
	(segment
		(start 120.80113 -42.82313)
		(end 119.847106 -42.82313)
		(width 0.11938)
		(layer "F.Cu")
		(net "FPGA_IN_MAC_ALARM_OUT_N")
	)
	(segment
		(start 121.285 -43.307)
		(end 120.80113 -42.82313)
		(width 0.11938)
		(layer "F.Cu")
		(net "FPGA_IN_MAC_ALARM_OUT_N")
	)
	(via
		(at 121.285 -43.307)
		(size 0.508)
		(drill 0.254)
		(layers "F.Cu" "B.Cu")
		(net "FPGA_IN_MAC_ALARM_OUT_N")
	)
	(via
		(at 81.407 -43.18)
		(size 0.508)
		(drill 0.254)
		(layers "F.Cu" "B.Cu")
		(net "FPGA_IN_MAC_ALARM_OUT_N")
	)
	(segment
		(start 96.596454 -43.2562)
		(end 94.0562 -43.2562)
		(width 0.127)
		(layer "In7.Cu")
		(net "FPGA_IN_MAC_ALARM_OUT_N")
	)
	(segment
		(start 81.8388 -43.6118)
		(end 81.407 -43.18)
		(width 0.127)
		(layer "In7.Cu")
		(net "FPGA_IN_MAC_ALARM_OUT_N")
	)
	(segment
		(start 93.599 -43.7134)
		(end 88.7476 -43.7134)
		(width 0.127)
		(layer "In7.Cu")
		(net "FPGA_IN_MAC_ALARM_OUT_N")
	)
	(segment
		(start 121.285 -43.307)
		(end 120.777 -42.799)
		(width 0.127)
		(layer "In7.Cu")
		(net "FPGA_IN_MAC_ALARM_OUT_N")
	)
	(segment
		(start 97.053654 -42.799)
		(end 96.596454 -43.2562)
		(width 0.127)
		(layer "In7.Cu")
		(net "FPGA_IN_MAC_ALARM_OUT_N")
	)
	(segment
		(start 94.0562 -43.2562)
		(end 93.599 -43.7134)
		(width 0.127)
		(layer "In7.Cu")
		(net "FPGA_IN_MAC_ALARM_OUT_N")
	)
	(segment
		(start 120.777 -42.799)
		(end 97.053654 -42.799)
		(width 0.127)
		(layer "In7.Cu")
		(net "FPGA_IN_MAC_ALARM_OUT_N")
	)
	(segment
		(start 88.646 -43.6118)
		(end 81.8388 -43.6118)
		(width 0.127)
		(layer "In7.Cu")
		(net "FPGA_IN_MAC_ALARM_OUT_N")
	)
	(segment
		(start 88.7476 -43.7134)
		(end 88.646 -43.6118)
		(width 0.127)
		(layer "In7.Cu")
		(net "FPGA_IN_MAC_ALARM_OUT_N")
	)
	(segment
		(start 115.847114 -45.823124)
		(end 116.346986 -46.322996)
		(width 0.11938)
		(layer "F.Cu")
		(net "FPGA_IN_MAC_10MHZ_OUT")
	)
	(via
		(at 122.936 -47.117)
		(size 0.508)
		(drill 0.254)
		(layers "F.Cu" "B.Cu")
		(net "FPGA_IN_MAC_10MHZ_OUT")
	)
	(via
		(at 116.346986 -46.322996)
		(size 0.4572)
		(drill 0.2032)
		(layers "F.Cu" "B.Cu")
		(net "FPGA_IN_MAC_10MHZ_OUT")
	)
	(segment
		(start 122.936 -47.117)
		(end 124.0536 -47.117)
		(width 0.11938)
		(layer "B.Cu")
		(net "FPGA_IN_MAC_10MHZ_OUT")
	)
	(segment
		(start 115.84686 -46.823122)
		(end 116.346986 -46.322996)
		(width 0.11938)
		(layer "B.Cu")
		(net "FPGA_IN_MAC_10MHZ_OUT")
	)
	(segment
		(start 116.633244 -46.322996)
		(end 117.10924 -45.847)
		(width 0.127)
		(layer "In7.Cu")
		(net "FPGA_IN_MAC_10MHZ_OUT")
	)
	(segment
		(start 121.479564 -46.803564)
		(end 122.495564 -46.803564)
		(width 0.127)
		(layer "In7.Cu")
		(net "FPGA_IN_MAC_10MHZ_OUT")
	)
	(segment
		(start 122.809 -47.117)
		(end 122.936 -47.117)
		(width 0.127)
		(layer "In7.Cu")
		(net "FPGA_IN_MAC_10MHZ_OUT")
	)
	(segment
		(start 122.495564 -46.803564)
		(end 122.809 -47.117)
		(width 0.127)
		(layer "In7.Cu")
		(net "FPGA_IN_MAC_10MHZ_OUT")
	)
	(segment
		(start 117.10924 -45.847)
		(end 120.523 -45.847)
		(width 0.127)
		(layer "In7.Cu")
		(net "FPGA_IN_MAC_10MHZ_OUT")
	)
	(segment
		(start 120.523 -45.847)
		(end 121.479564 -46.803564)
		(width 0.127)
		(layer "In7.Cu")
		(net "FPGA_IN_MAC_10MHZ_OUT")
	)
	(segment
		(start 116.346986 -46.322996)
		(end 116.633244 -46.322996)
		(width 0.127)
		(layer "In7.Cu")
		(net "FPGA_IN_MAC_10MHZ_OUT")
	)
	(segment
		(start 117.84711 -46.823122)
		(end 118.346982 -47.322994)
		(width 0.11938)
		(layer "F.Cu")
		(net "FPGA_IN_GPSTP2_OUT")
	)
	(via
		(at 122.301 -49.022)
		(size 0.508)
		(drill 0.254)
		(layers "F.Cu" "B.Cu")
		(net "FPGA_IN_GPSTP2_OUT")
	)
	(via
		(at 124.079 -87.884)
		(size 0.508)
		(drill 0.254)
		(layers "F.Cu" "B.Cu")
		(net "FPGA_IN_GPSTP2_OUT")
	)
	(via
		(at 118.346982 -47.322994)
		(size 0.4572)
		(drill 0.2032)
		(layers "F.Cu" "B.Cu")
		(net "FPGA_IN_GPSTP2_OUT")
	)
	(segment
		(start 118.847108 -47.823374)
		(end 120.721374 -47.823374)
		(width 0.11938)
		(layer "B.Cu")
		(net "FPGA_IN_GPSTP2_OUT")
	)
	(segment
		(start 120.890284 -47.992284)
		(end 121.271284 -47.992284)
		(width 0.11938)
		(layer "B.Cu")
		(net "FPGA_IN_GPSTP2_OUT")
	)
	(segment
		(start 118.847108 -47.823374)
		(end 118.847108 -47.82312)
		(width 0.11938)
		(layer "B.Cu")
		(net "FPGA_IN_GPSTP2_OUT")
	)
	(segment
		(start 118.847108 -47.82312)
		(end 118.346982 -47.322994)
		(width 0.11938)
		(layer "B.Cu")
		(net "FPGA_IN_GPSTP2_OUT")
	)
	(segment
		(start 121.271284 -47.992284)
		(end 122.301 -49.022)
		(width 0.11938)
		(layer "B.Cu")
		(net "FPGA_IN_GPSTP2_OUT")
	)
	(segment
		(start 124.079 -89.0016)
		(end 124.079 -87.884)
		(width 0.11938)
		(layer "B.Cu")
		(net "FPGA_IN_GPSTP2_OUT")
	)
	(segment
		(start 120.721374 -47.823374)
		(end 120.890284 -47.992284)
		(width 0.11938)
		(layer "B.Cu")
		(net "FPGA_IN_GPSTP2_OUT")
	)
	(segment
		(start 124.1425 -54.685692)
		(end 123.698 -55.130192)
		(width 0.127)
		(layer "In7.Cu")
		(net "FPGA_IN_GPSTP2_OUT")
	)
	(segment
		(start 123.825 -50.419)
		(end 123.825 -52.946808)
		(width 0.127)
		(layer "In7.Cu")
		(net "FPGA_IN_GPSTP2_OUT")
	)
	(segment
		(start 122.428 -49.022)
		(end 123.825 -50.419)
		(width 0.127)
		(layer "In7.Cu")
		(net "FPGA_IN_GPSTP2_OUT")
	)
	(segment
		(start 129.9972 -83.824318)
		(end 127.969518 -85.852)
		(width 0.127)
		(layer "In7.Cu")
		(net "FPGA_IN_GPSTP2_OUT")
	)
	(segment
		(start 127.889 -71.755)
		(end 129.8448 -73.7108)
		(width 0.127)
		(layer "In7.Cu")
		(net "FPGA_IN_GPSTP2_OUT")
	)
	(segment
		(start 127.269494 -60.5663)
		(end 127.795782 -60.5663)
		(width 0.127)
		(layer "In7.Cu")
		(net "FPGA_IN_GPSTP2_OUT")
	)
	(segment
		(start 128.1303 -61.374782)
		(end 127.889 -61.616082)
		(width 0.127)
		(layer "In7.Cu")
		(net "FPGA_IN_GPSTP2_OUT")
	)
	(segment
		(start 129.8448 -73.713594)
		(end 129.9972 -73.865994)
		(width 0.127)
		(layer "In7.Cu")
		(net "FPGA_IN_GPSTP2_OUT")
	)
	(segment
		(start 128.1303 -60.900818)
		(end 128.1303 -61.374782)
		(width 0.127)
		(layer "In7.Cu")
		(net "FPGA_IN_GPSTP2_OUT")
	)
	(segment
		(start 122.301 -49.022)
		(end 122.428 -49.022)
		(width 0.127)
		(layer "In7.Cu")
		(net "FPGA_IN_GPSTP2_OUT")
	)
	(segment
		(start 127.795782 -60.5663)
		(end 128.1303 -60.900818)
		(width 0.127)
		(layer "In7.Cu")
		(net "FPGA_IN_GPSTP2_OUT")
	)
	(segment
		(start 126.111 -85.852)
		(end 124.079 -87.884)
		(width 0.127)
		(layer "In7.Cu")
		(net "FPGA_IN_GPSTP2_OUT")
	)
	(segment
		(start 123.698 -55.130192)
		(end 123.698 -56.994806)
		(width 0.127)
		(layer "In7.Cu")
		(net "FPGA_IN_GPSTP2_OUT")
	)
	(segment
		(start 127.969518 -85.852)
		(end 126.111 -85.852)
		(width 0.127)
		(layer "In7.Cu")
		(net "FPGA_IN_GPSTP2_OUT")
	)
	(segment
		(start 123.698 -56.994806)
		(end 127.269494 -60.5663)
		(width 0.127)
		(layer "In7.Cu")
		(net "FPGA_IN_GPSTP2_OUT")
	)
	(segment
		(start 123.825 -52.946808)
		(end 124.1425 -53.264308)
		(width 0.127)
		(layer "In7.Cu")
		(net "FPGA_IN_GPSTP2_OUT")
	)
	(segment
		(start 129.8448 -73.7108)
		(end 129.8448 -73.713594)
		(width 0.127)
		(layer "In7.Cu")
		(net "FPGA_IN_GPSTP2_OUT")
	)
	(segment
		(start 127.889 -61.616082)
		(end 127.889 -71.755)
		(width 0.127)
		(layer "In7.Cu")
		(net "FPGA_IN_GPSTP2_OUT")
	)
	(segment
		(start 124.1425 -53.264308)
		(end 124.1425 -54.685692)
		(width 0.127)
		(layer "In7.Cu")
		(net "FPGA_IN_GPSTP2_OUT")
	)
	(segment
		(start 129.9972 -73.865994)
		(end 129.9972 -83.824318)
		(width 0.127)
		(layer "In7.Cu")
		(net "FPGA_IN_GPSTP2_OUT")
	)
	(segment
		(start 122.809 -89.0016)
		(end 122.809 -87.884254)
		(width 0.11938)
		(layer "F.Cu")
		(net "FPGA_IN_GPSTP1_OUT")
	)
	(segment
		(start 116.847112 -46.823122)
		(end 117.346984 -47.322994)
		(width 0.11938)
		(layer "F.Cu")
		(net "FPGA_IN_GPSTP1_OUT")
	)
	(segment
		(start 122.809 -87.884254)
		(end 122.809254 -87.884)
		(width 0.11938)
		(layer "F.Cu")
		(net "FPGA_IN_GPSTP1_OUT")
	)
	(via
		(at 122.809254 -87.884)
		(size 0.508)
		(drill 0.254)
		(layers "F.Cu" "B.Cu")
		(net "FPGA_IN_GPSTP1_OUT")
	)
	(via
		(at 117.346984 -47.322994)
		(size 0.4572)
		(drill 0.2032)
		(layers "F.Cu" "B.Cu")
		(net "FPGA_IN_GPSTP1_OUT")
	)
	(segment
		(start 116.847366 -47.82312)
		(end 116.847366 -47.822612)
		(width 0.11938)
		(layer "B.Cu")
		(net "FPGA_IN_GPSTP1_OUT")
	)
	(segment
		(start 116.847366 -47.822612)
		(end 117.346984 -47.322994)
		(width 0.11938)
		(layer "B.Cu")
		(net "FPGA_IN_GPSTP1_OUT")
	)
	(segment
		(start 117.346984 -47.322994)
		(end 117.346984 -47.57293)
		(width 0.127)
		(layer "In7.Cu")
		(net "FPGA_IN_GPSTP1_OUT")
	)
	(segment
		(start 118.11 -48.895)
		(end 120.823228 -48.895)
		(width 0.127)
		(layer "In7.Cu")
		(net "FPGA_IN_GPSTP1_OUT")
	)
	(segment
		(start 123.6345 -54.475126)
		(end 123.19 -54.919626)
		(width 0.127)
		(layer "In7.Cu")
		(net "FPGA_IN_GPSTP1_OUT")
	)
	(segment
		(start 117.856 -48.641)
		(end 118.11 -48.895)
		(width 0.127)
		(layer "In7.Cu")
		(net "FPGA_IN_GPSTP1_OUT")
	)
	(segment
		(start 117.856 -48.081946)
		(end 117.856 -48.641)
		(width 0.127)
		(layer "In7.Cu")
		(net "FPGA_IN_GPSTP1_OUT")
	)
	(segment
		(start 123.19 -57.205372)
		(end 126.8603 -60.875672)
		(width 0.127)
		(layer "In7.Cu")
		(net "FPGA_IN_GPSTP1_OUT")
	)
	(segment
		(start 122.6185 -51.3715)
		(end 122.6185 -52.458874)
		(width 0.127)
		(layer "In7.Cu")
		(net "FPGA_IN_GPSTP1_OUT")
	)
	(segment
		(start 129.4892 -83.613752)
		(end 127.885952 -85.217)
		(width 0.127)
		(layer "In7.Cu")
		(net "FPGA_IN_GPSTP1_OUT")
	)
	(segment
		(start 117.346984 -47.57293)
		(end 117.856 -48.081946)
		(width 0.127)
		(layer "In7.Cu")
		(net "FPGA_IN_GPSTP1_OUT")
	)
	(segment
		(start 126.4539 -71.04126)
		(end 129.4892 -74.07656)
		(width 0.127)
		(layer "In7.Cu")
		(net "FPGA_IN_GPSTP1_OUT")
	)
	(segment
		(start 120.823228 -48.895)
		(end 122.047 -50.118772)
		(width 0.127)
		(layer "In7.Cu")
		(net "FPGA_IN_GPSTP1_OUT")
	)
	(segment
		(start 127.885952 -85.217)
		(end 125.476254 -85.217)
		(width 0.127)
		(layer "In7.Cu")
		(net "FPGA_IN_GPSTP1_OUT")
	)
	(segment
		(start 126.8603 -64.2747)
		(end 126.4539 -64.6811)
		(width 0.127)
		(layer "In7.Cu")
		(net "FPGA_IN_GPSTP1_OUT")
	)
	(segment
		(start 122.6185 -52.458874)
		(end 123.6345 -53.474874)
		(width 0.127)
		(layer "In7.Cu")
		(net "FPGA_IN_GPSTP1_OUT")
	)
	(segment
		(start 123.6345 -53.474874)
		(end 123.6345 -54.475126)
		(width 0.127)
		(layer "In7.Cu")
		(net "FPGA_IN_GPSTP1_OUT")
	)
	(segment
		(start 126.8603 -60.875672)
		(end 126.8603 -64.2747)
		(width 0.127)
		(layer "In7.Cu")
		(net "FPGA_IN_GPSTP1_OUT")
	)
	(segment
		(start 122.047 -50.118772)
		(end 122.047 -50.8)
		(width 0.127)
		(layer "In7.Cu")
		(net "FPGA_IN_GPSTP1_OUT")
	)
	(segment
		(start 125.476254 -85.217)
		(end 122.809254 -87.884)
		(width 0.127)
		(layer "In7.Cu")
		(net "FPGA_IN_GPSTP1_OUT")
	)
	(segment
		(start 122.047 -50.8)
		(end 122.6185 -51.3715)
		(width 0.127)
		(layer "In7.Cu")
		(net "FPGA_IN_GPSTP1_OUT")
	)
	(segment
		(start 129.4892 -74.07656)
		(end 129.4892 -83.613752)
		(width 0.127)
		(layer "In7.Cu")
		(net "FPGA_IN_GPSTP1_OUT")
	)
	(segment
		(start 126.4539 -64.6811)
		(end 126.4539 -71.04126)
		(width 0.127)
		(layer "In7.Cu")
		(net "FPGA_IN_GPSTP1_OUT")
	)
	(segment
		(start 123.19 -54.919626)
		(end 123.19 -57.205372)
		(width 0.127)
		(layer "In7.Cu")
		(net "FPGA_IN_GPSTP1_OUT")
	)
	(segment
		(start 80.2386 -57.2516)
		(end 79.375 -57.2516)
		(width 0.11938)
		(layer "F.Cu")
		(net "FPGA_IN_BNO080_INT_N")
	)
	(segment
		(start 108.847128 -46.823122)
		(end 108.347256 -47.322994)
		(width 0.11938)
		(layer "F.Cu")
		(net "FPGA_IN_BNO080_INT_N")
	)
	(segment
		(start 80.2386 -56.1086)
		(end 80.2386 -57.2516)
		(width 0.11938)
		(layer "F.Cu")
		(net "FPGA_IN_BNO080_INT_N")
	)
	(via
		(at 79.375 -57.2516)
		(size 0.508)
		(drill 0.254)
		(layers "F.Cu" "B.Cu")
		(net "FPGA_IN_BNO080_INT_N")
	)
	(via
		(at 108.347256 -47.322994)
		(size 0.4572)
		(drill 0.2032)
		(layers "F.Cu" "B.Cu")
		(net "FPGA_IN_BNO080_INT_N")
	)
	(via
		(at 79.248 -68.326)
		(size 0.508)
		(drill 0.254)
		(layers "F.Cu" "B.Cu")
		(net "FPGA_IN_BNO080_INT_N")
	)
	(segment
		(start 79.375 -57.2516)
		(end 78.486 -58.1406)
		(width 0.127)
		(layer "In2.Cu")
		(net "FPGA_IN_BNO080_INT_N")
	)
	(segment
		(start 79.883 -66.675)
		(end 79.883 -67.691)
		(width 0.127)
		(layer "In2.Cu")
		(net "FPGA_IN_BNO080_INT_N")
	)
	(segment
		(start 79.883 -67.691)
		(end 79.248 -68.326)
		(width 0.127)
		(layer "In2.Cu")
		(net "FPGA_IN_BNO080_INT_N")
	)
	(segment
		(start 78.486 -58.1406)
		(end 78.486 -65.278)
		(width 0.127)
		(layer "In2.Cu")
		(net "FPGA_IN_BNO080_INT_N")
	)
	(segment
		(start 78.486 -65.278)
		(end 79.883 -66.675)
		(width 0.127)
		(layer "In2.Cu")
		(net "FPGA_IN_BNO080_INT_N")
	)
	(segment
		(start 90.764106 -69.83222)
		(end 90.083386 -69.1515)
		(width 0.127)
		(layer "In7.Cu")
		(net "FPGA_IN_BNO080_INT_N")
	)
	(segment
		(start 108.347256 -47.322994)
		(end 108.766356 -47.742094)
		(width 0.127)
		(layer "In7.Cu")
		(net "FPGA_IN_BNO080_INT_N")
	)
	(segment
		(start 108.547916 -50.76444)
		(end 108.23956 -50.76444)
		(width 0.127)
		(layer "In7.Cu")
		(net "FPGA_IN_BNO080_INT_N")
	)
	(segment
		(start 92.792296 -69.1515)
		(end 92.111576 -69.83222)
		(width 0.127)
		(layer "In7.Cu")
		(net "FPGA_IN_BNO080_INT_N")
	)
	(segment
		(start 106.045 -58.801)
		(end 106.426 -59.182)
		(width 0.127)
		(layer "In7.Cu")
		(net "FPGA_IN_BNO080_INT_N")
	)
	(segment
		(start 95.775018 -68.8975)
		(end 95.521018 -69.1515)
		(width 0.127)
		(layer "In7.Cu")
		(net "FPGA_IN_BNO080_INT_N")
	)
	(segment
		(start 81.198466 -67.1449)
		(end 81.008982 -66.955416)
		(width 0.127)
		(layer "In7.Cu")
		(net "FPGA_IN_BNO080_INT_N")
	)
	(segment
		(start 108.23956 -50.76444)
		(end 107.87126 -51.13274)
		(width 0.127)
		(layer "In7.Cu")
		(net "FPGA_IN_BNO080_INT_N")
	)
	(segment
		(start 83.21548 -69.1515)
		(end 81.20888 -67.1449)
		(width 0.127)
		(layer "In7.Cu")
		(net "FPGA_IN_BNO080_INT_N")
	)
	(segment
		(start 107.145582 -56.472582)
		(end 106.045 -57.573164)
		(width 0.127)
		(layer "In7.Cu")
		(net "FPGA_IN_BNO080_INT_N")
	)
	(segment
		(start 92.111576 -69.83222)
		(end 90.764106 -69.83222)
		(width 0.127)
		(layer "In7.Cu")
		(net "FPGA_IN_BNO080_INT_N")
	)
	(segment
		(start 100.099114 -69.1515)
		(end 96.502982 -69.1515)
		(width 0.127)
		(layer "In7.Cu")
		(net "FPGA_IN_BNO080_INT_N")
	)
	(segment
		(start 101.473 -68.707)
		(end 100.543614 -68.707)
		(width 0.127)
		(layer "In7.Cu")
		(net "FPGA_IN_BNO080_INT_N")
	)
	(segment
		(start 107.145582 -54.398418)
		(end 107.145582 -56.472582)
		(width 0.127)
		(layer "In7.Cu")
		(net "FPGA_IN_BNO080_INT_N")
	)
	(segment
		(start 106.426 -60.325)
		(end 105.8926 -60.8584)
		(width 0.127)
		(layer "In7.Cu")
		(net "FPGA_IN_BNO080_INT_N")
	)
	(segment
		(start 106.045 -57.573164)
		(end 106.045 -58.801)
		(width 0.127)
		(layer "In7.Cu")
		(net "FPGA_IN_BNO080_INT_N")
	)
	(segment
		(start 108.766356 -47.742094)
		(end 108.766356 -50.546)
		(width 0.127)
		(layer "In7.Cu")
		(net "FPGA_IN_BNO080_INT_N")
	)
	(segment
		(start 81.008982 -66.955416)
		(end 80.408018 -66.955416)
		(width 0.127)
		(layer "In7.Cu")
		(net "FPGA_IN_BNO080_INT_N")
	)
	(segment
		(start 108.766356 -50.546)
		(end 108.547916 -50.76444)
		(width 0.127)
		(layer "In7.Cu")
		(net "FPGA_IN_BNO080_INT_N")
	)
	(segment
		(start 80.408018 -66.955416)
		(end 79.248 -68.115434)
		(width 0.127)
		(layer "In7.Cu")
		(net "FPGA_IN_BNO080_INT_N")
	)
	(segment
		(start 107.87126 -51.13274)
		(end 107.87126 -53.67274)
		(width 0.127)
		(layer "In7.Cu")
		(net "FPGA_IN_BNO080_INT_N")
	)
	(segment
		(start 107.87126 -53.67274)
		(end 107.145582 -54.398418)
		(width 0.127)
		(layer "In7.Cu")
		(net "FPGA_IN_BNO080_INT_N")
	)
	(segment
		(start 79.248 -68.115434)
		(end 79.248 -68.326)
		(width 0.127)
		(layer "In7.Cu")
		(net "FPGA_IN_BNO080_INT_N")
	)
	(segment
		(start 96.502982 -69.1515)
		(end 96.248982 -68.8975)
		(width 0.127)
		(layer "In7.Cu")
		(net "FPGA_IN_BNO080_INT_N")
	)
	(segment
		(start 81.20888 -67.1449)
		(end 81.198466 -67.1449)
		(width 0.127)
		(layer "In7.Cu")
		(net "FPGA_IN_BNO080_INT_N")
	)
	(segment
		(start 105.8926 -64.2874)
		(end 101.473 -68.707)
		(width 0.127)
		(layer "In7.Cu")
		(net "FPGA_IN_BNO080_INT_N")
	)
	(segment
		(start 105.8926 -60.8584)
		(end 105.8926 -64.2874)
		(width 0.127)
		(layer "In7.Cu")
		(net "FPGA_IN_BNO080_INT_N")
	)
	(segment
		(start 95.521018 -69.1515)
		(end 92.792296 -69.1515)
		(width 0.127)
		(layer "In7.Cu")
		(net "FPGA_IN_BNO080_INT_N")
	)
	(segment
		(start 96.248982 -68.8975)
		(end 95.775018 -68.8975)
		(width 0.127)
		(layer "In7.Cu")
		(net "FPGA_IN_BNO080_INT_N")
	)
	(segment
		(start 106.426 -59.182)
		(end 106.426 -60.325)
		(width 0.127)
		(layer "In7.Cu")
		(net "FPGA_IN_BNO080_INT_N")
	)
	(segment
		(start 100.543614 -68.707)
		(end 100.099114 -69.1515)
		(width 0.127)
		(layer "In7.Cu")
		(net "FPGA_IN_BNO080_INT_N")
	)
	(segment
		(start 90.083386 -69.1515)
		(end 83.21548 -69.1515)
		(width 0.127)
		(layer "In7.Cu")
		(net "FPGA_IN_BNO080_INT_N")
	)
	(segment
		(start 35.1155 -94.5515)
		(end 35.1155 -96.7359)
		(width 0.11938)
		(layer "F.Cu")
		(net "FPGA_CFG_INIT_N")
	)
	(segment
		(start 133.202426 -74.655426)
		(end 133.604 -75.057)
		(width 0.11938)
		(layer "F.Cu")
		(net "FPGA_CFG_INIT_N")
	)
	(segment
		(start 115.9764 -76.073)
		(end 116.500148 -76.073)
		(width 0.11938)
		(layer "F.Cu")
		(net "FPGA_CFG_INIT_N")
	)
	(segment
		(start 117.917722 -74.655426)
		(end 133.202426 -74.655426)
		(width 0.11938)
		(layer "F.Cu")
		(net "FPGA_CFG_INIT_N")
	)
	(segment
		(start 116.500148 -76.073)
		(end 117.917722 -74.655426)
		(width 0.11938)
		(layer "F.Cu")
		(net "FPGA_CFG_INIT_N")
	)
	(segment
		(start 149.987 -76.581)
		(end 152.868376 -76.581)
		(width 0.11938)
		(layer "F.Cu")
		(net "FPGA_CFG_INIT_N")
	)
	(segment
		(start 35.1155 -96.7359)
		(end 36.195 -97.8154)
		(width 0.11938)
		(layer "F.Cu")
		(net "FPGA_CFG_INIT_N")
	)
	(segment
		(start 114.847116 -44.823126)
		(end 115.346988 -45.322998)
		(width 0.11938)
		(layer "F.Cu")
		(net "FPGA_CFG_INIT_N")
	)
	(segment
		(start 115.9764 -76.073)
		(end 115.9764 -77.5716)
		(width 0.11938)
		(layer "F.Cu")
		(net "FPGA_CFG_INIT_N")
	)
	(segment
		(start 115.9764 -77.5716)
		(end 115.951 -77.597)
		(width 0.11938)
		(layer "F.Cu")
		(net "FPGA_CFG_INIT_N")
	)
	(via
		(at 149.987 -76.581)
		(size 0.4572)
		(drill 0.2032)
		(layers "F.Cu" "B.Cu")
		(net "FPGA_CFG_INIT_N")
	)
	(via
		(at 123.198382 -44.433236)
		(size 0.508)
		(drill 0.254)
		(layers "F.Cu" "B.Cu")
		(net "FPGA_CFG_INIT_N")
	)
	(via
		(at 115.951 -77.597)
		(size 0.508)
		(drill 0.254)
		(layers "F.Cu" "B.Cu")
		(net "FPGA_CFG_INIT_N")
	)
	(via
		(at 35.1155 -94.5515)
		(size 0.4572)
		(drill 0.2032)
		(layers "F.Cu" "B.Cu")
		(net "FPGA_CFG_INIT_N")
	)
	(via
		(at 109.22 -96.774)
		(size 0.508)
		(drill 0.254)
		(layers "F.Cu" "B.Cu")
		(net "FPGA_CFG_INIT_N")
	)
	(via
		(at 133.604 -75.057)
		(size 0.508)
		(drill 0.254)
		(layers "F.Cu" "B.Cu")
		(net "FPGA_CFG_INIT_N")
	)
	(via
		(at 115.346988 -45.322998)
		(size 0.4572)
		(drill 0.2032)
		(layers "F.Cu" "B.Cu")
		(net "FPGA_CFG_INIT_N")
	)
	(segment
		(start 123.655836 -44.433236)
		(end 124.0536 -44.831)
		(width 0.11938)
		(layer "B.Cu")
		(net "FPGA_CFG_INIT_N")
	)
	(segment
		(start 112.141 -78.486)
		(end 113.665 -76.962)
		(width 0.11938)
		(layer "B.Cu")
		(net "FPGA_CFG_INIT_N")
	)
	(segment
		(start 137.414 -19.5072)
		(end 135.7884 -17.8816)
		(width 0.11938)
		(layer "B.Cu")
		(net "FPGA_CFG_INIT_N")
	)
	(segment
		(start 108.966 -86.96706)
		(end 108.966 -82.804)
		(width 0.11938)
		(layer "B.Cu")
		(net "FPGA_CFG_INIT_N")
	)
	(segment
		(start 108.712 -89.662)
		(end 109.728 -88.646)
		(width 0.11938)
		(layer "B.Cu")
		(net "FPGA_CFG_INIT_N")
	)
	(segment
		(start 108.966 -82.804)
		(end 112.141 -79.629)
		(width 0.11938)
		(layer "B.Cu")
		(net "FPGA_CFG_INIT_N")
	)
	(segment
		(start 123.198382 -44.433236)
		(end 123.655836 -44.433236)
		(width 0.11938)
		(layer "B.Cu")
		(net "FPGA_CFG_INIT_N")
	)
	(segment
		(start 108.712 -95.885)
		(end 108.712 -89.662)
		(width 0.11938)
		(layer "B.Cu")
		(net "FPGA_CFG_INIT_N")
	)
	(segment
		(start 136.144 -16.256)
		(end 137.2616 -16.256)
		(width 0.11938)
		(layer "B.Cu")
		(net "FPGA_CFG_INIT_N")
	)
	(segment
		(start 135.7884 -16.6116)
		(end 136.144 -16.256)
		(width 0.11938)
		(layer "B.Cu")
		(net "FPGA_CFG_INIT_N")
	)
	(segment
		(start 137.414 -24.384)
		(end 137.414 -19.5072)
		(width 0.11938)
		(layer "B.Cu")
		(net "FPGA_CFG_INIT_N")
	)
	(segment
		(start 135.7884 -17.8816)
		(end 135.7884 -16.6116)
		(width 0.11938)
		(layer "B.Cu")
		(net "FPGA_CFG_INIT_N")
	)
	(segment
		(start 109.22 -96.774)
		(end 109.22 -96.393)
		(width 0.11938)
		(layer "B.Cu")
		(net "FPGA_CFG_INIT_N")
	)
	(segment
		(start 115.316 -76.962)
		(end 115.951 -77.597)
		(width 0.11938)
		(layer "B.Cu")
		(net "FPGA_CFG_INIT_N")
	)
	(segment
		(start 109.728 -87.72906)
		(end 108.966 -86.96706)
		(width 0.11938)
		(layer "B.Cu")
		(net "FPGA_CFG_INIT_N")
	)
	(segment
		(start 109.728 -88.646)
		(end 109.728 -87.72906)
		(width 0.11938)
		(layer "B.Cu")
		(net "FPGA_CFG_INIT_N")
	)
	(segment
		(start 112.141 -79.629)
		(end 112.141 -78.486)
		(width 0.11938)
		(layer "B.Cu")
		(net "FPGA_CFG_INIT_N")
	)
	(segment
		(start 113.665 -76.962)
		(end 115.316 -76.962)
		(width 0.11938)
		(layer "B.Cu")
		(net "FPGA_CFG_INIT_N")
	)
	(segment
		(start 109.22 -96.393)
		(end 108.712 -95.885)
		(width 0.11938)
		(layer "B.Cu")
		(net "FPGA_CFG_INIT_N")
	)
	(segment
		(start 147.828 -74.8665)
		(end 144.0815 -78.613)
		(width 0.127)
		(layer "In2.Cu")
		(net "FPGA_CFG_INIT_N")
	)
	(segment
		(start 37.355018 -93.4085)
		(end 36.910518 -93.853)
		(width 0.127)
		(layer "In2.Cu")
		(net "FPGA_CFG_INIT_N")
	)
	(segment
		(start 149.20214 -75.125834)
		(end 148.942806 -74.8665)
		(width 0.127)
		(layer "In2.Cu")
		(net "FPGA_CFG_INIT_N")
	)
	(segment
		(start 152.273 -20.32)
		(end 149.0345 -23.5585)
		(width 0.127)
		(layer "In2.Cu")
		(net "FPGA_CFG_INIT_N")
	)
	(segment
		(start 158.369 -72.11568)
		(end 158.369 -64.769746)
		(width 0.127)
		(layer "In2.Cu")
		(net "FPGA_CFG_INIT_N")
	)
	(segment
		(start 134.874 -76.835)
		(end 134.874 -75.692)
		(width 0.127)
		(layer "In2.Cu")
		(net "FPGA_CFG_INIT_N")
	)
	(segment
		(start 159.766 -55.245254)
		(end 160.147 -54.864254)
		(width 0.127)
		(layer "In2.Cu")
		(net "FPGA_CFG_INIT_N")
	)
	(segment
		(start 158.75 -47.371)
		(end 164.084 -42.037)
		(width 0.127)
		(layer "In2.Cu")
		(net "FPGA_CFG_INIT_N")
	)
	(segment
		(start 159.639 -20.32)
		(end 152.273 -20.32)
		(width 0.127)
		(layer "In2.Cu")
		(net "FPGA_CFG_INIT_N")
	)
	(segment
		(start 93.599 -98.806)
		(end 93.599 -95.758)
		(width 0.127)
		(layer "In2.Cu")
		(net "FPGA_CFG_INIT_N")
	)
	(segment
		(start 164.084 -42.037)
		(end 164.084 -29.845)
		(width 0.127)
		(layer "In2.Cu")
		(net "FPGA_CFG_INIT_N")
	)
	(segment
		(start 136.652 -78.613)
		(end 134.874 -76.835)
		(width 0.127)
		(layer "In2.Cu")
		(net "FPGA_CFG_INIT_N")
	)
	(segment
		(start 158.75 -52.58943)
		(end 158.75 -47.371)
		(width 0.127)
		(layer "In2.Cu")
		(net "FPGA_CFG_INIT_N")
	)
	(segment
		(start 160.401 -62.737746)
		(end 160.401 -59.055254)
		(width 0.127)
		(layer "In2.Cu")
		(net "FPGA_CFG_INIT_N")
	)
	(segment
		(start 149.987 -76.581)
		(end 153.90368 -76.581)
		(width 0.127)
		(layer "In2.Cu")
		(net "FPGA_CFG_INIT_N")
	)
	(segment
		(start 108.966 -96.774)
		(end 107.061 -98.679)
		(width 0.127)
		(layer "In2.Cu")
		(net "FPGA_CFG_INIT_N")
	)
	(segment
		(start 138.0998 -24.2697)
		(end 137.9855 -24.384)
		(width 0.127)
		(layer "In2.Cu")
		(net "FPGA_CFG_INIT_N")
	)
	(segment
		(start 160.147 -53.98643)
		(end 158.75 -52.58943)
		(width 0.127)
		(layer "In2.Cu")
		(net "FPGA_CFG_INIT_N")
	)
	(segment
		(start 134.874 -75.692)
		(end 134.239 -75.057)
		(width 0.127)
		(layer "In2.Cu")
		(net "FPGA_CFG_INIT_N")
	)
	(segment
		(start 149.20214 -75.79614)
		(end 149.20214 -75.125834)
		(width 0.127)
		(layer "In2.Cu")
		(net "FPGA_CFG_INIT_N")
	)
	(segment
		(start 145.351754 -23.5585)
		(end 144.640554 -24.2697)
		(width 0.127)
		(layer "In2.Cu")
		(net "FPGA_CFG_INIT_N")
	)
	(segment
		(start 160.147 -54.864254)
		(end 160.147 -53.98643)
		(width 0.127)
		(layer "In2.Cu")
		(net "FPGA_CFG_INIT_N")
	)
	(segment
		(start 164.084 -29.845)
		(end 163.449 -29.21)
		(width 0.127)
		(layer "In2.Cu")
		(net "FPGA_CFG_INIT_N")
	)
	(segment
		(start 160.401 -59.055254)
		(end 159.766 -58.420254)
		(width 0.127)
		(layer "In2.Cu")
		(net "FPGA_CFG_INIT_N")
	)
	(segment
		(start 101.473 -100.457)
		(end 95.25 -100.457)
		(width 0.127)
		(layer "In2.Cu")
		(net "FPGA_CFG_INIT_N")
	)
	(segment
		(start 103.251 -98.679)
		(end 101.473 -100.457)
		(width 0.127)
		(layer "In2.Cu")
		(net "FPGA_CFG_INIT_N")
	)
	(segment
		(start 153.90368 -76.581)
		(end 158.369 -72.11568)
		(width 0.127)
		(layer "In2.Cu")
		(net "FPGA_CFG_INIT_N")
	)
	(segment
		(start 107.061 -98.679)
		(end 103.251 -98.679)
		(width 0.127)
		(layer "In2.Cu")
		(net "FPGA_CFG_INIT_N")
	)
	(segment
		(start 144.0815 -78.613)
		(end 136.652 -78.613)
		(width 0.127)
		(layer "In2.Cu")
		(net "FPGA_CFG_INIT_N")
	)
	(segment
		(start 158.369 -64.769746)
		(end 160.401 -62.737746)
		(width 0.127)
		(layer "In2.Cu")
		(net "FPGA_CFG_INIT_N")
	)
	(segment
		(start 47.581566 -94.615)
		(end 46.375066 -93.4085)
		(width 0.127)
		(layer "In2.Cu")
		(net "FPGA_CFG_INIT_N")
	)
	(segment
		(start 144.640554 -24.2697)
		(end 138.0998 -24.2697)
		(width 0.127)
		(layer "In2.Cu")
		(net "FPGA_CFG_INIT_N")
	)
	(segment
		(start 109.22 -96.774)
		(end 108.966 -96.774)
		(width 0.127)
		(layer "In2.Cu")
		(net "FPGA_CFG_INIT_N")
	)
	(segment
		(start 70.358 -94.615)
		(end 47.581566 -94.615)
		(width 0.127)
		(layer "In2.Cu")
		(net "FPGA_CFG_INIT_N")
	)
	(segment
		(start 35.814 -93.853)
		(end 35.1155 -94.5515)
		(width 0.127)
		(layer "In2.Cu")
		(net "FPGA_CFG_INIT_N")
	)
	(segment
		(start 163.449 -29.21)
		(end 163.449 -24.13)
		(width 0.127)
		(layer "In2.Cu")
		(net "FPGA_CFG_INIT_N")
	)
	(segment
		(start 88.9 -91.059)
		(end 73.914 -91.059)
		(width 0.127)
		(layer "In2.Cu")
		(net "FPGA_CFG_INIT_N")
	)
	(segment
		(start 163.449 -24.13)
		(end 159.639 -20.32)
		(width 0.127)
		(layer "In2.Cu")
		(net "FPGA_CFG_INIT_N")
	)
	(segment
		(start 149.0345 -23.5585)
		(end 145.351754 -23.5585)
		(width 0.127)
		(layer "In2.Cu")
		(net "FPGA_CFG_INIT_N")
	)
	(segment
		(start 159.766 -58.420254)
		(end 159.766 -55.245254)
		(width 0.127)
		(layer "In2.Cu")
		(net "FPGA_CFG_INIT_N")
	)
	(segment
		(start 93.599 -95.758)
		(end 88.9 -91.059)
		(width 0.127)
		(layer "In2.Cu")
		(net "FPGA_CFG_INIT_N")
	)
	(segment
		(start 134.239 -75.057)
		(end 133.604 -75.057)
		(width 0.127)
		(layer "In2.Cu")
		(net "FPGA_CFG_INIT_N")
	)
	(segment
		(start 46.375066 -93.4085)
		(end 37.355018 -93.4085)
		(width 0.127)
		(layer "In2.Cu")
		(net "FPGA_CFG_INIT_N")
	)
	(segment
		(start 73.914 -91.059)
		(end 70.358 -94.615)
		(width 0.127)
		(layer "In2.Cu")
		(net "FPGA_CFG_INIT_N")
	)
	(segment
		(start 149.987 -76.581)
		(end 149.20214 -75.79614)
		(width 0.127)
		(layer "In2.Cu")
		(net "FPGA_CFG_INIT_N")
	)
	(segment
		(start 95.25 -100.457)
		(end 93.599 -98.806)
		(width 0.127)
		(layer "In2.Cu")
		(net "FPGA_CFG_INIT_N")
	)
	(segment
		(start 148.942806 -74.8665)
		(end 147.828 -74.8665)
		(width 0.127)
		(layer "In2.Cu")
		(net "FPGA_CFG_INIT_N")
	)
	(segment
		(start 36.910518 -93.853)
		(end 35.814 -93.853)
		(width 0.127)
		(layer "In2.Cu")
		(net "FPGA_CFG_INIT_N")
	)
	(segment
		(start 137.9855 -24.384)
		(end 137.414 -24.384)
		(width 0.127)
		(layer "In2.Cu")
		(net "FPGA_CFG_INIT_N")
	)
	(segment
		(start 130.1115 -32.7025)
		(end 136.271 -26.543)
		(width 0.127)
		(layer "In7.Cu")
		(net "FPGA_CFG_INIT_N")
	)
	(segment
		(start 120.450356 -43.742356)
		(end 121.141236 -44.433236)
		(width 0.127)
		(layer "In7.Cu")
		(net "FPGA_CFG_INIT_N")
	)
	(segment
		(start 116.92763 -43.742356)
		(end 120.450356 -43.742356)
		(width 0.127)
		(layer "In7.Cu")
		(net "FPGA_CFG_INIT_N")
	)
	(segment
		(start 123.198382 -44.433236)
		(end 124.324618 -43.307)
		(width 0.127)
		(layer "In7.Cu")
		(net "FPGA_CFG_INIT_N")
	)
	(segment
		(start 121.141236 -44.433236)
		(end 123.198382 -44.433236)
		(width 0.127)
		(layer "In7.Cu")
		(net "FPGA_CFG_INIT_N")
	)
	(segment
		(start 136.271 -25.527)
		(end 137.414 -24.384)
		(width 0.127)
		(layer "In7.Cu")
		(net "FPGA_CFG_INIT_N")
	)
	(segment
		(start 115.346988 -45.322998)
		(end 116.92763 -43.742356)
		(width 0.127)
		(layer "In7.Cu")
		(net "FPGA_CFG_INIT_N")
	)
	(segment
		(start 136.271 -26.543)
		(end 136.271 -25.527)
		(width 0.127)
		(layer "In7.Cu")
		(net "FPGA_CFG_INIT_N")
	)
	(segment
		(start 130.1115 -40.152066)
		(end 130.1115 -32.7025)
		(width 0.127)
		(layer "In7.Cu")
		(net "FPGA_CFG_INIT_N")
	)
	(segment
		(start 126.956566 -43.307)
		(end 130.1115 -40.152066)
		(width 0.127)
		(layer "In7.Cu")
		(net "FPGA_CFG_INIT_N")
	)
	(segment
		(start 124.324618 -43.307)
		(end 126.956566 -43.307)
		(width 0.127)
		(layer "In7.Cu")
		(net "FPGA_CFG_INIT_N")
	)
	(segment
		(start 160.983676 -53.4543)
		(end 161.68624 -53.4543)
		(width 0.14478)
		(layer "F.Cu")
		(net "CONN_MICRO_USB_DP")
	)
	(segment
		(start 92.290646 -23.73757)
		(end 92.2909 -23.736808)
		(width 0.14478)
		(layer "F.Cu")
		(net "CONN_MICRO_USB_DP")
	)
	(segment
		(start 159.464502 -54.518814)
		(end 159.260286 -54.314598)
		(width 0.14478)
		(layer "F.Cu")
		(net "CONN_MICRO_USB_DP")
	)
	(segment
		(start 160.404556 -53.6067)
		(end 160.831276 -53.6067)
		(width 0.14478)
		(layer "F.Cu")
		(net "CONN_MICRO_USB_DP")
	)
	(segment
		(start 161.929318 -53.600096)
		(end 162.8267 -53.600096)
		(width 0.14478)
		(layer "F.Cu")
		(net "CONN_MICRO_USB_DP")
	)
	(segment
		(start 161.745422 -53.476144)
		(end 161.826956 -53.557678)
		(width 0.14478)
		(layer "F.Cu")
		(net "CONN_MICRO_USB_DP")
	)
	(segment
		(start 159.510222 -53.4543)
		(end 160.252156 -53.4543)
		(width 0.14478)
		(layer "F.Cu")
		(net "CONN_MICRO_USB_DP")
	)
	(segment
		(start 160.205166 -55.926736)
		(end 160.205166 -56.484266)
		(width 0.14478)
		(layer "F.Cu")
		(net "CONN_MICRO_USB_DP")
	)
	(segment
		(start 91.544394 -48.872394)
		(end 91.73464 -48.872394)
		(width 0.14478)
		(layer "F.Cu")
		(net "CONN_MICRO_USB_DP")
	)
	(segment
		(start 91.525344 -48.853344)
		(end 91.544394 -48.872394)
		(width 0.14478)
		(layer "F.Cu")
		(net "CONN_MICRO_USB_DP")
	)
	(segment
		(start 157.656022 -57.722262)
		(end 157.470094 -57.829196)
		(width 0.14478)
		(layer "F.Cu")
		(net "CONN_MICRO_USB_DP")
	)
	(segment
		(start 160.205166 -55.926736)
		(end 160.205166 -54.962806)
		(width 0.14478)
		(layer "F.Cu")
		(net "CONN_MICRO_USB_DP")
	)
	(segment
		(start 92.2909 -27.409648)
		(end 92.2909 -23.748746)
		(width 0.14478)
		(layer "F.Cu")
		(net "CONN_MICRO_USB_DP")
	)
	(segment
		(start 86.36 -50.479452)
		(end 86.36 -35.267138)
		(width 0.14478)
		(layer "F.Cu")
		(net "CONN_MICRO_USB_DP")
	)
	(segment
		(start 159.17418 -57.7088)
		(end 157.76067 -57.7088)
		(width 0.14478)
		(layer "F.Cu")
		(net "CONN_MICRO_USB_DP")
	)
	(segment
		(start 159.15894 -54.069996)
		(end 159.15894 -53.767482)
		(width 0.14478)
		(layer "F.Cu")
		(net "CONN_MICRO_USB_DP")
	)
	(segment
		(start 92.26042 -49.398174)
		(end 92.26042 -50.932334)
		(width 0.14478)
		(layer "F.Cu")
		(net "CONN_MICRO_USB_DP")
	)
	(segment
		(start 160.070292 -54.72176)
		(end 159.92475 -54.661308)
		(width 0.14478)
		(layer "F.Cu")
		(net "CONN_MICRO_USB_DP")
	)
	(segment
		(start 90.984578 -48.853344)
		(end 91.525344 -48.853344)
		(width 0.14478)
		(layer "F.Cu")
		(net "CONN_MICRO_USB_DP")
	)
	(segment
		(start 159.69488 -56.994552)
		(end 159.69488 -57.255918)
		(width 0.14478)
		(layer "F.Cu")
		(net "CONN_MICRO_USB_DP")
	)
	(segment
		(start 86.858602 -34.063178)
		(end 91.427046 -29.494734)
		(width 0.14478)
		(layer "F.Cu")
		(net "CONN_MICRO_USB_DP")
	)
	(segment
		(start 91.240864 -51.79822)
		(end 87.493602 -51.79822)
		(width 0.14478)
		(layer "F.Cu")
		(net "CONN_MICRO_USB_DP")
	)
	(arc
		(start 86.381082 -50.697892)
		(mid 86.365201 -50.589188)
		(end 86.36 -50.479452)
		(width 0.14478)
		(layer "F.Cu")
		(net "CONN_MICRO_USB_DP")
	)
	(arc
		(start 91.427046 -29.494734)
		(mid 92.066393 -28.538118)
		(end 92.2909 -27.409648)
		(width 0.14478)
		(layer "F.Cu")
		(net "CONN_MICRO_USB_DP")
	)
	(arc
		(start 160.205166 -54.962806)
		(mid 160.197476 -54.890939)
		(end 160.174686 -54.822344)
		(width 0.14478)
		(layer "F.Cu")
		(net "CONN_MICRO_USB_DP")
	)
	(arc
		(start 91.497658 -51.759612)
		(mid 91.370721 -51.788631)
		(end 91.240864 -51.79822)
		(width 0.14478)
		(layer "F.Cu")
		(net "CONN_MICRO_USB_DP")
	)
	(arc
		(start 159.69488 -57.255918)
		(mid 159.519227 -57.579738)
		(end 159.17418 -57.7088)
		(width 0.14478)
		(layer "F.Cu")
		(net "CONN_MICRO_USB_DP")
	)
	(arc
		(start 160.328356 -53.5305)
		(mid 160.350674 -53.584382)
		(end 160.404556 -53.6067)
		(width 0.14478)
		(layer "F.Cu")
		(net "CONN_MICRO_USB_DP")
	)
	(arc
		(start 92.2909 -23.748746)
		(mid 92.290742 -23.743159)
		(end 92.290646 -23.73757)
		(width 0.14478)
		(layer "F.Cu")
		(net "CONN_MICRO_USB_DP")
	)
	(arc
		(start 87.110824 -51.699414)
		(mid 86.635595 -51.279081)
		(end 86.381082 -50.697892)
		(width 0.14478)
		(layer "F.Cu")
		(net "CONN_MICRO_USB_DP")
	)
	(arc
		(start 159.699452 -54.616096)
		(mid 159.572298 -54.590821)
		(end 159.464502 -54.518814)
		(width 0.14478)
		(layer "F.Cu")
		(net "CONN_MICRO_USB_DP")
	)
	(arc
		(start 161.68624 -53.4543)
		(mid 161.701104 -53.454126)
		(end 161.715958 -53.453538)
		(width 0.14478)
		(layer "F.Cu")
		(net "CONN_MICRO_USB_DP")
	)
	(arc
		(start 160.907476 -53.5305)
		(mid 160.929794 -53.476618)
		(end 160.983676 -53.4543)
		(width 0.14478)
		(layer "F.Cu")
		(net "CONN_MICRO_USB_DP")
	)
	(arc
		(start 160.252156 -53.4543)
		(mid 160.306038 -53.476618)
		(end 160.328356 -53.5305)
		(width 0.14478)
		(layer "F.Cu")
		(net "CONN_MICRO_USB_DP")
	)
	(arc
		(start 159.15894 -53.767482)
		(mid 159.168991 -53.694981)
		(end 159.198564 -53.628036)
		(width 0.14478)
		(layer "F.Cu")
		(net "CONN_MICRO_USB_DP")
	)
	(arc
		(start 161.826956 -53.557678)
		(mid 161.87392 -53.589058)
		(end 161.929318 -53.600096)
		(width 0.14478)
		(layer "F.Cu")
		(net "CONN_MICRO_USB_DP")
	)
	(arc
		(start 160.174686 -54.822344)
		(mid 160.131987 -54.762201)
		(end 160.070292 -54.72176)
		(width 0.14478)
		(layer "F.Cu")
		(net "CONN_MICRO_USB_DP")
	)
	(arc
		(start 92.2909 -23.736808)
		(mid 92.206595 -23.538566)
		(end 92.075 -23.368)
		(width 0.14478)
		(layer "F.Cu")
		(net "CONN_MICRO_USB_DP")
	)
	(arc
		(start 160.205166 -56.484266)
		(mid 160.116264 -56.698894)
		(end 159.901636 -56.787796)
		(width 0.14478)
		(layer "F.Cu")
		(net "CONN_MICRO_USB_DP")
	)
	(arc
		(start 157.76067 -57.7088)
		(mid 157.707914 -57.712167)
		(end 157.656022 -57.722262)
		(width 0.14478)
		(layer "F.Cu")
		(net "CONN_MICRO_USB_DP")
	)
	(arc
		(start 159.92475 -54.661308)
		(mid 159.814338 -54.627564)
		(end 159.699452 -54.616096)
		(width 0.14478)
		(layer "F.Cu")
		(net "CONN_MICRO_USB_DP")
	)
	(arc
		(start 161.715958 -53.453538)
		(mid 161.73142 -53.46389)
		(end 161.745422 -53.476144)
		(width 0.14478)
		(layer "F.Cu")
		(net "CONN_MICRO_USB_DP")
	)
	(arc
		(start 92.145104 -51.292506)
		(mid 91.859486 -51.578874)
		(end 91.497658 -51.759612)
		(width 0.14478)
		(layer "F.Cu")
		(net "CONN_MICRO_USB_DP")
	)
	(arc
		(start 159.260286 -54.314598)
		(mid 159.1853 -54.202374)
		(end 159.15894 -54.069996)
		(width 0.14478)
		(layer "F.Cu")
		(net "CONN_MICRO_USB_DP")
	)
	(arc
		(start 91.73464 -48.872394)
		(mid 92.106423 -49.026391)
		(end 92.26042 -49.398174)
		(width 0.14478)
		(layer "F.Cu")
		(net "CONN_MICRO_USB_DP")
	)
	(arc
		(start 159.901636 -56.787796)
		(mid 159.755437 -56.848353)
		(end 159.69488 -56.994552)
		(width 0.14478)
		(layer "F.Cu")
		(net "CONN_MICRO_USB_DP")
	)
	(arc
		(start 160.831276 -53.6067)
		(mid 160.885158 -53.584382)
		(end 160.907476 -53.5305)
		(width 0.14478)
		(layer "F.Cu")
		(net "CONN_MICRO_USB_DP")
	)
	(arc
		(start 87.493602 -51.79822)
		(mid 87.2959 -51.77326)
		(end 87.110824 -51.699414)
		(width 0.14478)
		(layer "F.Cu")
		(net "CONN_MICRO_USB_DP")
	)
	(arc
		(start 92.26042 -50.932334)
		(mid 92.231001 -51.121461)
		(end 92.145104 -51.292506)
		(width 0.14478)
		(layer "F.Cu")
		(net "CONN_MICRO_USB_DP")
	)
	(arc
		(start 159.198564 -53.628036)
		(mid 159.33183 -53.500707)
		(end 159.510222 -53.4543)
		(width 0.14478)
		(layer "F.Cu")
		(net "CONN_MICRO_USB_DP")
	)
	(arc
		(start 86.36 -35.267138)
		(mid 86.489532 -34.615556)
		(end 86.858602 -34.063178)
		(width 0.14478)
		(layer "F.Cu")
		(net "CONN_MICRO_USB_DP")
	)
	(segment
		(start 127.532384 -23.1775)
		(end 145.658078 -23.1775)
		(width 0.15748)
		(layer "In7.Cu")
		(net "CONN_MICRO_USB_DP")
	)
	(segment
		(start 151.656288 -31.270194)
		(end 152.21966 -31.83382)
		(width 0.15748)
		(layer "In7.Cu")
		(net "CONN_MICRO_USB_DP")
	)
	(segment
		(start 158.193994 -57.587896)
		(end 158.036514 -57.587896)
		(width 0.15748)
		(layer "In7.Cu")
		(net "CONN_MICRO_USB_DP")
	)
	(segment
		(start 96.658176 -17.39646)
		(end 119.187468 -17.39646)
		(width 0.15748)
		(layer "In7.Cu")
		(net "CONN_MICRO_USB_DP")
	)
	(segment
		(start 153.5811 -35.12058)
		(end 153.5811 -42.415714)
		(width 0.15748)
		(layer "In7.Cu")
		(net "CONN_MICRO_USB_DP")
	)
	(segment
		(start 157.481524 -57.817766)
		(end 157.470094 -57.829196)
		(width 0.15748)
		(layer "In7.Cu")
		(net "CONN_MICRO_USB_DP")
	)
	(segment
		(start 158.34106 -48.801528)
		(end 158.34106 -55.205376)
		(width 0.15748)
		(layer "In7.Cu")
		(net "CONN_MICRO_USB_DP")
	)
	(segment
		(start 158.399734 -55.346854)
		(end 158.56077 -55.50789)
		(width 0.15748)
		(layer "In7.Cu")
		(net "CONN_MICRO_USB_DP")
	)
	(segment
		(start 93.104208 -19.859752)
		(end 94.796864 -18.167096)
		(width 0.15748)
		(layer "In7.Cu")
		(net "CONN_MICRO_USB_DP")
	)
	(segment
		(start 92.3163 -22.952456)
		(end 92.3163 -21.762466)
		(width 0.15748)
		(layer "In7.Cu")
		(net "CONN_MICRO_USB_DP")
	)
	(segment
		(start 154.228038 -43.976798)
		(end 157.837886 -47.586138)
		(width 0.15748)
		(layer "In7.Cu")
		(net "CONN_MICRO_USB_DP")
	)
	(segment
		(start 151.0538 -28.649676)
		(end 151.0538 -29.816044)
		(width 0.15748)
		(layer "In7.Cu")
		(net "CONN_MICRO_USB_DP")
	)
	(segment
		(start 121.51868 -18.36166)
		(end 125.486922 -22.330156)
		(width 0.15748)
		(layer "In7.Cu")
		(net "CONN_MICRO_USB_DP")
	)
	(segment
		(start 147.21078 -23.876)
		(end 150.395432 -27.060652)
		(width 0.15748)
		(layer "In7.Cu")
		(net "CONN_MICRO_USB_DP")
	)
	(segment
		(start 92.075 -23.368)
		(end 92.19311 -23.24989)
		(width 0.15748)
		(layer "In7.Cu")
		(net "CONN_MICRO_USB_DP")
	)
	(segment
		(start 158.85668 -56.2229)
		(end 158.85668 -56.92521)
		(width 0.15748)
		(layer "In7.Cu")
		(net "CONN_MICRO_USB_DP")
	)
	(arc
		(start 92.3163 -21.762466)
		(mid 92.521066 -20.732767)
		(end 93.104208 -19.859752)
		(width 0.15748)
		(layer "In7.Cu")
		(net "CONN_MICRO_USB_DP")
	)
	(arc
		(start 125.486922 -22.330156)
		(mid 126.425359 -22.957326)
		(end 127.532384 -23.1775)
		(width 0.15748)
		(layer "In7.Cu")
		(net "CONN_MICRO_USB_DP")
	)
	(arc
		(start 153.5811 -42.415714)
		(mid 153.749274 -43.26062)
		(end 154.228038 -43.976798)
		(width 0.15748)
		(layer "In7.Cu")
		(net "CONN_MICRO_USB_DP")
	)
	(arc
		(start 145.865596 -23.193502)
		(mid 146.592536 -23.427643)
		(end 147.21078 -23.876)
		(width 0.15748)
		(layer "In7.Cu")
		(net "CONN_MICRO_USB_DP")
	)
	(arc
		(start 119.187468 -17.39646)
		(mid 120.449097 -17.647151)
		(end 121.51868 -18.36166)
		(width 0.15748)
		(layer "In7.Cu")
		(net "CONN_MICRO_USB_DP")
	)
	(arc
		(start 151.0538 -29.816044)
		(mid 151.210435 -30.603032)
		(end 151.656288 -31.270194)
		(width 0.15748)
		(layer "In7.Cu")
		(net "CONN_MICRO_USB_DP")
	)
	(arc
		(start 150.395432 -27.060652)
		(mid 150.882651 -27.789687)
		(end 151.0538 -28.649676)
		(width 0.15748)
		(layer "In7.Cu")
		(net "CONN_MICRO_USB_DP")
	)
	(arc
		(start 158.85668 -56.92521)
		(mid 158.662584 -57.3938)
		(end 158.193994 -57.587896)
		(width 0.15748)
		(layer "In7.Cu")
		(net "CONN_MICRO_USB_DP")
	)
	(arc
		(start 94.796864 -18.167096)
		(mid 95.65087 -17.596623)
		(end 96.658176 -17.39646)
		(width 0.15748)
		(layer "In7.Cu")
		(net "CONN_MICRO_USB_DP")
	)
	(arc
		(start 145.658078 -23.1775)
		(mid 145.762145 -23.181504)
		(end 145.865596 -23.193502)
		(width 0.15748)
		(layer "In7.Cu")
		(net "CONN_MICRO_USB_DP")
	)
	(arc
		(start 158.56077 -55.50789)
		(mid 158.779883 -55.835954)
		(end 158.85668 -56.2229)
		(width 0.15748)
		(layer "In7.Cu")
		(net "CONN_MICRO_USB_DP")
	)
	(arc
		(start 157.837886 -47.586138)
		(mid 158.210397 -48.143779)
		(end 158.34106 -48.801528)
		(width 0.15748)
		(layer "In7.Cu")
		(net "CONN_MICRO_USB_DP")
	)
	(arc
		(start 158.34106 -55.205376)
		(mid 158.356363 -55.281931)
		(end 158.399734 -55.346854)
		(width 0.15748)
		(layer "In7.Cu")
		(net "CONN_MICRO_USB_DP")
	)
	(arc
		(start 92.19311 -23.24989)
		(mid 92.284292 -23.113426)
		(end 92.3163 -22.952456)
		(width 0.15748)
		(layer "In7.Cu")
		(net "CONN_MICRO_USB_DP")
	)
	(arc
		(start 158.036514 -57.587896)
		(mid 157.736161 -57.64764)
		(end 157.481524 -57.817766)
		(width 0.15748)
		(layer "In7.Cu")
		(net "CONN_MICRO_USB_DP")
	)
	(arc
		(start 152.21966 -31.83382)
		(mid 153.227259 -33.341798)
		(end 153.5811 -35.12058)
		(width 0.15748)
		(layer "In7.Cu")
		(net "CONN_MICRO_USB_DP")
	)
	(segment
		(start 86.94166 -43.09491)
		(end 86.94166 -42.71645)
		(width 0.14478)
		(layer "F.Cu")
		(net "CONN_MICRO_USB_DM")
	)
	(segment
		(start 87.128096 -34.332672)
		(end 91.69654 -29.764228)
		(width 0.14478)
		(layer "F.Cu")
		(net "CONN_MICRO_USB_DM")
	)
	(segment
		(start 91.241372 -51.41722)
		(end 87.493348 -51.41722)
		(width 0.14478)
		(layer "F.Cu")
		(net "CONN_MICRO_USB_DM")
	)
	(segment
		(start 157.727396 -57.273698)
		(end 157.470094 -57.016396)
		(width 0.14478)
		(layer "F.Cu")
		(net "CONN_MICRO_USB_DM")
	)
	(segment
		(start 86.741 -37.88283)
		(end 86.741 -37.50437)
		(width 0.14478)
		(layer "F.Cu")
		(net "CONN_MICRO_USB_DM")
	)
	(segment
		(start 91.87942 -49.398174)
		(end 91.87942 -50.932334)
		(width 0.14478)
		(layer "F.Cu")
		(net "CONN_MICRO_USB_DM")
	)
	(segment
		(start 158.77794 -54.00802)
		(end 158.77794 -53.767736)
		(width 0.14478)
		(layer "F.Cu")
		(net "CONN_MICRO_USB_DM")
	)
	(segment
		(start 159.31388 -57.008776)
		(end 159.31388 -57.220866)
		(width 0.14478)
		(layer "F.Cu")
		(net "CONN_MICRO_USB_DM")
	)
	(segment
		(start 86.741 -50.479706)
		(end 86.741 -44.45381)
		(width 0.14478)
		(layer "F.Cu")
		(net "CONN_MICRO_USB_DM")
	)
	(segment
		(start 86.94166 -38.46195)
		(end 86.94166 -38.08349)
		(width 0.14478)
		(layer "F.Cu")
		(net "CONN_MICRO_USB_DM")
	)
	(segment
		(start 86.741 -40.19931)
		(end 86.741 -39.82085)
		(width 0.14478)
		(layer "F.Cu")
		(net "CONN_MICRO_USB_DM")
	)
	(segment
		(start 86.741 -39.04107)
		(end 86.741 -38.66261)
		(width 0.14478)
		(layer "F.Cu")
		(net "CONN_MICRO_USB_DM")
	)
	(segment
		(start 86.94166 -37.30371)
		(end 86.94166 -36.92525)
		(width 0.14478)
		(layer "F.Cu")
		(net "CONN_MICRO_USB_DM")
	)
	(segment
		(start 158.305246 -55.926736)
		(end 158.305246 -56.643016)
		(width 0.14478)
		(layer "F.Cu")
		(net "CONN_MICRO_USB_DM")
	)
	(segment
		(start 161.788602 -53.030882)
		(end 161.826956 -52.992528)
		(width 0.14478)
		(layer "F.Cu")
		(net "CONN_MICRO_USB_DM")
	)
	(segment
		(start 161.929318 -52.95011)
		(end 162.8267 -52.95011)
		(width 0.14478)
		(layer "F.Cu")
		(net "CONN_MICRO_USB_DM")
	)
	(segment
		(start 157.798262 -57.3278)
		(end 157.727396 -57.273698)
		(width 0.14478)
		(layer "F.Cu")
		(net "CONN_MICRO_USB_DM")
	)
	(segment
		(start 86.741 -41.35755)
		(end 86.741 -40.97909)
		(width 0.14478)
		(layer "F.Cu")
		(net "CONN_MICRO_USB_DM")
	)
	(segment
		(start 158.616142 -54.230524)
		(end 158.735776 -54.110382)
		(width 0.14478)
		(layer "F.Cu")
		(net "CONN_MICRO_USB_DM")
	)
	(segment
		(start 86.741 -36.72459)
		(end 86.741 -35.267138)
		(width 0.14478)
		(layer "F.Cu")
		(net "CONN_MICRO_USB_DM")
	)
	(segment
		(start 158.36646 -54.48046)
		(end 158.616142 -54.230524)
		(width 0.14478)
		(layer "F.Cu")
		(net "CONN_MICRO_USB_DM")
	)
	(segment
		(start 159.510222 -53.0733)
		(end 161.68624 -53.0733)
		(width 0.14478)
		(layer "F.Cu")
		(net "CONN_MICRO_USB_DM")
	)
	(segment
		(start 86.94166 -41.93667)
		(end 86.94166 -41.55821)
		(width 0.14478)
		(layer "F.Cu")
		(net "CONN_MICRO_USB_DM")
	)
	(segment
		(start 86.94166 -39.62019)
		(end 86.94166 -39.24173)
		(width 0.14478)
		(layer "F.Cu")
		(net "CONN_MICRO_USB_DM")
	)
	(segment
		(start 92.6719 -23.742904)
		(end 92.6719 -23.736808)
		(width 0.14478)
		(layer "F.Cu")
		(net "CONN_MICRO_USB_DM")
	)
	(segment
		(start 92.6719 -27.409648)
		(end 92.6719 -23.746714)
		(width 0.14478)
		(layer "F.Cu")
		(net "CONN_MICRO_USB_DM")
	)
	(segment
		(start 158.305246 -55.926736)
		(end 158.305246 -54.628288)
		(width 0.14478)
		(layer "F.Cu")
		(net "CONN_MICRO_USB_DM")
	)
	(segment
		(start 159.17418 -57.3278)
		(end 157.798262 -57.3278)
		(width 0.14478)
		(layer "F.Cu")
		(net "CONN_MICRO_USB_DM")
	)
	(segment
		(start 158.526226 -56.863996)
		(end 159.1691 -56.863996)
		(width 0.14478)
		(layer "F.Cu")
		(net "CONN_MICRO_USB_DM")
	)
	(segment
		(start 86.94166 -40.77843)
		(end 86.94166 -40.39997)
		(width 0.14478)
		(layer "F.Cu")
		(net "CONN_MICRO_USB_DM")
	)
	(segment
		(start 90.984578 -49.253394)
		(end 91.73464 -49.253394)
		(width 0.14478)
		(layer "F.Cu")
		(net "CONN_MICRO_USB_DM")
	)
	(segment
		(start 86.741 -43.67403)
		(end 86.741 -43.29557)
		(width 0.14478)
		(layer "F.Cu")
		(net "CONN_MICRO_USB_DM")
	)
	(segment
		(start 86.741 -42.51579)
		(end 86.741 -42.13733)
		(width 0.14478)
		(layer "F.Cu")
		(net "CONN_MICRO_USB_DM")
	)
	(segment
		(start 86.94166 -44.25315)
		(end 86.94166 -43.87469)
		(width 0.14478)
		(layer "F.Cu")
		(net "CONN_MICRO_USB_DM")
	)
	(arc
		(start 86.84133 -40.87876)
		(mid 86.912274 -40.849374)
		(end 86.94166 -40.77843)
		(width 0.14478)
		(layer "F.Cu")
		(net "CONN_MICRO_USB_DM")
	)
	(arc
		(start 86.84133 -39.1414)
		(mid 86.770386 -39.112014)
		(end 86.741 -39.04107)
		(width 0.14478)
		(layer "F.Cu")
		(net "CONN_MICRO_USB_DM")
	)
	(arc
		(start 92.6719 -23.746714)
		(mid 92.671886 -23.744809)
		(end 92.6719 -23.742904)
		(width 0.14478)
		(layer "F.Cu")
		(net "CONN_MICRO_USB_DM")
	)
	(arc
		(start 86.75497 -50.623978)
		(mid 86.744447 -50.552184)
		(end 86.741 -50.479706)
		(width 0.14478)
		(layer "F.Cu")
		(net "CONN_MICRO_USB_DM")
	)
	(arc
		(start 86.94166 -43.87469)
		(mid 86.912274 -43.803746)
		(end 86.84133 -43.77436)
		(width 0.14478)
		(layer "F.Cu")
		(net "CONN_MICRO_USB_DM")
	)
	(arc
		(start 86.94166 -42.71645)
		(mid 86.912274 -42.645506)
		(end 86.84133 -42.61612)
		(width 0.14478)
		(layer "F.Cu")
		(net "CONN_MICRO_USB_DM")
	)
	(arc
		(start 86.741 -37.50437)
		(mid 86.770386 -37.433426)
		(end 86.84133 -37.40404)
		(width 0.14478)
		(layer "F.Cu")
		(net "CONN_MICRO_USB_DM")
	)
	(arc
		(start 158.305246 -54.628288)
		(mid 158.321158 -54.548291)
		(end 158.36646 -54.48046)
		(width 0.14478)
		(layer "F.Cu")
		(net "CONN_MICRO_USB_DM")
	)
	(arc
		(start 86.741 -44.45381)
		(mid 86.770386 -44.382866)
		(end 86.84133 -44.35348)
		(width 0.14478)
		(layer "F.Cu")
		(net "CONN_MICRO_USB_DM")
	)
	(arc
		(start 86.84133 -36.82492)
		(mid 86.770386 -36.795534)
		(end 86.741 -36.72459)
		(width 0.14478)
		(layer "F.Cu")
		(net "CONN_MICRO_USB_DM")
	)
	(arc
		(start 86.84133 -40.29964)
		(mid 86.770386 -40.270254)
		(end 86.741 -40.19931)
		(width 0.14478)
		(layer "F.Cu")
		(net "CONN_MICRO_USB_DM")
	)
	(arc
		(start 92.6719 -23.736808)
		(mid 92.75614 -23.538522)
		(end 92.8878 -23.368)
		(width 0.14478)
		(layer "F.Cu")
		(net "CONN_MICRO_USB_DM")
	)
	(arc
		(start 86.94166 -39.24173)
		(mid 86.912274 -39.170786)
		(end 86.84133 -39.1414)
		(width 0.14478)
		(layer "F.Cu")
		(net "CONN_MICRO_USB_DM")
	)
	(arc
		(start 158.305246 -56.643016)
		(mid 158.36997 -56.799272)
		(end 158.526226 -56.863996)
		(width 0.14478)
		(layer "F.Cu")
		(net "CONN_MICRO_USB_DM")
	)
	(arc
		(start 86.741 -43.29557)
		(mid 86.770386 -43.224626)
		(end 86.84133 -43.19524)
		(width 0.14478)
		(layer "F.Cu")
		(net "CONN_MICRO_USB_DM")
	)
	(arc
		(start 86.84133 -42.037)
		(mid 86.912274 -42.007614)
		(end 86.94166 -41.93667)
		(width 0.14478)
		(layer "F.Cu")
		(net "CONN_MICRO_USB_DM")
	)
	(arc
		(start 159.1691 -56.863996)
		(mid 159.271475 -56.906401)
		(end 159.31388 -57.008776)
		(width 0.14478)
		(layer "F.Cu")
		(net "CONN_MICRO_USB_DM")
	)
	(arc
		(start 158.87446 -53.42763)
		(mid 159.146304 -53.167862)
		(end 159.510222 -53.0733)
		(width 0.14478)
		(layer "F.Cu")
		(net "CONN_MICRO_USB_DM")
	)
	(arc
		(start 86.94166 -38.08349)
		(mid 86.912274 -38.012546)
		(end 86.84133 -37.98316)
		(width 0.14478)
		(layer "F.Cu")
		(net "CONN_MICRO_USB_DM")
	)
	(arc
		(start 86.84133 -44.35348)
		(mid 86.912274 -44.324094)
		(end 86.94166 -44.25315)
		(width 0.14478)
		(layer "F.Cu")
		(net "CONN_MICRO_USB_DM")
	)
	(arc
		(start 87.493348 -51.41722)
		(mid 87.39141 -51.404285)
		(end 87.29599 -51.366166)
		(width 0.14478)
		(layer "F.Cu")
		(net "CONN_MICRO_USB_DM")
	)
	(arc
		(start 159.31388 -57.220866)
		(mid 159.262131 -57.297968)
		(end 159.17418 -57.3278)
		(width 0.14478)
		(layer "F.Cu")
		(net "CONN_MICRO_USB_DM")
	)
	(arc
		(start 86.84133 -42.61612)
		(mid 86.770386 -42.586734)
		(end 86.741 -42.51579)
		(width 0.14478)
		(layer "F.Cu")
		(net "CONN_MICRO_USB_DM")
	)
	(arc
		(start 91.384882 -51.39563)
		(mid 91.313945 -51.411869)
		(end 91.241372 -51.41722)
		(width 0.14478)
		(layer "F.Cu")
		(net "CONN_MICRO_USB_DM")
	)
	(arc
		(start 86.84133 -38.56228)
		(mid 86.912274 -38.532894)
		(end 86.94166 -38.46195)
		(width 0.14478)
		(layer "F.Cu")
		(net "CONN_MICRO_USB_DM")
	)
	(arc
		(start 86.741 -40.97909)
		(mid 86.770386 -40.908146)
		(end 86.84133 -40.87876)
		(width 0.14478)
		(layer "F.Cu")
		(net "CONN_MICRO_USB_DM")
	)
	(arc
		(start 86.84133 -39.72052)
		(mid 86.912274 -39.691134)
		(end 86.94166 -39.62019)
		(width 0.14478)
		(layer "F.Cu")
		(net "CONN_MICRO_USB_DM")
	)
	(arc
		(start 161.68624 -53.0733)
		(mid 161.741645 -53.062279)
		(end 161.788602 -53.030882)
		(width 0.14478)
		(layer "F.Cu")
		(net "CONN_MICRO_USB_DM")
	)
	(arc
		(start 86.741 -38.66261)
		(mid 86.770386 -38.591666)
		(end 86.84133 -38.56228)
		(width 0.14478)
		(layer "F.Cu")
		(net "CONN_MICRO_USB_DM")
	)
	(arc
		(start 91.69654 -29.764228)
		(mid 92.418421 -28.683952)
		(end 92.6719 -27.409648)
		(width 0.14478)
		(layer "F.Cu")
		(net "CONN_MICRO_USB_DM")
	)
	(arc
		(start 86.84133 -41.45788)
		(mid 86.770386 -41.428494)
		(end 86.741 -41.35755)
		(width 0.14478)
		(layer "F.Cu")
		(net "CONN_MICRO_USB_DM")
	)
	(arc
		(start 86.741 -39.82085)
		(mid 86.770386 -39.749906)
		(end 86.84133 -39.72052)
		(width 0.14478)
		(layer "F.Cu")
		(net "CONN_MICRO_USB_DM")
	)
	(arc
		(start 91.87942 -50.932334)
		(mid 91.868137 -51.00476)
		(end 91.835224 -51.070256)
		(width 0.14478)
		(layer "F.Cu")
		(net "CONN_MICRO_USB_DM")
	)
	(arc
		(start 86.94166 -40.39997)
		(mid 86.912274 -40.329026)
		(end 86.84133 -40.29964)
		(width 0.14478)
		(layer "F.Cu")
		(net "CONN_MICRO_USB_DM")
	)
	(arc
		(start 86.94166 -41.55821)
		(mid 86.912274 -41.487266)
		(end 86.84133 -41.45788)
		(width 0.14478)
		(layer "F.Cu")
		(net "CONN_MICRO_USB_DM")
	)
	(arc
		(start 86.741 -35.267138)
		(mid 86.841613 -34.761412)
		(end 87.128096 -34.332672)
		(width 0.14478)
		(layer "F.Cu")
		(net "CONN_MICRO_USB_DM")
	)
	(arc
		(start 91.73464 -49.253394)
		(mid 91.837015 -49.295799)
		(end 91.87942 -49.398174)
		(width 0.14478)
		(layer "F.Cu")
		(net "CONN_MICRO_USB_DM")
	)
	(arc
		(start 86.84133 -37.98316)
		(mid 86.770386 -37.953774)
		(end 86.741 -37.88283)
		(width 0.14478)
		(layer "F.Cu")
		(net "CONN_MICRO_USB_DM")
	)
	(arc
		(start 91.835224 -51.070256)
		(mid 91.636586 -51.269674)
		(end 91.384882 -51.39563)
		(width 0.14478)
		(layer "F.Cu")
		(net "CONN_MICRO_USB_DM")
	)
	(arc
		(start 161.826956 -52.992528)
		(mid 161.87392 -52.961148)
		(end 161.929318 -52.95011)
		(width 0.14478)
		(layer "F.Cu")
		(net "CONN_MICRO_USB_DM")
	)
	(arc
		(start 158.77794 -53.767736)
		(mid 158.80247 -53.590949)
		(end 158.87446 -53.42763)
		(width 0.14478)
		(layer "F.Cu")
		(net "CONN_MICRO_USB_DM")
	)
	(arc
		(start 87.29599 -51.366166)
		(mid 86.943708 -51.054689)
		(end 86.75497 -50.623978)
		(width 0.14478)
		(layer "F.Cu")
		(net "CONN_MICRO_USB_DM")
	)
	(arc
		(start 86.84133 -43.19524)
		(mid 86.912274 -43.165854)
		(end 86.94166 -43.09491)
		(width 0.14478)
		(layer "F.Cu")
		(net "CONN_MICRO_USB_DM")
	)
	(arc
		(start 86.84133 -43.77436)
		(mid 86.770386 -43.744974)
		(end 86.741 -43.67403)
		(width 0.14478)
		(layer "F.Cu")
		(net "CONN_MICRO_USB_DM")
	)
	(arc
		(start 86.741 -42.13733)
		(mid 86.770386 -42.066386)
		(end 86.84133 -42.037)
		(width 0.14478)
		(layer "F.Cu")
		(net "CONN_MICRO_USB_DM")
	)
	(arc
		(start 86.94166 -36.92525)
		(mid 86.912274 -36.854306)
		(end 86.84133 -36.82492)
		(width 0.14478)
		(layer "F.Cu")
		(net "CONN_MICRO_USB_DM")
	)
	(arc
		(start 86.84133 -37.40404)
		(mid 86.912274 -37.374654)
		(end 86.94166 -37.30371)
		(width 0.14478)
		(layer "F.Cu")
		(net "CONN_MICRO_USB_DM")
	)
	(arc
		(start 158.735776 -54.110382)
		(mid 158.766996 -54.063375)
		(end 158.77794 -54.00802)
		(width 0.14478)
		(layer "F.Cu")
		(net "CONN_MICRO_USB_DM")
	)
	(segment
		(start 158.01086 -50.041048)
		(end 158.01086 -48.801528)
		(width 0.15748)
		(layer "In7.Cu")
		(net "CONN_MICRO_USB_DM")
	)
	(segment
		(start 154.953462 -45.4152)
		(end 154.630882 -45.09262)
		(width 0.15748)
		(layer "In7.Cu")
		(net "CONN_MICRO_USB_DM")
	)
	(segment
		(start 158.036514 -57.257696)
		(end 158.193994 -57.257696)
		(width 0.15748)
		(layer "In7.Cu")
		(net "CONN_MICRO_USB_DM")
	)
	(segment
		(start 157.84576 -53.190648)
		(end 157.84576 -52.725828)
		(width 0.15748)
		(layer "In7.Cu")
		(net "CONN_MICRO_USB_DM")
	)
	(segment
		(start 145.657824 -23.5077)
		(end 127.53213 -23.5077)
		(width 0.15748)
		(layer "In7.Cu")
		(net "CONN_MICRO_USB_DM")
	)
	(segment
		(start 158.32709 -55.74157)
		(end 158.166054 -55.580534)
		(width 0.15748)
		(layer "In7.Cu")
		(net "CONN_MICRO_USB_DM")
	)
	(segment
		(start 92.729558 -23.209758)
		(end 92.8878 -23.368)
		(width 0.15748)
		(layer "In7.Cu")
		(net "CONN_MICRO_USB_DM")
	)
	(segment
		(start 158.52648 -56.92521)
		(end 158.52648 -56.2229)
		(width 0.15748)
		(layer "In7.Cu")
		(net "CONN_MICRO_USB_DM")
	)
	(segment
		(start 155.844494 -46.306232)
		(end 155.521914 -45.983652)
		(width 0.15748)
		(layer "In7.Cu")
		(net "CONN_MICRO_USB_DM")
	)
	(segment
		(start 150.161752 -27.294332)
		(end 146.9771 -24.10968)
		(width 0.15748)
		(layer "In7.Cu")
		(net "CONN_MICRO_USB_DM")
	)
	(segment
		(start 151.98598 -32.0675)
		(end 151.422608 -31.503874)
		(width 0.15748)
		(layer "In7.Cu")
		(net "CONN_MICRO_USB_DM")
	)
	(segment
		(start 150.7236 -29.816298)
		(end 150.7236 -28.64993)
		(width 0.15748)
		(layer "In7.Cu")
		(net "CONN_MICRO_USB_DM")
	)
	(segment
		(start 157.470094 -57.016396)
		(end 157.481524 -57.027826)
		(width 0.15748)
		(layer "In7.Cu")
		(net "CONN_MICRO_USB_DM")
	)
	(segment
		(start 157.84576 -50.670968)
		(end 157.84576 -50.206148)
		(width 0.15748)
		(layer "In7.Cu")
		(net "CONN_MICRO_USB_DM")
	)
	(segment
		(start 156.412946 -46.628812)
		(end 156.090366 -46.306232)
		(width 0.15748)
		(layer "In7.Cu")
		(net "CONN_MICRO_USB_DM")
	)
	(segment
		(start 125.253496 -22.563836)
		(end 121.285 -18.59534)
		(width 0.15748)
		(layer "In7.Cu")
		(net "CONN_MICRO_USB_DM")
	)
	(segment
		(start 95.030544 -18.400776)
		(end 93.337888 -20.093432)
		(width 0.15748)
		(layer "In7.Cu")
		(net "CONN_MICRO_USB_DM")
	)
	(segment
		(start 153.2509 -38.415468)
		(end 153.2509 -37.955728)
		(width 0.15748)
		(layer "In7.Cu")
		(net "CONN_MICRO_USB_DM")
	)
	(segment
		(start 157.84576 -51.930808)
		(end 157.84576 -51.465988)
		(width 0.15748)
		(layer "In7.Cu")
		(net "CONN_MICRO_USB_DM")
	)
	(segment
		(start 157.604206 -47.819818)
		(end 156.981398 -47.197264)
		(width 0.15748)
		(layer "In7.Cu")
		(net "CONN_MICRO_USB_DM")
	)
	(segment
		(start 158.01086 -51.300888)
		(end 158.01086 -50.836068)
		(width 0.15748)
		(layer "In7.Cu")
		(net "CONN_MICRO_USB_DM")
	)
	(segment
		(start 153.2509 -37.155628)
		(end 153.2509 -35.120834)
		(width 0.15748)
		(layer "In7.Cu")
		(net "CONN_MICRO_USB_DM")
	)
	(segment
		(start 153.2509 -39.675308)
		(end 153.2509 -39.215568)
		(width 0.15748)
		(layer "In7.Cu")
		(net "CONN_MICRO_USB_DM")
	)
	(segment
		(start 156.735526 -47.197264)
		(end 156.412946 -46.874684)
		(width 0.15748)
		(layer "In7.Cu")
		(net "CONN_MICRO_USB_DM")
	)
	(segment
		(start 154.630882 -44.846748)
		(end 153.994358 -44.210478)
		(width 0.15748)
		(layer "In7.Cu")
		(net "CONN_MICRO_USB_DM")
	)
	(segment
		(start 158.01086 -52.560728)
		(end 158.01086 -52.095908)
		(width 0.15748)
		(layer "In7.Cu")
		(net "CONN_MICRO_USB_DM")
	)
	(segment
		(start 155.521914 -45.73778)
		(end 155.199334 -45.4152)
		(width 0.15748)
		(layer "In7.Cu")
		(net "CONN_MICRO_USB_DM")
	)
	(segment
		(start 153.08072 -37.785548)
		(end 153.08072 -37.325808)
		(width 0.15748)
		(layer "In7.Cu")
		(net "CONN_MICRO_USB_DM")
	)
	(segment
		(start 92.6465 -21.76272)
		(end 92.6465 -23.009098)
		(width 0.15748)
		(layer "In7.Cu")
		(net "CONN_MICRO_USB_DM")
	)
	(segment
		(start 153.08072 -40.305228)
		(end 153.08072 -39.845488)
		(width 0.15748)
		(layer "In7.Cu")
		(net "CONN_MICRO_USB_DM")
	)
	(segment
		(start 119.187722 -17.72666)
		(end 96.658176 -17.72666)
		(width 0.15748)
		(layer "In7.Cu")
		(net "CONN_MICRO_USB_DM")
	)
	(segment
		(start 153.08072 -39.045388)
		(end 153.08072 -38.585648)
		(width 0.15748)
		(layer "In7.Cu")
		(net "CONN_MICRO_USB_DM")
	)
	(segment
		(start 158.01086 -55.205122)
		(end 158.01086 -53.355748)
		(width 0.15748)
		(layer "In7.Cu")
		(net "CONN_MICRO_USB_DM")
	)
	(segment
		(start 153.2509 -42.415714)
		(end 153.2509 -40.475408)
		(width 0.15748)
		(layer "In7.Cu")
		(net "CONN_MICRO_USB_DM")
	)
	(arc
		(start 127.53213 -23.5077)
		(mid 126.298933 -23.262402)
		(end 125.253496 -22.563836)
		(width 0.15748)
		(layer "In7.Cu")
		(net "CONN_MICRO_USB_DM")
	)
	(arc
		(start 154.630882 -45.09262)
		(mid 154.605421 -45.031152)
		(end 154.630882 -44.969684)
		(width 0.15748)
		(layer "In7.Cu")
		(net "CONN_MICRO_USB_DM")
	)
	(arc
		(start 92.6465 -23.009098)
		(mid 92.668082 -23.117686)
		(end 92.729558 -23.209758)
		(width 0.15748)
		(layer "In7.Cu")
		(net "CONN_MICRO_USB_DM")
	)
	(arc
		(start 153.16581 -39.760398)
		(mid 153.225978 -39.735476)
		(end 153.2509 -39.675308)
		(width 0.15748)
		(layer "In7.Cu")
		(net "CONN_MICRO_USB_DM")
	)
	(arc
		(start 154.630882 -44.969684)
		(mid 154.656343 -44.908216)
		(end 154.630882 -44.846748)
		(width 0.15748)
		(layer "In7.Cu")
		(net "CONN_MICRO_USB_DM")
	)
	(arc
		(start 156.090366 -46.306232)
		(mid 156.028898 -46.280771)
		(end 155.96743 -46.306232)
		(width 0.15748)
		(layer "In7.Cu")
		(net "CONN_MICRO_USB_DM")
	)
	(arc
		(start 153.08072 -38.585648)
		(mid 153.105642 -38.52548)
		(end 153.16581 -38.500558)
		(width 0.15748)
		(layer "In7.Cu")
		(net "CONN_MICRO_USB_DM")
	)
	(arc
		(start 158.01086 -53.355748)
		(mid 157.986682 -53.297376)
		(end 157.92831 -53.273198)
		(width 0.15748)
		(layer "In7.Cu")
		(net "CONN_MICRO_USB_DM")
	)
	(arc
		(start 157.84576 -51.465988)
		(mid 157.869938 -51.407616)
		(end 157.92831 -51.383438)
		(width 0.15748)
		(layer "In7.Cu")
		(net "CONN_MICRO_USB_DM")
	)
	(arc
		(start 153.16581 -39.130478)
		(mid 153.105642 -39.105556)
		(end 153.08072 -39.045388)
		(width 0.15748)
		(layer "In7.Cu")
		(net "CONN_MICRO_USB_DM")
	)
	(arc
		(start 153.08072 -39.845488)
		(mid 153.105642 -39.78532)
		(end 153.16581 -39.760398)
		(width 0.15748)
		(layer "In7.Cu")
		(net "CONN_MICRO_USB_DM")
	)
	(arc
		(start 156.858462 -47.197264)
		(mid 156.796994 -47.222725)
		(end 156.735526 -47.197264)
		(width 0.15748)
		(layer "In7.Cu")
		(net "CONN_MICRO_USB_DM")
	)
	(arc
		(start 156.981398 -47.197264)
		(mid 156.91993 -47.171803)
		(end 156.858462 -47.197264)
		(width 0.15748)
		(layer "In7.Cu")
		(net "CONN_MICRO_USB_DM")
	)
	(arc
		(start 153.16581 -38.500558)
		(mid 153.225978 -38.475636)
		(end 153.2509 -38.415468)
		(width 0.15748)
		(layer "In7.Cu")
		(net "CONN_MICRO_USB_DM")
	)
	(arc
		(start 158.166054 -55.580534)
		(mid 158.051103 -55.408264)
		(end 158.01086 -55.205122)
		(width 0.15748)
		(layer "In7.Cu")
		(net "CONN_MICRO_USB_DM")
	)
	(arc
		(start 155.076398 -45.4152)
		(mid 155.01493 -45.440661)
		(end 154.953462 -45.4152)
		(width 0.15748)
		(layer "In7.Cu")
		(net "CONN_MICRO_USB_DM")
	)
	(arc
		(start 158.01086 -52.095908)
		(mid 157.986682 -52.037536)
		(end 157.92831 -52.013358)
		(width 0.15748)
		(layer "In7.Cu")
		(net "CONN_MICRO_USB_DM")
	)
	(arc
		(start 153.16581 -37.870638)
		(mid 153.105642 -37.845716)
		(end 153.08072 -37.785548)
		(width 0.15748)
		(layer "In7.Cu")
		(net "CONN_MICRO_USB_DM")
	)
	(arc
		(start 153.2509 -39.215568)
		(mid 153.225978 -39.1554)
		(end 153.16581 -39.130478)
		(width 0.15748)
		(layer "In7.Cu")
		(net "CONN_MICRO_USB_DM")
	)
	(arc
		(start 157.84576 -52.725828)
		(mid 157.869938 -52.667456)
		(end 157.92831 -52.643278)
		(width 0.15748)
		(layer "In7.Cu")
		(net "CONN_MICRO_USB_DM")
	)
	(arc
		(start 146.9771 -24.10968)
		(mid 146.44289 -23.72229)
		(end 145.814796 -23.519892)
		(width 0.15748)
		(layer "In7.Cu")
		(net "CONN_MICRO_USB_DM")
	)
	(arc
		(start 156.412946 -46.751748)
		(mid 156.438407 -46.69028)
		(end 156.412946 -46.628812)
		(width 0.15748)
		(layer "In7.Cu")
		(net "CONN_MICRO_USB_DM")
	)
	(arc
		(start 158.52648 -56.2229)
		(mid 158.474663 -55.9624)
		(end 158.32709 -55.74157)
		(width 0.15748)
		(layer "In7.Cu")
		(net "CONN_MICRO_USB_DM")
	)
	(arc
		(start 157.92831 -53.273198)
		(mid 157.869938 -53.24902)
		(end 157.84576 -53.190648)
		(width 0.15748)
		(layer "In7.Cu")
		(net "CONN_MICRO_USB_DM")
	)
	(arc
		(start 157.92831 -50.123598)
		(mid 157.986682 -50.09942)
		(end 158.01086 -50.041048)
		(width 0.15748)
		(layer "In7.Cu")
		(net "CONN_MICRO_USB_DM")
	)
	(arc
		(start 153.16581 -40.390318)
		(mid 153.105642 -40.365396)
		(end 153.08072 -40.305228)
		(width 0.15748)
		(layer "In7.Cu")
		(net "CONN_MICRO_USB_DM")
	)
	(arc
		(start 156.412946 -46.874684)
		(mid 156.387485 -46.813216)
		(end 156.412946 -46.751748)
		(width 0.15748)
		(layer "In7.Cu")
		(net "CONN_MICRO_USB_DM")
	)
	(arc
		(start 157.92831 -52.013358)
		(mid 157.869938 -51.98918)
		(end 157.84576 -51.930808)
		(width 0.15748)
		(layer "In7.Cu")
		(net "CONN_MICRO_USB_DM")
	)
	(arc
		(start 157.92831 -50.753518)
		(mid 157.869938 -50.72934)
		(end 157.84576 -50.670968)
		(width 0.15748)
		(layer "In7.Cu")
		(net "CONN_MICRO_USB_DM")
	)
	(arc
		(start 153.2509 -35.120834)
		(mid 152.922162 -33.468338)
		(end 151.98598 -32.0675)
		(width 0.15748)
		(layer "In7.Cu")
		(net "CONN_MICRO_USB_DM")
	)
	(arc
		(start 145.814796 -23.519892)
		(mid 145.736544 -23.510781)
		(end 145.657824 -23.5077)
		(width 0.15748)
		(layer "In7.Cu")
		(net "CONN_MICRO_USB_DM")
	)
	(arc
		(start 158.193994 -57.257696)
		(mid 158.429097 -57.160313)
		(end 158.52648 -56.92521)
		(width 0.15748)
		(layer "In7.Cu")
		(net "CONN_MICRO_USB_DM")
	)
	(arc
		(start 155.96743 -46.306232)
		(mid 155.905962 -46.331693)
		(end 155.844494 -46.306232)
		(width 0.15748)
		(layer "In7.Cu")
		(net "CONN_MICRO_USB_DM")
	)
	(arc
		(start 93.337888 -20.093432)
		(mid 92.8262 -20.859322)
		(end 92.6465 -21.76272)
		(width 0.15748)
		(layer "In7.Cu")
		(net "CONN_MICRO_USB_DM")
	)
	(arc
		(start 153.16581 -37.240718)
		(mid 153.225978 -37.215796)
		(end 153.2509 -37.155628)
		(width 0.15748)
		(layer "In7.Cu")
		(net "CONN_MICRO_USB_DM")
	)
	(arc
		(start 155.521914 -45.983652)
		(mid 155.496453 -45.922184)
		(end 155.521914 -45.860716)
		(width 0.15748)
		(layer "In7.Cu")
		(net "CONN_MICRO_USB_DM")
	)
	(arc
		(start 155.199334 -45.4152)
		(mid 155.137866 -45.389739)
		(end 155.076398 -45.4152)
		(width 0.15748)
		(layer "In7.Cu")
		(net "CONN_MICRO_USB_DM")
	)
	(arc
		(start 153.08072 -37.325808)
		(mid 153.105642 -37.26564)
		(end 153.16581 -37.240718)
		(width 0.15748)
		(layer "In7.Cu")
		(net "CONN_MICRO_USB_DM")
	)
	(arc
		(start 153.994358 -44.210478)
		(mid 153.444096 -43.387048)
		(end 153.2509 -42.415714)
		(width 0.15748)
		(layer "In7.Cu")
		(net "CONN_MICRO_USB_DM")
	)
	(arc
		(start 96.658176 -17.72666)
		(mid 95.777321 -17.901855)
		(end 95.030544 -18.400776)
		(width 0.15748)
		(layer "In7.Cu")
		(net "CONN_MICRO_USB_DM")
	)
	(arc
		(start 153.2509 -37.955728)
		(mid 153.225978 -37.89556)
		(end 153.16581 -37.870638)
		(width 0.15748)
		(layer "In7.Cu")
		(net "CONN_MICRO_USB_DM")
	)
	(arc
		(start 157.92831 -52.643278)
		(mid 157.986682 -52.6191)
		(end 158.01086 -52.560728)
		(width 0.15748)
		(layer "In7.Cu")
		(net "CONN_MICRO_USB_DM")
	)
	(arc
		(start 157.481524 -57.027826)
		(mid 157.736156 -57.197965)
		(end 158.036514 -57.257696)
		(width 0.15748)
		(layer "In7.Cu")
		(net "CONN_MICRO_USB_DM")
	)
	(arc
		(start 151.422608 -31.503874)
		(mid 150.905313 -30.729593)
		(end 150.7236 -29.816298)
		(width 0.15748)
		(layer "In7.Cu")
		(net "CONN_MICRO_USB_DM")
	)
	(arc
		(start 153.2509 -40.475408)
		(mid 153.225978 -40.41524)
		(end 153.16581 -40.390318)
		(width 0.15748)
		(layer "In7.Cu")
		(net "CONN_MICRO_USB_DM")
	)
	(arc
		(start 121.285 -18.59534)
		(mid 120.322761 -17.952392)
		(end 119.187722 -17.72666)
		(width 0.15748)
		(layer "In7.Cu")
		(net "CONN_MICRO_USB_DM")
	)
	(arc
		(start 155.521914 -45.860716)
		(mid 155.547375 -45.799248)
		(end 155.521914 -45.73778)
		(width 0.15748)
		(layer "In7.Cu")
		(net "CONN_MICRO_USB_DM")
	)
	(arc
		(start 157.84576 -50.206148)
		(mid 157.869938 -50.147776)
		(end 157.92831 -50.123598)
		(width 0.15748)
		(layer "In7.Cu")
		(net "CONN_MICRO_USB_DM")
	)
	(arc
		(start 150.7236 -28.64993)
		(mid 150.577545 -27.916223)
		(end 150.161752 -27.294332)
		(width 0.15748)
		(layer "In7.Cu")
		(net "CONN_MICRO_USB_DM")
	)
	(arc
		(start 158.01086 -50.836068)
		(mid 157.986682 -50.777696)
		(end 157.92831 -50.753518)
		(width 0.15748)
		(layer "In7.Cu")
		(net "CONN_MICRO_USB_DM")
	)
	(arc
		(start 158.01086 -48.801528)
		(mid 157.905177 -48.270224)
		(end 157.604206 -47.819818)
		(width 0.15748)
		(layer "In7.Cu")
		(net "CONN_MICRO_USB_DM")
	)
	(arc
		(start 157.92831 -51.383438)
		(mid 157.986682 -51.35926)
		(end 158.01086 -51.300888)
		(width 0.15748)
		(layer "In7.Cu")
		(net "CONN_MICRO_USB_DM")
	)
	(segment
		(start 83.7184 -54.953408)
		(end 83.120992 -54.356)
		(width 0.11938)
		(layer "F.Cu")
		(net "BNO080_SA0")
	)
	(segment
		(start 83.120992 -54.356)
		(end 81.915 -54.356)
		(width 0.11938)
		(layer "F.Cu")
		(net "BNO080_SA0")
	)
	(segment
		(start 81.915 -54.356)
		(end 81.3054 -54.9656)
		(width 0.11938)
		(layer "F.Cu")
		(net "BNO080_SA0")
	)
	(segment
		(start 83.7184 -54.991)
		(end 83.7184 -54.953408)
		(width 0.11938)
		(layer "F.Cu")
		(net "BNO080_SA0")
	)
	(segment
		(start 84.9249 -54.2417)
		(end 84.4677 -54.2417)
		(width 0.11938)
		(layer "F.Cu")
		(net "BNO080_SA0")
	)
	(segment
		(start 84.4677 -54.2417)
		(end 83.7184 -54.991)
		(width 0.11938)
		(layer "F.Cu")
		(net "BNO080_SA0")
	)
	(segment
		(start 85.856064 -56.463184)
		(end 85.856064 -55.172864)
		(width 0.11938)
		(layer "F.Cu")
		(net "BNO080_SA0")
	)
	(segment
		(start 85.856064 -55.172864)
		(end 84.9249 -54.2417)
		(width 0.11938)
		(layer "F.Cu")
		(net "BNO080_SA0")
	)
	(via
		(at 84.4677 -54.2417)
		(size 0.508)
		(drill 0.254)
		(layers "F.Cu" "B.Cu")
		(net "BNO080_SA0")
	)
	(segment
		(start 85.128862 -55.34025)
		(end 85.355938 -55.567326)
		(width 0.11938)
		(layer "F.Cu")
		(net "R_BNO080_EVN_SDA")
	)
	(segment
		(start 85.355938 -55.567326)
		(end 85.355938 -56.463184)
		(width 0.11938)
		(layer "F.Cu")
		(net "R_BNO080_EVN_SDA")
	)
	(via
		(at 87.376 -74.93)
		(size 0.4572)
		(drill 0.2032)
		(layers "F.Cu" "B.Cu")
		(net "R_BNO080_EVN_SDA")
	)
	(via
		(at 85.128862 -55.34025)
		(size 0.508)
		(drill 0.254)
		(layers "F.Cu" "B.Cu")
		(net "R_BNO080_EVN_SDA")
	)
	(segment
		(start 87.376 -73.8124)
		(end 87.376 -74.93)
		(width 0.11938)
		(layer "B.Cu")
		(net "R_BNO080_EVN_SDA")
	)
	(segment
		(start 85.598 -72.644)
		(end 87.376 -74.422)
		(width 0.127)
		(layer "In2.Cu")
		(net "R_BNO080_EVN_SDA")
	)
	(segment
		(start 85.128862 -55.34025)
		(end 83.319112 -57.15)
		(width 0.127)
		(layer "In2.Cu")
		(net "R_BNO080_EVN_SDA")
	)
	(segment
		(start 83.319112 -57.15)
		(end 81.998566 -57.15)
		(width 0.127)
		(layer "In2.Cu")
		(net "R_BNO080_EVN_SDA")
	)
	(segment
		(start 81.4705 -66.51244)
		(end 81.4705 -67.1195)
		(width 0.127)
		(layer "In2.Cu")
		(net "R_BNO080_EVN_SDA")
	)
	(segment
		(start 81.661 -66.32194)
		(end 81.4705 -66.51244)
		(width 0.127)
		(layer "In2.Cu")
		(net "R_BNO080_EVN_SDA")
	)
	(segment
		(start 85.598 -71.247)
		(end 85.598 -72.644)
		(width 0.127)
		(layer "In2.Cu")
		(net "R_BNO080_EVN_SDA")
	)
	(segment
		(start 81.998566 -57.15)
		(end 81.661 -57.487566)
		(width 0.127)
		(layer "In2.Cu")
		(net "R_BNO080_EVN_SDA")
	)
	(segment
		(start 87.376 -74.422)
		(end 87.376 -74.93)
		(width 0.127)
		(layer "In2.Cu")
		(net "R_BNO080_EVN_SDA")
	)
	(segment
		(start 81.4705 -67.1195)
		(end 85.598 -71.247)
		(width 0.127)
		(layer "In2.Cu")
		(net "R_BNO080_EVN_SDA")
	)
	(segment
		(start 81.661 -57.487566)
		(end 81.661 -66.32194)
		(width 0.127)
		(layer "In2.Cu")
		(net "R_BNO080_EVN_SDA")
	)
	(segment
		(start 83.537552 -56.525668)
		(end 84.543392 -56.525668)
		(width 0.11938)
		(layer "F.Cu")
		(net "R_BNO080_EVN_SCL")
	)
	(segment
		(start 83.292442 -56.280558)
		(end 83.537552 -56.525668)
		(width 0.11938)
		(layer "F.Cu")
		(net "R_BNO080_EVN_SCL")
	)
	(via
		(at 84.9249 -71.628)
		(size 0.4572)
		(drill 0.2032)
		(layers "F.Cu" "B.Cu")
		(net "R_BNO080_EVN_SCL")
	)
	(via
		(at 83.292442 -56.280558)
		(size 0.508)
		(drill 0.254)
		(layers "F.Cu" "B.Cu")
		(net "R_BNO080_EVN_SCL")
	)
	(segment
		(start 85.09 -71.7931)
		(end 84.9249 -71.628)
		(width 0.11938)
		(layer "B.Cu")
		(net "R_BNO080_EVN_SCL")
	)
	(segment
		(start 85.09 -72.7456)
		(end 85.09 -71.7931)
		(width 0.11938)
		(layer "B.Cu")
		(net "R_BNO080_EVN_SCL")
	)
	(segment
		(start 80.9625 -66.301874)
		(end 81.153 -66.111374)
		(width 0.127)
		(layer "In2.Cu")
		(net "R_BNO080_EVN_SCL")
	)
	(segment
		(start 83.78825 -70.506082)
		(end 82.888836 -71.405496)
		(width 0.127)
		(layer "In2.Cu")
		(net "R_BNO080_EVN_SCL")
	)
	(segment
		(start 81.81086 -70.507352)
		(end 81.54162 -70.238112)
		(width 0.127)
		(layer "In2.Cu")
		(net "R_BNO080_EVN_SCL")
	)
	(segment
		(start 83.339178 -70.05701)
		(end 83.339178 -69.877178)
		(width 0.127)
		(layer "In2.Cu")
		(net "R_BNO080_EVN_SCL")
	)
	(segment
		(start 82.439764 -71.136256)
		(end 82.439764 -70.956424)
		(width 0.127)
		(layer "In2.Cu")
		(net "R_BNO080_EVN_SCL")
	)
	(segment
		(start 80.643476 -69.160136)
		(end 81.54289 -68.260722)
		(width 0.127)
		(layer "In2.Cu")
		(net "R_BNO080_EVN_SCL")
	)
	(segment
		(start 81.153 -57.277)
		(end 81.788 -56.642)
		(width 0.127)
		(layer "In2.Cu")
		(net "R_BNO080_EVN_SCL")
	)
	(segment
		(start 82.890106 -69.607938)
		(end 81.990692 -70.507352)
		(width 0.127)
		(layer "In2.Cu")
		(net "R_BNO080_EVN_SCL")
	)
	(segment
		(start 80.912716 -69.609208)
		(end 80.643476 -69.339968)
		(width 0.127)
		(layer "In2.Cu")
		(net "R_BNO080_EVN_SCL")
	)
	(segment
		(start 83.069938 -69.607938)
		(end 82.890106 -69.607938)
		(width 0.127)
		(layer "In2.Cu")
		(net "R_BNO080_EVN_SCL")
	)
	(segment
		(start 81.54289 -68.260722)
		(end 81.54289 -68.08089)
		(width 0.127)
		(layer "In2.Cu")
		(net "R_BNO080_EVN_SCL")
	)
	(segment
		(start 81.990692 -70.507352)
		(end 81.81086 -70.507352)
		(width 0.127)
		(layer "In2.Cu")
		(net "R_BNO080_EVN_SCL")
	)
	(segment
		(start 82.441034 -68.979034)
		(end 82.171794 -68.709794)
		(width 0.127)
		(layer "In2.Cu")
		(net "R_BNO080_EVN_SCL")
	)
	(segment
		(start 82.441034 -69.158866)
		(end 82.441034 -68.979034)
		(width 0.127)
		(layer "In2.Cu")
		(net "R_BNO080_EVN_SCL")
	)
	(segment
		(start 84.9249 -71.628)
		(end 84.9249 -71.4629)
		(width 0.127)
		(layer "In2.Cu")
		(net "R_BNO080_EVN_SCL")
	)
	(segment
		(start 80.643476 -69.339968)
		(end 80.643476 -69.160136)
		(width 0.127)
		(layer "In2.Cu")
		(net "R_BNO080_EVN_SCL")
	)
	(segment
		(start 82.888836 -71.405496)
		(end 82.709004 -71.405496)
		(width 0.127)
		(layer "In2.Cu")
		(net "R_BNO080_EVN_SCL")
	)
	(segment
		(start 82.931 -56.642)
		(end 83.292442 -56.280558)
		(width 0.127)
		(layer "In2.Cu")
		(net "R_BNO080_EVN_SCL")
	)
	(segment
		(start 82.439764 -70.956424)
		(end 83.339178 -70.05701)
		(width 0.127)
		(layer "In2.Cu")
		(net "R_BNO080_EVN_SCL")
	)
	(segment
		(start 81.788 -56.642)
		(end 82.931 -56.642)
		(width 0.127)
		(layer "In2.Cu")
		(net "R_BNO080_EVN_SCL")
	)
	(segment
		(start 80.9625 -67.5005)
		(end 80.9625 -66.301874)
		(width 0.127)
		(layer "In2.Cu")
		(net "R_BNO080_EVN_SCL")
	)
	(segment
		(start 82.709004 -71.405496)
		(end 82.439764 -71.136256)
		(width 0.127)
		(layer "In2.Cu")
		(net "R_BNO080_EVN_SCL")
	)
	(segment
		(start 84.9249 -71.4629)
		(end 83.968082 -70.506082)
		(width 0.127)
		(layer "In2.Cu")
		(net "R_BNO080_EVN_SCL")
	)
	(segment
		(start 83.968082 -70.506082)
		(end 83.78825 -70.506082)
		(width 0.127)
		(layer "In2.Cu")
		(net "R_BNO080_EVN_SCL")
	)
	(segment
		(start 82.171794 -68.709794)
		(end 81.991962 -68.709794)
		(width 0.127)
		(layer "In2.Cu")
		(net "R_BNO080_EVN_SCL")
	)
	(segment
		(start 81.153 -66.111374)
		(end 81.153 -57.277)
		(width 0.127)
		(layer "In2.Cu")
		(net "R_BNO080_EVN_SCL")
	)
	(segment
		(start 81.54289 -68.08089)
		(end 80.9625 -67.5005)
		(width 0.127)
		(layer "In2.Cu")
		(net "R_BNO080_EVN_SCL")
	)
	(segment
		(start 81.54162 -70.05828)
		(end 82.441034 -69.158866)
		(width 0.127)
		(layer "In2.Cu")
		(net "R_BNO080_EVN_SCL")
	)
	(segment
		(start 81.092548 -69.609208)
		(end 80.912716 -69.609208)
		(width 0.127)
		(layer "In2.Cu")
		(net "R_BNO080_EVN_SCL")
	)
	(segment
		(start 83.339178 -69.877178)
		(end 83.069938 -69.607938)
		(width 0.127)
		(layer "In2.Cu")
		(net "R_BNO080_EVN_SCL")
	)
	(segment
		(start 81.991962 -68.709794)
		(end 81.092548 -69.609208)
		(width 0.127)
		(layer "In2.Cu")
		(net "R_BNO080_EVN_SCL")
	)
	(segment
		(start 81.54162 -70.238112)
		(end 81.54162 -70.05828)
		(width 0.127)
		(layer "In2.Cu")
		(net "R_BNO080_EVN_SCL")
	)
	(segment
		(start 113.284 -74.676)
		(end 113.284 -74.319638)
		(width 0.11938)
		(layer "F.Cu")
		(net "XP3R3V_FPGA_SR")
	)
	(segment
		(start 113.767362 -74.803)
		(end 113.640362 -74.676)
		(width 0.11938)
		(layer "F.Cu")
		(net "XP3R3V_FPGA_SR")
	)
	(segment
		(start 112.764824 -73.800462)
		(end 112.26165 -73.800462)
		(width 0.11938)
		(layer "F.Cu")
		(net "XP3R3V_FPGA_SR")
	)
	(segment
		(start 113.640362 -74.676)
		(end 113.284 -74.676)
		(width 0.11938)
		(layer "F.Cu")
		(net "XP3R3V_FPGA_SR")
	)
	(segment
		(start 113.284 -74.319638)
		(end 112.764824 -73.800462)
		(width 0.11938)
		(layer "F.Cu")
		(net "XP3R3V_FPGA_SR")
	)
	(segment
		(start 114.9096 -74.803)
		(end 113.767362 -74.803)
		(width 0.11938)
		(layer "F.Cu")
		(net "XP3R3V_FPGA_SR")
	)
	(via
		(at 113.284 -74.676)
		(size 0.508)
		(drill 0.254)
		(layers "F.Cu" "B.Cu")
		(net "XP3R3V_FPGA_SR")
	)
	(segment
		(start 114.9096 -72.263)
		(end 113.919 -72.263)
		(width 0.11938)
		(layer "F.Cu")
		(net "XP3R3V_FPGA_EN_R")
	)
	(segment
		(start 113.119662 -72.300338)
		(end 112.26165 -72.300338)
		(width 0.11938)
		(layer "F.Cu")
		(net "XP3R3V_FPGA_EN_R")
	)
	(segment
		(start 113.538 -71.882)
		(end 113.119662 -72.300338)
		(width 0.11938)
		(layer "F.Cu")
		(net "XP3R3V_FPGA_EN_R")
	)
	(segment
		(start 113.919 -72.263)
		(end 113.538 -71.882)
		(width 0.11938)
		(layer "F.Cu")
		(net "XP3R3V_FPGA_EN_R")
	)
	(via
		(at 113.538 -71.882)
		(size 0.508)
		(drill 0.254)
		(layers "F.Cu" "B.Cu")
		(net "XP3R3V_FPGA_EN_R")
	)
	(segment
		(start 114.9096 -72.263)
		(end 114.9096 -70.993)
		(width 0.11938)
		(layer "B.Cu")
		(net "XP3R3V_FPGA_EN_R")
	)
	(segment
		(start 114.9096 -74.803)
		(end 114.9096 -73.533)
		(width 0.11938)
		(layer "B.Cu")
		(net "XP3R3V_FPGA_EN_R")
	)
	(segment
		(start 113.919 -72.263)
		(end 114.9096 -72.263)
		(width 0.11938)
		(layer "B.Cu")
		(net "XP3R3V_FPGA_EN_R")
	)
	(segment
		(start 114.9096 -72.263)
		(end 114.9096 -73.533)
		(width 0.11938)
		(layer "B.Cu")
		(net "XP3R3V_FPGA_EN_R")
	)
	(segment
		(start 113.538 -71.882)
		(end 113.919 -72.263)
		(width 0.11938)
		(layer "B.Cu")
		(net "XP3R3V_FPGA_EN_R")
	)
	(segment
		(start 101.847142 -50.823114)
		(end 101.34727 -51.322986)
		(width 0.381)
		(layer "F.Cu")
		(net "XP3R3V_FPGA")
	)
	(segment
		(start 73.6854 -15.7734)
		(end 75.057 -15.7734)
		(width 0.3048)
		(layer "F.Cu")
		(net "XP3R3V_FPGA")
	)
	(segment
		(start 82.296 -56.0705)
		(end 82.2325 -56.0705)
		(width 0.381)
		(layer "F.Cu")
		(net "XP3R3V_FPGA")
	)
	(segment
		(start 15.3924 -43.662854)
		(end 14.649704 -44.40555)
		(width 0.254)
		(layer "F.Cu")
		(net "XP3R3V_FPGA")
	)
	(segment
		(start 55.20436 -77.89164)
		(end 56.3372 -76.7588)
		(width 0.381)
		(layer "F.Cu")
		(net "XP3R3V_FPGA")
	)
	(segment
		(start 134.112 -17.526)
		(end 134.112 -18.10512)
		(width 0.381)
		(layer "F.Cu")
		(net "XP3R3V_FPGA")
	)
	(segment
		(start 40.96258 -14.986)
		(end 42.21988 -14.986)
		(width 0.381)
		(layer "F.Cu")
		(net "XP3R3V_FPGA")
	)
	(segment
		(start 27.9019 -15.19174)
		(end 27.1907 -15.90294)
		(width 0.381)
		(layer "F.Cu")
		(net "XP3R3V_FPGA")
	)
	(segment
		(start 111.847122 -50.823114)
		(end 112.346994 -51.322986)
		(width 0.381)
		(layer "F.Cu")
		(net "XP3R3V_FPGA")
	)
	(segment
		(start 15.1384 -15.2908)
		(end 15.1384 -15.3416)
		(width 0.254)
		(layer "F.Cu")
		(net "XP3R3V_FPGA")
	)
	(segment
		(start 88.6714 -65.8876)
		(end 88.519 -66.04)
		(width 0.381)
		(layer "F.Cu")
		(net "XP3R3V_FPGA")
	)
	(segment
		(start 82.1944 -56.1086)
		(end 81.3054 -56.1086)
		(width 0.381)
		(layer "F.Cu")
		(net "XP3R3V_FPGA")
	)
	(segment
		(start 96.5454 -64.8208)
		(end 98.044 -64.8208)
		(width 0.381)
		(layer "F.Cu")
		(net "XP3R3V_FPGA")
	)
	(segment
		(start 14.649704 -59.909964)
		(end 14.649704 -59.645296)
		(width 0.254)
		(layer "F.Cu")
		(net "XP3R3V_FPGA")
	)
	(segment
		(start 88.519254 -47.56277)
		(end 88.519254 -47.850298)
		(width 0.2032)
		(layer "F.Cu")
		(net "XP3R3V_FPGA")
	)
	(segment
		(start 15.1384 -15.3416)
		(end 14.649704 -15.830296)
		(width 0.254)
		(layer "F.Cu")
		(net "XP3R3V_FPGA")
	)
	(segment
		(start 88.722454 -48.053498)
		(end 89.05113 -48.053498)
		(width 0.2032)
		(layer "F.Cu")
		(net "XP3R3V_FPGA")
	)
	(segment
		(start 118.237 -19.939)
		(end 118.237 -20.9804)
		(width 0.381)
		(layer "F.Cu")
		(net "XP3R3V_FPGA")
	)
	(segment
		(start 20.660106 -19.948906)
		(end 20.8534 -20.1422)
		(width 0.381)
		(layer "F.Cu")
		(net "XP3R3V_FPGA")
	)
	(segment
		(start 106.847132 -45.823124)
		(end 106.34726 -46.322996)
		(width 0.381)
		(layer "F.Cu")
		(net "XP3R3V_FPGA")
	)
	(segment
		(start 35.5854 -80.1116)
		(end 36.5506 -81.0768)
		(width 0.381)
		(layer "F.Cu")
		(net "XP3R3V_FPGA")
	)
	(segment
		(start 49.7586 -83.5406)
		(end 49.7586 -84.455)
		(width 0.381)
		(layer "F.Cu")
		(net "XP3R3V_FPGA")
	)
	(segment
		(start 155.956 -58.9534)
		(end 155.8798 -59.0296)
		(width 0.4572)
		(layer "F.Cu")
		(net "XP3R3V_FPGA")
	)
	(segment
		(start 14.732 -37.973)
		(end 15.367 -38.608)
		(width 0.254)
		(layer "F.Cu")
		(net "XP3R3V_FPGA")
	)
	(segment
		(start 125.349 -88.265)
		(end 125.73 -87.884)
		(width 0.381)
		(layer "F.Cu")
		(net "XP3R3V_FPGA")
	)
	(segment
		(start 90.424 -66.04)
		(end 89.535 -66.04)
		(width 0.381)
		(layer "F.Cu")
		(net "XP3R3V_FPGA")
	)
	(segment
		(start 101.0412 -64.8208)
		(end 102.5398 -64.8208)
		(width 0.381)
		(layer "F.Cu")
		(net "XP3R3V_FPGA")
	)
	(segment
		(start 80.2386 -60.6806)
		(end 80.2386 -61.8236)
		(width 0.381)
		(layer "F.Cu")
		(net "XP3R3V_FPGA")
	)
	(segment
		(start 119.2276 -19.939)
		(end 118.237 -19.939)
		(width 0.381)
		(layer "F.Cu")
		(net "XP3R3V_FPGA")
	)
	(segment
		(start 107.84713 -52.82311)
		(end 107.347258 -53.322982)
		(width 0.381)
		(layer "F.Cu")
		(net "XP3R3V_FPGA")
	)
	(segment
		(start 13.86586 -67.78498)
		(end 14.6812 -66.96964)
		(width 0.381)
		(layer "F.Cu")
		(net "XP3R3V_FPGA")
	)
	(segment
		(start 105.41 -64.8208)
		(end 106.9086 -64.8208)
		(width 0.381)
		(layer "F.Cu")
		(net "XP3R3V_FPGA")
	)
	(segment
		(start 79.3496 -41.783)
		(end 78.486 -41.783)
		(width 0.381)
		(layer "F.Cu")
		(net "XP3R3V_FPGA")
	)
	(segment
		(start 14.649704 -29.696664)
		(end 14.649704 -30.909768)
		(width 0.3048)
		(layer "F.Cu")
		(net "XP3R3V_FPGA")
	)
	(segment
		(start 159.1437 -27.51836)
		(end 159.72536 -27.51836)
		(width 0.381)
		(layer "F.Cu")
		(net "XP3R3V_FPGA")
	)
	(segment
		(start 15.875 -28.6004)
		(end 15.875 -29.718)
		(width 0.381)
		(layer "F.Cu")
		(net "XP3R3V_FPGA")
	)
	(segment
		(start 152.2603 -32.274002)
		(end 150.368 -32.274002)
		(width 0.381)
		(layer "F.Cu")
		(net "XP3R3V_FPGA")
	)
	(segment
		(start 114.5286 -83.058)
		(end 114.5286 -84.0486)
		(width 0.381)
		(layer "F.Cu")
		(net "XP3R3V_FPGA")
	)
	(segment
		(start 109.847126 -46.823122)
		(end 110.346998 -47.322994)
		(width 0.381)
		(layer "F.Cu")
		(net "XP3R3V_FPGA")
	)
	(segment
		(start 16.256 -58.039)
		(end 16.256 -57.6834)
		(width 0.254)
		(layer "F.Cu")
		(net "XP3R3V_FPGA")
	)
	(segment
		(start 40.1701 -15.77848)
		(end 40.96258 -14.986)
		(width 0.381)
		(layer "F.Cu")
		(net "XP3R3V_FPGA")
	)
	(segment
		(start 107.67314 -100.896674)
		(end 109.542326 -100.896674)
		(width 0.254)
		(layer "F.Cu")
		(net "XP3R3V_FPGA")
	)
	(segment
		(start 103.9622 -64.8208)
		(end 105.41 -64.8208)
		(width 0.381)
		(layer "F.Cu")
		(net "XP3R3V_FPGA")
	)
	(segment
		(start 117.84711 -52.82311)
		(end 118.346982 -53.322982)
		(width 0.381)
		(layer "F.Cu")
		(net "XP3R3V_FPGA")
	)
	(segment
		(start 73.441814 -16.016986)
		(end 73.6854 -15.7734)
		(width 0.3048)
		(layer "F.Cu")
		(net "XP3R3V_FPGA")
	)
	(segment
		(start 57.0738 -76.6572)
		(end 57.023 -76.708)
		(width 0.381)
		(layer "F.Cu")
		(net "XP3R3V_FPGA")
	)
	(segment
		(start 113.847118 -54.823106)
		(end 114.34699 -55.322978)
		(width 0.381)
		(layer "F.Cu")
		(net "XP3R3V_FPGA")
	)
	(segment
		(start 57.912 -19.05)
		(end 58.039 -19.177)
		(width 0.381)
		(layer "F.Cu")
		(net "XP3R3V_FPGA")
	)
	(segment
		(start 39.3192 -15.22222)
		(end 38.93058 -14.8336)
		(width 0.381)
		(layer "F.Cu")
		(net "XP3R3V_FPGA")
	)
	(segment
		(start 113.171478 -82.437478)
		(end 111.9759 -82.437478)
		(width 0.381)
		(layer "F.Cu")
		(net "XP3R3V_FPGA")
	)
	(segment
		(start 82.296 -56.007)
		(end 82.296 -56.0705)
		(width 0.381)
		(layer "F.Cu")
		(net "XP3R3V_FPGA")
	)
	(segment
		(start 155.9814 -60.0456)
		(end 155.9814 -58.9788)
		(width 0.4572)
		(layer "F.Cu")
		(net "XP3R3V_FPGA")
	)
	(segment
		(start 103.847138 -54.823106)
		(end 103.347266 -55.322978)
		(width 0.381)
		(layer "F.Cu")
		(net "XP3R3V_FPGA")
	)
	(segment
		(start 109.717078 -95.620078)
		(end 110.363 -96.266)
		(width 0.381)
		(layer "F.Cu")
		(net "XP3R3V_FPGA")
	)
	(segment
		(start 126.238 -44.45)
		(end 126.238 -43.434)
		(width 0.381)
		(layer "F.Cu")
		(net "XP3R3V_FPGA")
	)
	(segment
		(start 115.847114 -48.823118)
		(end 116.346986 -49.32299)
		(width 0.381)
		(layer "F.Cu")
		(net "XP3R3V_FPGA")
	)
	(segment
		(start 14.649704 -59.645296)
		(end 16.256 -58.039)
		(width 0.254)
		(layer "F.Cu")
		(net "XP3R3V_FPGA")
	)
	(segment
		(start 114.427 -93.599)
		(end 114.046 -93.98)
		(width 0.381)
		(layer "F.Cu")
		(net "XP3R3V_FPGA")
	)
	(segment
		(start 14.605 -53.1114)
		(end 14.605 -54.102)
		(width 0.254)
		(layer "F.Cu")
		(net "XP3R3V_FPGA")
	)
	(segment
		(start 114.5286 -83.058)
		(end 113.792 -83.058)
		(width 0.381)
		(layer "F.Cu")
		(net "XP3R3V_FPGA")
	)
	(segment
		(start 133.731 -17.145)
		(end 134.112 -17.526)
		(width 0.381)
		(layer "F.Cu")
		(net "XP3R3V_FPGA")
	)
	(segment
		(start 133.3246 -23.368)
		(end 131.0386 -23.368)
		(width 0.381)
		(layer "F.Cu")
		(net "XP3R3V_FPGA")
	)
	(segment
		(start 114.046 -93.98)
		(end 112.4204 -93.98)
		(width 0.381)
		(layer "F.Cu")
		(net "XP3R3V_FPGA")
	)
	(segment
		(start 57.6326 -18.8214)
		(end 57.8612 -19.05)
		(width 0.381)
		(layer "F.Cu")
		(net "XP3R3V_FPGA")
	)
	(segment
		(start 15.875 -28.6004)
		(end 15.745968 -28.6004)
		(width 0.3048)
		(layer "F.Cu")
		(net "XP3R3V_FPGA")
	)
	(segment
		(start 104.847136 -51.823112)
		(end 104.347264 -52.322984)
		(width 0.381)
		(layer "F.Cu")
		(net "XP3R3V_FPGA")
	)
	(segment
		(start 14.732 -37.7444)
		(end 14.732 -37.973)
		(width 0.254)
		(layer "F.Cu")
		(net "XP3R3V_FPGA")
	)
	(segment
		(start 119.847106 -46.823122)
		(end 120.346978 -47.322994)
		(width 0.381)
		(layer "F.Cu")
		(net "XP3R3V_FPGA")
	)
	(segment
		(start 114.847116 -51.823112)
		(end 115.346988 -52.322984)
		(width 0.381)
		(layer "F.Cu")
		(net "XP3R3V_FPGA")
	)
	(segment
		(start 54.0512 -74.4474)
		(end 55.1942 -74.4474)
		(width 0.381)
		(layer "F.Cu")
		(net "XP3R3V_FPGA")
	)
	(segment
		(start 82.6516 -54.991)
		(end 82.6516 -55.6514)
		(width 0.381)
		(layer "F.Cu")
		(net "XP3R3V_FPGA")
	)
	(segment
		(start 151.2824 -28.6004)
		(end 152.273 -29.591)
		(width 0.381)
		(layer "F.Cu")
		(net "XP3R3V_FPGA")
	)
	(segment
		(start 72.3392 -16.016986)
		(end 73.441814 -16.016986)
		(width 0.3048)
		(layer "F.Cu")
		(net "XP3R3V_FPGA")
	)
	(segment
		(start 95.504 -60.5536)
		(end 96.1644 -60.5536)
		(width 0.381)
		(layer "F.Cu")
		(net "XP3R3V_FPGA")
	)
	(segment
		(start 90.85072 -69.03212)
		(end 92.63888 -69.03212)
		(width 0.381)
		(layer "F.Cu")
		(net "XP3R3V_FPGA")
	)
	(segment
		(start 15.3924 -42.91203)
		(end 16.36903 -42.91203)
		(width 0.381)
		(layer "F.Cu")
		(net "XP3R3V_FPGA")
	)
	(segment
		(start 2.096008 -38.675056)
		(end 2.861056 -38.675056)
		(width 0.381)
		(layer "F.Cu")
		(net "XP3R3V_FPGA")
	)
	(segment
		(start 52.7685 -17.2847)
		(end 54.3052 -18.8214)
		(width 0.381)
		(layer "F.Cu")
		(net "XP3R3V_FPGA")
	)
	(segment
		(start 106.9086 -64.8208)
		(end 106.9086 -65.786)
		(width 0.381)
		(layer "F.Cu")
		(net "XP3R3V_FPGA")
	)
	(segment
		(start 136.525 -77.216)
		(end 132.715 -77.216)
		(width 0.381)
		(layer "F.Cu")
		(net "XP3R3V_FPGA")
	)
	(segment
		(start 39.3192 -15.77848)
		(end 40.1701 -15.77848)
		(width 0.381)
		(layer "F.Cu")
		(net "XP3R3V_FPGA")
	)
	(segment
		(start 31.46044 -19.14144)
		(end 30.87878 -19.14144)
		(width 0.381)
		(layer "F.Cu")
		(net "XP3R3V_FPGA")
	)
	(segment
		(start 102.5398 -64.8208)
		(end 103.9622 -64.8208)
		(width 0.381)
		(layer "F.Cu")
		(net "XP3R3V_FPGA")
	)
	(segment
		(start 15.3924 -42.91203)
		(end 15.3924 -43.662854)
		(width 0.254)
		(layer "F.Cu")
		(net "XP3R3V_FPGA")
	)
	(segment
		(start 103.847138 -44.823126)
		(end 103.347266 -45.322998)
		(width 0.381)
		(layer "F.Cu")
		(net "XP3R3V_FPGA")
	)
	(segment
		(start 94.80804 -62.79896)
		(end 94.790514 -62.781434)
		(width 0.381)
		(layer "F.Cu")
		(net "XP3R3V_FPGA")
	)
	(segment
		(start 125.1204 -44.831)
		(end 125.857 -44.831)
		(width 0.381)
		(layer "F.Cu")
		(net "XP3R3V_FPGA")
	)
	(segment
		(start 116.847112 -45.823124)
		(end 117.346984 -46.322996)
		(width 0.381)
		(layer "F.Cu")
		(net "XP3R3V_FPGA")
	)
	(segment
		(start 106.045 -86.55304)
		(end 106.045 -85.598)
		(width 0.381)
		(layer "F.Cu")
		(net "XP3R3V_FPGA")
	)
	(segment
		(start 109.542326 -100.896674)
		(end 109.728 -100.711)
		(width 0.254)
		(layer "F.Cu")
		(net "XP3R3V_FPGA")
	)
	(segment
		(start 94.251526 -62.781434)
		(end 93.853 -63.17996)
		(width 0.381)
		(layer "F.Cu")
		(net "XP3R3V_FPGA")
	)
	(segment
		(start 150.2156 -24.511)
		(end 150.2156 -26.035)
		(width 0.381)
		(layer "F.Cu")
		(net "XP3R3V_FPGA")
	)
	(segment
		(start 94.80296 -62.80404)
		(end 94.80804 -62.79896)
		(width 0.381)
		(layer "F.Cu")
		(net "XP3R3V_FPGA")
	)
	(segment
		(start 155.9814 -58.9788)
		(end 155.956 -58.9534)
		(width 0.4572)
		(layer "F.Cu")
		(net "XP3R3V_FPGA")
	)
	(segment
		(start 110.363 -96.266)
		(end 111.3536 -96.266)
		(width 0.381)
		(layer "F.Cu")
		(net "XP3R3V_FPGA")
	)
	(segment
		(start 13.0556 -41.91)
		(end 13.0556 -41.0464)
		(width 0.381)
		(layer "F.Cu")
		(net "XP3R3V_FPGA")
	)
	(segment
		(start 90.0684 -64.897)
		(end 89.9414 -65.024)
		(width 0.381)
		(layer "F.Cu")
		(net "XP3R3V_FPGA")
	)
	(segment
		(start 52.01158 -17.21612)
		(end 52.08016 -17.2847)
		(width 0.381)
		(layer "F.Cu")
		(net "XP3R3V_FPGA")
	)
	(segment
		(start 2.096008 -67.674998)
		(end 3.038602 -67.674998)
		(width 0.381)
		(layer "F.Cu")
		(net "XP3R3V_FPGA")
	)
	(segment
		(start 92.63888 -69.03212)
		(end 92.837 -68.834)
		(width 0.381)
		(layer "F.Cu")
		(net "XP3R3V_FPGA")
	)
	(segment
		(start 126.238 -43.434)
		(end 126.6825 -42.9895)
		(width 0.381)
		(layer "F.Cu")
		(net "XP3R3V_FPGA")
	)
	(segment
		(start 116.205 -62.5094)
		(end 116.205 -63.5)
		(width 0.381)
		(layer "F.Cu")
		(net "XP3R3V_FPGA")
	)
	(segment
		(start 39.3192 -15.77848)
		(end 39.3192 -15.22222)
		(width 0.381)
		(layer "F.Cu")
		(net "XP3R3V_FPGA")
	)
	(segment
		(start 124.587 -55.0545)
		(end 125.1204 -54.5211)
		(width 0.381)
		(layer "F.Cu")
		(net "XP3R3V_FPGA")
	)
	(segment
		(start 90.9828 -71.1962)
		(end 90.9828 -72.5424)
		(width 0.381)
		(layer "F.Cu")
		(net "XP3R3V_FPGA")
	)
	(segment
		(start 118.237 -20.9804)
		(end 119.2276 -21.971)
		(width 0.381)
		(layer "F.Cu")
		(net "XP3R3V_FPGA")
	)
	(segment
		(start 98.044 -64.8208)
		(end 99.5426 -64.8208)
		(width 0.381)
		(layer "F.Cu")
		(net "XP3R3V_FPGA")
	)
	(segment
		(start 30.87878 -19.14144)
		(end 30.87878 -17.99844)
		(width 0.381)
		(layer "F.Cu")
		(net "XP3R3V_FPGA")
	)
	(segment
		(start 162.0266 -28.829)
		(end 162.0266 -29.6926)
		(width 0.381)
		(layer "F.Cu")
		(net "XP3R3V_FPGA")
	)
	(segment
		(start 29.81198 -15.58544)
		(end 28.67152 -15.58544)
		(width 0.381)
		(layer "F.Cu")
		(net "XP3R3V_FPGA")
	)
	(segment
		(start 80.2386 -61.8236)
		(end 79.2226 -61.8236)
		(width 0.381)
		(layer "F.Cu")
		(net "XP3R3V_FPGA")
	)
	(segment
		(start 82.6516 -55.6514)
		(end 82.296 -56.007)
		(width 0.381)
		(layer "F.Cu")
		(net "XP3R3V_FPGA")
	)
	(segment
		(start 112.84712 -47.82312)
		(end 113.346992 -48.322992)
		(width 0.381)
		(layer "F.Cu")
		(net "XP3R3V_FPGA")
	)
	(segment
		(start 94.790514 -62.781434)
		(end 94.251526 -62.781434)
		(width 0.381)
		(layer "F.Cu")
		(net "XP3R3V_FPGA")
	)
	(segment
		(start 2.096008 -82.175096)
		(end 3.041904 -82.175096)
		(width 0.381)
		(layer "F.Cu")
		(net "XP3R3V_FPGA")
	)
	(segment
		(start 13.068808 -56.7182)
		(end 13.068808 -55.8546)
		(width 0.3048)
		(layer "F.Cu")
		(net "XP3R3V_FPGA")
	)
	(segment
		(start 54.3052 -18.8214)
		(end 57.6326 -18.8214)
		(width 0.381)
		(layer "F.Cu")
		(net "XP3R3V_FPGA")
	)
	(segment
		(start 117.84711 -42.82313)
		(end 118.346982 -42.323258)
		(width 0.381)
		(layer "F.Cu")
		(net "XP3R3V_FPGA")
	)
	(segment
		(start 156.120592 -32.274002)
		(end 157.988 -32.274002)
		(width 0.381)
		(layer "F.Cu")
		(net "XP3R3V_FPGA")
	)
	(segment
		(start 148.59 -57.531)
		(end 149.2504 -56.8706)
		(width 0.381)
		(layer "F.Cu")
		(net "XP3R3V_FPGA")
	)
	(segment
		(start 27.1907 -15.90294)
		(end 27.1907 -16.60144)
		(width 0.381)
		(layer "F.Cu")
		(net "XP3R3V_FPGA")
	)
	(segment
		(start 16.256 -57.6834)
		(end 17.1196 -57.6834)
		(width 0.381)
		(layer "F.Cu")
		(net "XP3R3V_FPGA")
	)
	(segment
		(start 56.3372 -76.7588)
		(end 56.3372 -75.5142)
		(width 0.381)
		(layer "F.Cu")
		(net "XP3R3V_FPGA")
	)
	(segment
		(start 109.728 -100.711)
		(end 110.5916 -100.711)
		(width 0.381)
		(layer "F.Cu")
		(net "XP3R3V_FPGA")
	)
	(segment
		(start 125.1204 -54.5211)
		(end 125.1204 -53.721)
		(width 0.381)
		(layer "F.Cu")
		(net "XP3R3V_FPGA")
	)
	(segment
		(start 28.27782 -15.19174)
		(end 27.9019 -15.19174)
		(width 0.381)
		(layer "F.Cu")
		(net "XP3R3V_FPGA")
	)
	(segment
		(start 88.519254 -47.850298)
		(end 88.722454 -48.053498)
		(width 0.2032)
		(layer "F.Cu")
		(net "XP3R3V_FPGA")
	)
	(segment
		(start 94.80296 -63.8429)
		(end 94.80296 -62.80404)
		(width 0.381)
		(layer "F.Cu")
		(net "XP3R3V_FPGA")
	)
	(segment
		(start 134.3914 -20.828)
		(end 135.382 -20.828)
		(width 0.381)
		(layer "F.Cu")
		(net "XP3R3V_FPGA")
	)
	(segment
		(start 149.2504 -56.8706)
		(end 149.848062 -56.8706)
		(width 0.381)
		(layer "F.Cu")
		(net "XP3R3V_FPGA")
	)
	(segment
		(start 98.044 -64.8208)
		(end 98.044 -65.8495)
		(width 0.381)
		(layer "F.Cu")
		(net "XP3R3V_FPGA")
	)
	(segment
		(start 82.2325 -56.0705)
		(end 82.1944 -56.1086)
		(width 0.381)
		(layer "F.Cu")
		(net "XP3R3V_FPGA")
	)
	(segment
		(start 113.792 -83.058)
		(end 113.171478 -82.437478)
		(width 0.381)
		(layer "F.Cu")
		(net "XP3R3V_FPGA")
	)
	(segment
		(start 108.5723 -95.620078)
		(end 109.717078 -95.620078)
		(width 0.381)
		(layer "F.Cu")
		(net "XP3R3V_FPGA")
	)
	(segment
		(start 14.649704 -44.40555)
		(end 14.649704 -45.409866)
		(width 0.254)
		(layer "F.Cu")
		(net "XP3R3V_FPGA")
	)
	(segment
		(start 55.20436 -78.3463)
		(end 55.20436 -77.89164)
		(width 0.381)
		(layer "F.Cu")
		(net "XP3R3V_FPGA")
	)
	(segment
		(start 100.84689 -53.823108)
		(end 100.347018 -54.32298)
		(width 0.381)
		(layer "F.Cu")
		(net "XP3R3V_FPGA")
	)
	(segment
		(start 90.932 -66.421)
		(end 90.805 -66.421)
		(width 0.381)
		(layer "F.Cu")
		(net "XP3R3V_FPGA")
	)
	(segment
		(start 52.01158 -16.0528)
		(end 52.01158 -17.21612)
		(width 0.381)
		(layer "F.Cu")
		(net "XP3R3V_FPGA")
	)
	(segment
		(start 88.678512 -47.403512)
		(end 88.519254 -47.56277)
		(width 0.2032)
		(layer "F.Cu")
		(net "XP3R3V_FPGA")
	)
	(segment
		(start 75.06208 -15.77848)
		(end 75.057 -15.7734)
		(width 0.381)
		(layer "F.Cu")
		(net "XP3R3V_FPGA")
	)
	(segment
		(start 125.349 -89.0016)
		(end 125.349 -88.265)
		(width 0.381)
		(layer "F.Cu")
		(net "XP3R3V_FPGA")
	)
	(segment
		(start 111.3536 -96.266)
		(end 111.3536 -97.1296)
		(width 0.381)
		(layer "F.Cu")
		(net "XP3R3V_FPGA")
	)
	(segment
		(start 14.649704 -15.830296)
		(end 14.649704 -16.409924)
		(width 0.254)
		(layer "F.Cu")
		(net "XP3R3V_FPGA")
	)
	(segment
		(start 163.0934 -27.432)
		(end 163.0934 -25.908)
		(width 0.381)
		(layer "F.Cu")
		(net "XP3R3V_FPGA")
	)
	(segment
		(start 93.853 -63.17996)
		(end 93.853 -63.8429)
		(width 0.381)
		(layer "F.Cu")
		(net "XP3R3V_FPGA")
	)
	(segment
		(start 126.6825 -42.25544)
		(end 125.984 -41.55694)
		(width 0.381)
		(layer "F.Cu")
		(net "XP3R3V_FPGA")
	)
	(segment
		(start 132.715 -77.216)
		(end 131.826 -78.105)
		(width 0.381)
		(layer "F.Cu")
		(net "XP3R3V_FPGA")
	)
	(segment
		(start 99.5426 -64.8208)
		(end 101.0412 -64.8208)
		(width 0.381)
		(layer "F.Cu")
		(net "XP3R3V_FPGA")
	)
	(segment
		(start 150.876762 -47.54626)
		(end 150.876762 -47.498)
		(width 0.381)
		(layer "F.Cu")
		(net "XP3R3V_FPGA")
	)
	(segment
		(start 151.613108 -48.47971)
		(end 151.613108 -48.282606)
		(width 0.381)
		(layer "F.Cu")
		(net "XP3R3V_FPGA")
	)
	(segment
		(start 150.2156 -24.511)
		(end 149.352 -24.511)
		(width 0.381)
		(layer "F.Cu")
		(net "XP3R3V_FPGA")
	)
	(segment
		(start 108.847128 -49.823116)
		(end 108.347256 -50.322988)
		(width 0.381)
		(layer "F.Cu")
		(net "XP3R3V_FPGA")
	)
	(segment
		(start 15.745968 -28.6004)
		(end 14.649704 -29.696664)
		(width 0.3048)
		(layer "F.Cu")
		(net "XP3R3V_FPGA")
	)
	(segment
		(start 111.633 -62.5094)
		(end 111.633 -63.5)
		(width 0.381)
		(layer "F.Cu")
		(net "XP3R3V_FPGA")
	)
	(segment
		(start 84.709 -65.7606)
		(end 84.709 -64.8462)
		(width 0.381)
		(layer "F.Cu")
		(net "XP3R3V_FPGA")
	)
	(segment
		(start 126.6825 -42.9895)
		(end 126.6825 -42.25544)
		(width 0.381)
		(layer "F.Cu")
		(net "XP3R3V_FPGA")
	)
	(segment
		(start 20.660106 -17.9959)
		(end 20.660106 -19.948906)
		(width 0.381)
		(layer "F.Cu")
		(net "XP3R3V_FPGA")
	)
	(segment
		(start 86.7156 -77.3176)
		(end 86.7156 -82.169)
		(width 0.381)
		(layer "F.Cu")
		(net "XP3R3V_FPGA")
	)
	(segment
		(start 155.8798 -59.0296)
		(end 154.6098 -59.0296)
		(width 0.4572)
		(layer "F.Cu")
		(net "XP3R3V_FPGA")
	)
	(segment
		(start 134.112 -18.10512)
		(end 134.3914 -18.38452)
		(width 0.381)
		(layer "F.Cu")
		(net "XP3R3V_FPGA")
	)
	(segment
		(start 56.3372 -75.5142)
		(end 56.6928 -75.5142)
		(width 0.381)
		(layer "F.Cu")
		(net "XP3R3V_FPGA")
	)
	(segment
		(start 52.08016 -17.2847)
		(end 52.7685 -17.2847)
		(width 0.381)
		(layer "F.Cu")
		(net "XP3R3V_FPGA")
	)
	(segment
		(start 14.732 -24.257)
		(end 14.732 -23.5204)
		(width 0.381)
		(layer "F.Cu")
		(net "XP3R3V_FPGA")
	)
	(segment
		(start 90.9828 -72.5424)
		(end 90.1192 -72.5424)
		(width 0.381)
		(layer "F.Cu")
		(net "XP3R3V_FPGA")
	)
	(segment
		(start 111.6584 -98.171)
		(end 112.522 -98.171)
		(width 0.381)
		(layer "F.Cu")
		(net "XP3R3V_FPGA")
	)
	(segment
		(start 57.0738 -75.8952)
		(end 57.0738 -76.6572)
		(width 0.381)
		(layer "F.Cu")
		(net "XP3R3V_FPGA")
	)
	(segment
		(start 125.857 -44.831)
		(end 126.238 -44.45)
		(width 0.381)
		(layer "F.Cu")
		(net "XP3R3V_FPGA")
	)
	(segment
		(start 14.605 -54.102)
		(end 14.732 -54.229)
		(width 0.254)
		(layer "F.Cu")
		(net "XP3R3V_FPGA")
	)
	(segment
		(start 113.847118 -44.823126)
		(end 114.34699 -45.322998)
		(width 0.381)
		(layer "F.Cu")
		(net "XP3R3V_FPGA")
	)
	(segment
		(start 125.984 -41.55694)
		(end 125.984 -41.402)
		(width 0.381)
		(layer "F.Cu")
		(net "XP3R3V_FPGA")
	)
	(segment
		(start 159.72536 -27.51836)
		(end 161.036 -28.829)
		(width 0.381)
		(layer "F.Cu")
		(net "XP3R3V_FPGA")
	)
	(segment
		(start 110.847124 -53.823108)
		(end 111.346996 -54.32298)
		(width 0.381)
		(layer "F.Cu")
		(net "XP3R3V_FPGA")
	)
	(segment
		(start 52.9082 -74.4474)
		(end 54.0512 -74.4474)
		(width 0.381)
		(layer "F.Cu")
		(net "XP3R3V_FPGA")
	)
	(segment
		(start 134.3914 -18.38452)
		(end 134.3914 -19.304)
		(width 0.381)
		(layer "F.Cu")
		(net "XP3R3V_FPGA")
	)
	(segment
		(start 2.096008 -53.175154)
		(end 3.137154 -53.175154)
		(width 0.381)
		(layer "F.Cu")
		(net "XP3R3V_FPGA")
	)
	(segment
		(start 75.06208 -17.60728)
		(end 75.2856 -17.8308)
		(width 0.381)
		(layer "F.Cu")
		(net "XP3R3V_FPGA")
	)
	(segment
		(start 127.0254 -33.909)
		(end 128.0033 -33.909)
		(width 0.381)
		(layer "F.Cu")
		(net "XP3R3V_FPGA")
	)
	(segment
		(start 56.6928 -75.5142)
		(end 57.0738 -75.8952)
		(width 0.381)
		(layer "F.Cu")
		(net "XP3R3V_FPGA")
	)
	(segment
		(start 92.837 -68.834)
		(end 93.7006 -68.834)
		(width 0.381)
		(layer "F.Cu")
		(net "XP3R3V_FPGA")
	)
	(segment
		(start 101.092 -86.50224)
		(end 101.092 -85.471)
		(width 0.381)
		(layer "F.Cu")
		(net "XP3R3V_FPGA")
	)
	(segment
		(start 88.7476 -65.024)
		(end 88.6714 -65.1002)
		(width 0.381)
		(layer "F.Cu")
		(net "XP3R3V_FPGA")
	)
	(segment
		(start 98.846894 -49.823116)
		(end 97.917 -49.823116)
		(width 0.381)
		(layer "F.Cu")
		(net "XP3R3V_FPGA")
	)
	(segment
		(start 151.613108 -48.282606)
		(end 150.876762 -47.54626)
		(width 0.381)
		(layer "F.Cu")
		(net "XP3R3V_FPGA")
	)
	(segment
		(start 14.6812 -66.96964)
		(end 14.6812 -66.3194)
		(width 0.381)
		(layer "F.Cu")
		(net "XP3R3V_FPGA")
	)
	(segment
		(start 161.036 -28.829)
		(end 162.0266 -28.829)
		(width 0.381)
		(layer "F.Cu")
		(net "XP3R3V_FPGA")
	)
	(segment
		(start 133.3246 -25.146)
		(end 133.3246 -23.368)
		(width 0.381)
		(layer "F.Cu")
		(net "XP3R3V_FPGA")
	)
	(segment
		(start 96.1644 -60.5536)
		(end 96.393 -60.325)
		(width 0.381)
		(layer "F.Cu")
		(net "XP3R3V_FPGA")
	)
	(segment
		(start 88.4174 -82.169)
		(end 86.7156 -82.169)
		(width 0.381)
		(layer "F.Cu")
		(net "XP3R3V_FPGA")
	)
	(segment
		(start 118.847108 -49.823116)
		(end 119.34698 -50.322988)
		(width 0.381)
		(layer "F.Cu")
		(net "XP3R3V_FPGA")
	)
	(segment
		(start 105.847134 -48.823118)
		(end 105.347262 -49.32299)
		(width 0.381)
		(layer "F.Cu")
		(net "XP3R3V_FPGA")
	)
	(segment
		(start 131.027678 -23.357078)
		(end 130.1623 -23.357078)
		(width 0.381)
		(layer "F.Cu")
		(net "XP3R3V_FPGA")
	)
	(segment
		(start 86.614 -77.216)
		(end 86.7156 -77.3176)
		(width 0.381)
		(layer "F.Cu")
		(net "XP3R3V_FPGA")
	)
	(segment
		(start 28.67152 -15.58544)
		(end 28.27782 -15.19174)
		(width 0.381)
		(layer "F.Cu")
		(net "XP3R3V_FPGA")
	)
	(segment
		(start 94.80804 -62.79896)
		(end 94.869 -62.738)
		(width 0.381)
		(layer "F.Cu")
		(net "XP3R3V_FPGA")
	)
	(segment
		(start 57.8612 -19.05)
		(end 57.912 -19.05)
		(width 0.381)
		(layer "F.Cu")
		(net "XP3R3V_FPGA")
	)
	(segment
		(start 163.0934 -25.908)
		(end 163.0934 -24.511)
		(width 0.381)
		(layer "F.Cu")
		(net "XP3R3V_FPGA")
	)
	(segment
		(start 131.0386 -23.368)
		(end 131.027678 -23.357078)
		(width 0.381)
		(layer "F.Cu")
		(net "XP3R3V_FPGA")
	)
	(segment
		(start 75.06208 -16.96212)
		(end 75.06208 -15.77848)
		(width 0.381)
		(layer "F.Cu")
		(net "XP3R3V_FPGA")
	)
	(segment
		(start 36.5506 -81.0768)
		(end 36.957 -81.0768)
		(width 0.381)
		(layer "F.Cu")
		(net "XP3R3V_FPGA")
	)
	(segment
		(start 102.84714 -47.82312)
		(end 102.347268 -48.322992)
		(width 0.381)
		(layer "F.Cu")
		(net "XP3R3V_FPGA")
	)
	(segment
		(start 155.9814 -58.928)
		(end 155.956 -58.9534)
		(width 0.4572)
		(layer "F.Cu")
		(net "XP3R3V_FPGA")
	)
	(segment
		(start 163.0934 -27.432)
		(end 164.338 -27.432)
		(width 0.381)
		(layer "F.Cu")
		(net "XP3R3V_FPGA")
	)
	(segment
		(start 2.965958 -24.174958)
		(end 2.096008 -24.174958)
		(width 0.381)
		(layer "F.Cu")
		(net "XP3R3V_FPGA")
	)
	(segment
		(start 99.846892 -46.823122)
		(end 99.34702 -47.322994)
		(width 0.381)
		(layer "F.Cu")
		(net "XP3R3V_FPGA")
	)
	(segment
		(start 54.0512 -73.533)
		(end 54.0512 -74.4474)
		(width 0.381)
		(layer "F.Cu")
		(net "XP3R3V_FPGA")
	)
	(segment
		(start 31.75 -19.431)
		(end 31.46044 -19.14144)
		(width 0.381)
		(layer "F.Cu")
		(net "XP3R3V_FPGA")
	)
	(segment
		(start 3.175 -24.384)
		(end 2.965958 -24.174958)
		(width 0.381)
		(layer "F.Cu")
		(net "XP3R3V_FPGA")
	)
	(segment
		(start 75.06208 -16.96212)
		(end 75.06208 -17.60728)
		(width 0.381)
		(layer "F.Cu")
		(net "XP3R3V_FPGA")
	)
	(segment
		(start 127.0254 -35.179)
		(end 127.0254 -33.909)
		(width 0.381)
		(layer "F.Cu")
		(net "XP3R3V_FPGA")
	)
	(segment
		(start 151.2824 -28.575)
		(end 151.2824 -28.6004)
		(width 0.381)
		(layer "F.Cu")
		(net "XP3R3V_FPGA")
	)
	(segment
		(start 90.805 -66.421)
		(end 90.424 -66.04)
		(width 0.381)
		(layer "F.Cu")
		(net "XP3R3V_FPGA")
	)
	(segment
		(start 96.5454 -64.8208)
		(end 95.4532 -64.8208)
		(width 0.381)
		(layer "F.Cu")
		(net "XP3R3V_FPGA")
	)
	(segment
		(start 3.137154 -53.175154)
		(end 3.175 -53.213)
		(width 0.381)
		(layer "F.Cu")
		(net "XP3R3V_FPGA")
	)
	(segment
		(start 88.6714 -65.1002)
		(end 88.6714 -65.8876)
		(width 0.381)
		(layer "F.Cu")
		(net "XP3R3V_FPGA")
	)
	(segment
		(start 12.827 -27.53106)
		(end 12.827 -26.6192)
		(width 0.381)
		(layer "F.Cu")
		(net "XP3R3V_FPGA")
	)
	(segment
		(start 35.5854 -77.9526)
		(end 35.5854 -80.1116)
		(width 0.381)
		(layer "F.Cu")
		(net "XP3R3V_FPGA")
	)
	(segment
		(start 14.986 -24.511)
		(end 14.732 -24.257)
		(width 0.381)
		(layer "F.Cu")
		(net "XP3R3V_FPGA")
	)
	(segment
		(start 89.9414 -65.024)
		(end 88.7476 -65.024)
		(width 0.381)
		(layer "F.Cu")
		(net "XP3R3V_FPGA")
	)
	(via
		(at 17.1196 -57.6834)
		(size 0.508)
		(drill 0.254)
		(layers "F.Cu" "B.Cu")
		(net "XP3R3V_FPGA")
	)
	(via
		(at 17.1958 -61.0108)
		(size 0.508)
		(drill 0.254)
		(layers "F.Cu" "B.Cu")
		(net "XP3R3V_FPGA")
	)
	(via
		(at 13.86586 -67.78498)
		(size 0.508)
		(drill 0.254)
		(layers "F.Cu" "B.Cu")
		(net "XP3R3V_FPGA")
	)
	(via
		(at 49.7586 -84.455)
		(size 0.508)
		(drill 0.254)
		(layers "F.Cu" "B.Cu")
		(net "XP3R3V_FPGA")
	)
	(via
		(at 126.111 -50.165)
		(size 0.508)
		(drill 0.254)
		(layers "F.Cu" "B.Cu")
		(net "XP3R3V_FPGA")
	)
	(via
		(at 14.986 -24.511)
		(size 0.508)
		(drill 0.254)
		(layers "F.Cu" "B.Cu")
		(net "XP3R3V_FPGA")
	)
	(via
		(at 132.6134 -105.791)
		(size 0.508)
		(drill 0.254)
		(layers "F.Cu" "B.Cu")
		(net "XP3R3V_FPGA")
	)
	(via
		(at 86.614 -77.216)
		(size 0.508)
		(drill 0.254)
		(layers "F.Cu" "B.Cu")
		(net "XP3R3V_FPGA")
	)
	(via
		(at 6.1214 -78.9686)
		(size 0.508)
		(drill 0.254)
		(layers "F.Cu" "B.Cu")
		(net "XP3R3V_FPGA")
	)
	(via
		(at 150.368 -32.274002)
		(size 0.508)
		(drill 0.254)
		(layers "F.Cu" "B.Cu")
		(net "XP3R3V_FPGA")
	)
	(via
		(at 97.5106 -97.6884)
		(size 0.508)
		(drill 0.254)
		(layers "F.Cu" "B.Cu")
		(net "XP3R3V_FPGA")
	)
	(via
		(at 133.3246 -25.146)
		(size 0.508)
		(drill 0.254)
		(layers "F.Cu" "B.Cu")
		(net "XP3R3V_FPGA")
	)
	(via
		(at 103.505 -57.15)
		(size 0.508)
		(drill 0.254)
		(layers "F.Cu" "B.Cu")
		(net "XP3R3V_FPGA")
	)
	(via
		(at 15.2654 -18.542)
		(size 0.508)
		(drill 0.254)
		(layers "F.Cu" "B.Cu")
		(net "XP3R3V_FPGA")
	)
	(via
		(at 15.367 -38.608)
		(size 0.508)
		(drill 0.254)
		(layers "F.Cu" "B.Cu")
		(net "XP3R3V_FPGA")
	)
	(via
		(at 107.347258 -53.322982)
		(size 0.4572)
		(drill 0.2032)
		(layers "F.Cu" "B.Cu")
		(net "XP3R3V_FPGA")
	)
	(via
		(at 58.039 -20.066)
		(size 0.508)
		(drill 0.254)
		(layers "F.Cu" "B.Cu")
		(net "XP3R3V_FPGA")
	)
	(via
		(at 90.85072 -69.03212)
		(size 0.508)
		(drill 0.254)
		(layers "F.Cu" "B.Cu")
		(net "XP3R3V_FPGA")
	)
	(via
		(at 90.17 -85.598)
		(size 0.508)
		(drill 0.254)
		(layers "F.Cu" "B.Cu")
		(net "XP3R3V_FPGA")
	)
	(via
		(at 3.041904 -82.175096)
		(size 0.508)
		(drill 0.254)
		(layers "F.Cu" "B.Cu")
		(net "XP3R3V_FPGA")
	)
	(via
		(at 90.1192 -72.5424)
		(size 0.4572)
		(drill 0.2032)
		(layers "F.Cu" "B.Cu")
		(net "XP3R3V_FPGA")
	)
	(via
		(at 90.17 -83.312)
		(size 0.4572)
		(drill 0.2032)
		(layers "F.Cu" "B.Cu")
		(net "XP3R3V_FPGA")
	)
	(via
		(at 13.0556 -41.0464)
		(size 0.508)
		(drill 0.254)
		(layers "F.Cu" "B.Cu")
		(net "XP3R3V_FPGA")
	)
	(via
		(at 149.352 -24.511)
		(size 0.508)
		(drill 0.254)
		(layers "F.Cu" "B.Cu")
		(net "XP3R3V_FPGA")
	)
	(via
		(at 115.189 -96.901)
		(size 0.508)
		(drill 0.254)
		(layers "F.Cu" "B.Cu")
		(net "XP3R3V_FPGA")
	)
	(via
		(at 16.36903 -42.91203)
		(size 0.508)
		(drill 0.254)
		(layers "F.Cu" "B.Cu")
		(net "XP3R3V_FPGA")
	)
	(via
		(at 58.039 -19.177)
		(size 0.508)
		(drill 0.254)
		(layers "F.Cu" "B.Cu")
		(net "XP3R3V_FPGA")
	)
	(via
		(at 121.158 -60.706)
		(size 0.508)
		(drill 0.254)
		(layers "F.Cu" "B.Cu")
		(net "XP3R3V_FPGA")
	)
	(via
		(at 103.347266 -45.322998)
		(size 0.4572)
		(drill 0.2032)
		(layers "F.Cu" "B.Cu")
		(net "XP3R3V_FPGA")
	)
	(via
		(at 78.486 -41.783)
		(size 0.508)
		(drill 0.254)
		(layers "F.Cu" "B.Cu")
		(net "XP3R3V_FPGA")
	)
	(via
		(at 94.869 -62.738)
		(size 0.508)
		(drill 0.254)
		(layers "F.Cu" "B.Cu")
		(net "XP3R3V_FPGA")
	)
	(via
		(at 131.826 -78.105)
		(size 0.508)
		(drill 0.254)
		(layers "F.Cu" "B.Cu")
		(net "XP3R3V_FPGA")
	)
	(via
		(at 28.27782 -15.19174)
		(size 0.508)
		(drill 0.254)
		(layers "F.Cu" "B.Cu")
		(net "XP3R3V_FPGA")
	)
	(via
		(at 89.535 -66.04)
		(size 0.508)
		(drill 0.254)
		(layers "F.Cu" "B.Cu")
		(net "XP3R3V_FPGA")
	)
	(via
		(at 78.8924 -82.804)
		(size 0.508)
		(drill 0.254)
		(layers "F.Cu" "B.Cu")
		(net "XP3R3V_FPGA")
	)
	(via
		(at 86.233 -71.628)
		(size 0.508)
		(drill 0.254)
		(layers "F.Cu" "B.Cu")
		(net "XP3R3V_FPGA")
	)
	(via
		(at 3.175 -24.384)
		(size 0.508)
		(drill 0.254)
		(layers "F.Cu" "B.Cu")
		(net "XP3R3V_FPGA")
	)
	(via
		(at 19.4056 -22.1488)
		(size 0.508)
		(drill 0.254)
		(layers "F.Cu" "B.Cu")
		(net "XP3R3V_FPGA")
	)
	(via
		(at 93.98 -85.598)
		(size 0.508)
		(drill 0.254)
		(layers "F.Cu" "B.Cu")
		(net "XP3R3V_FPGA")
	)
	(via
		(at 35.5854 -77.9526)
		(size 0.508)
		(drill 0.254)
		(layers "F.Cu" "B.Cu")
		(net "XP3R3V_FPGA")
	)
	(via
		(at 107.9246 -72.2122)
		(size 0.508)
		(drill 0.254)
		(layers "F.Cu" "B.Cu")
		(net "XP3R3V_FPGA")
	)
	(via
		(at 115.346988 -52.322984)
		(size 0.4572)
		(drill 0.2032)
		(layers "F.Cu" "B.Cu")
		(net "XP3R3V_FPGA")
	)
	(via
		(at 113.346992 -48.322992)
		(size 0.4572)
		(drill 0.2032)
		(layers "F.Cu" "B.Cu")
		(net "XP3R3V_FPGA")
	)
	(via
		(at 106.9086 -65.786)
		(size 0.508)
		(drill 0.254)
		(layers "F.Cu" "B.Cu")
		(net "XP3R3V_FPGA")
	)
	(via
		(at 54.0512 -73.533)
		(size 0.4572)
		(drill 0.2032)
		(layers "F.Cu" "B.Cu")
		(net "XP3R3V_FPGA")
	)
	(via
		(at 95.4532 -64.8208)
		(size 0.508)
		(drill 0.254)
		(layers "F.Cu" "B.Cu")
		(net "XP3R3V_FPGA")
	)
	(via
		(at 142.748 -64.73698)
		(size 0.508)
		(drill 0.254)
		(layers "F.Cu" "B.Cu")
		(net "XP3R3V_FPGA")
	)
	(via
		(at 111.3536 -97.1296)
		(size 0.508)
		(drill 0.254)
		(layers "F.Cu" "B.Cu")
		(net "XP3R3V_FPGA")
	)
	(via
		(at 21.7678 -60.071)
		(size 0.508)
		(drill 0.254)
		(layers "F.Cu" "B.Cu")
		(net "XP3R3V_FPGA")
	)
	(via
		(at 46.3804 -73.533)
		(size 0.508)
		(drill 0.254)
		(layers "F.Cu" "B.Cu")
		(net "XP3R3V_FPGA")
	)
	(via
		(at 81.8388 -81.407)
		(size 0.4572)
		(drill 0.2032)
		(layers "F.Cu" "B.Cu")
		(net "XP3R3V_FPGA")
	)
	(via
		(at 2.861056 -38.675056)
		(size 0.508)
		(drill 0.254)
		(layers "F.Cu" "B.Cu")
		(net "XP3R3V_FPGA")
	)
	(via
		(at 14.732 -54.229)
		(size 0.508)
		(drill 0.254)
		(layers "F.Cu" "B.Cu")
		(net "XP3R3V_FPGA")
	)
	(via
		(at 152.273 -29.591)
		(size 0.508)
		(drill 0.254)
		(layers "F.Cu" "B.Cu")
		(net "XP3R3V_FPGA")
	)
	(via
		(at 106.34726 -46.322996)
		(size 0.4572)
		(drill 0.2032)
		(layers "F.Cu" "B.Cu")
		(net "XP3R3V_FPGA")
	)
	(via
		(at 75.2856 -17.8308)
		(size 0.508)
		(drill 0.254)
		(layers "F.Cu" "B.Cu")
		(net "XP3R3V_FPGA")
	)
	(via
		(at 114.5286 -84.0486)
		(size 0.508)
		(drill 0.254)
		(layers "F.Cu" "B.Cu")
		(net "XP3R3V_FPGA")
	)
	(via
		(at 88.519 -66.04)
		(size 0.508)
		(drill 0.254)
		(layers "F.Cu" "B.Cu")
		(net "XP3R3V_FPGA")
	)
	(via
		(at 15.875 -29.718)
		(size 0.508)
		(drill 0.254)
		(layers "F.Cu" "B.Cu")
		(net "XP3R3V_FPGA")
	)
	(via
		(at 107.6706 -70.739)
		(size 0.508)
		(drill 0.254)
		(layers "F.Cu" "B.Cu")
		(net "XP3R3V_FPGA")
	)
	(via
		(at 116.346986 -49.32299)
		(size 0.4572)
		(drill 0.2032)
		(layers "F.Cu" "B.Cu")
		(net "XP3R3V_FPGA")
	)
	(via
		(at 120.346978 -47.322994)
		(size 0.4572)
		(drill 0.2032)
		(layers "F.Cu" "B.Cu")
		(net "XP3R3V_FPGA")
	)
	(via
		(at 15.1384 -15.2908)
		(size 0.508)
		(drill 0.254)
		(layers "F.Cu" "B.Cu")
		(net "XP3R3V_FPGA")
	)
	(via
		(at 148.336 -107.1626)
		(size 0.508)
		(drill 0.254)
		(layers "F.Cu" "B.Cu")
		(net "XP3R3V_FPGA")
	)
	(via
		(at 99.34702 -47.322994)
		(size 0.4572)
		(drill 0.2032)
		(layers "F.Cu" "B.Cu")
		(net "XP3R3V_FPGA")
	)
	(via
		(at 136.525 -77.216)
		(size 0.508)
		(drill 0.254)
		(layers "F.Cu" "B.Cu")
		(net "XP3R3V_FPGA")
	)
	(via
		(at 82.296 -56.0705)
		(size 0.508)
		(drill 0.254)
		(layers "F.Cu" "B.Cu")
		(net "XP3R3V_FPGA")
	)
	(via
		(at 79.2226 -61.8236)
		(size 0.508)
		(drill 0.254)
		(layers "F.Cu" "B.Cu")
		(net "XP3R3V_FPGA")
	)
	(via
		(at 111.346996 -54.32298)
		(size 0.4572)
		(drill 0.2032)
		(layers "F.Cu" "B.Cu")
		(net "XP3R3V_FPGA")
	)
	(via
		(at 101.34727 -51.322986)
		(size 0.4572)
		(drill 0.2032)
		(layers "F.Cu" "B.Cu")
		(net "XP3R3V_FPGA")
	)
	(via
		(at 101.092 -85.471)
		(size 0.508)
		(drill 0.254)
		(layers "F.Cu" "B.Cu")
		(net "XP3R3V_FPGA")
	)
	(via
		(at 150.876762 -47.498)
		(size 0.508)
		(drill 0.254)
		(layers "F.Cu" "B.Cu")
		(net "XP3R3V_FPGA")
	)
	(via
		(at 155.067 -48.387)
		(size 0.508)
		(drill 0.254)
		(layers "F.Cu" "B.Cu")
		(net "XP3R3V_FPGA")
	)
	(via
		(at 114.427 -93.599)
		(size 0.508)
		(drill 0.254)
		(layers "F.Cu" "B.Cu")
		(net "XP3R3V_FPGA")
	)
	(via
		(at 106.045 -85.598)
		(size 0.508)
		(drill 0.254)
		(layers "F.Cu" "B.Cu")
		(net "XP3R3V_FPGA")
	)
	(via
		(at 108.347256 -50.322988)
		(size 0.4572)
		(drill 0.2032)
		(layers "F.Cu" "B.Cu")
		(net "XP3R3V_FPGA")
	)
	(via
		(at 119.634 -60.706)
		(size 0.508)
		(drill 0.254)
		(layers "F.Cu" "B.Cu")
		(net "XP3R3V_FPGA")
	)
	(via
		(at 124.587 -55.0545)
		(size 0.508)
		(drill 0.254)
		(layers "F.Cu" "B.Cu")
		(net "XP3R3V_FPGA")
	)
	(via
		(at 137.414 -71.501)
		(size 0.508)
		(drill 0.254)
		(layers "F.Cu" "B.Cu")
		(net "XP3R3V_FPGA")
	)
	(via
		(at 63.246 -73.7362)
		(size 0.508)
		(drill 0.254)
		(layers "F.Cu" "B.Cu")
		(net "XP3R3V_FPGA")
	)
	(via
		(at 21.844 -16.0274)
		(size 0.508)
		(drill 0.254)
		(layers "F.Cu" "B.Cu")
		(net "XP3R3V_FPGA")
	)
	(via
		(at 103.347266 -55.322978)
		(size 0.4572)
		(drill 0.2032)
		(layers "F.Cu" "B.Cu")
		(net "XP3R3V_FPGA")
	)
	(via
		(at 97.917 -49.823116)
		(size 0.4572)
		(drill 0.2032)
		(layers "F.Cu" "B.Cu")
		(net "XP3R3V_FPGA")
	)
	(via
		(at 78.8924 -85.09)
		(size 0.4572)
		(drill 0.2032)
		(layers "F.Cu" "B.Cu")
		(net "XP3R3V_FPGA")
	)
	(via
		(at 117.094 -76.835)
		(size 0.508)
		(drill 0.254)
		(layers "F.Cu" "B.Cu")
		(net "XP3R3V_FPGA")
	)
	(via
		(at 140.8176 -67.945)
		(size 0.508)
		(drill 0.254)
		(layers "F.Cu" "B.Cu")
		(net "XP3R3V_FPGA")
	)
	(via
		(at 3.038602 -67.674998)
		(size 0.508)
		(drill 0.254)
		(layers "F.Cu" "B.Cu")
		(net "XP3R3V_FPGA")
	)
	(via
		(at 52.01158 -17.21612)
		(size 0.508)
		(drill 0.254)
		(layers "F.Cu" "B.Cu")
		(net "XP3R3V_FPGA")
	)
	(via
		(at 126.238 -44.45)
		(size 0.508)
		(drill 0.254)
		(layers "F.Cu" "B.Cu")
		(net "XP3R3V_FPGA")
	)
	(via
		(at 98.044 -65.8495)
		(size 0.508)
		(drill 0.254)
		(layers "F.Cu" "B.Cu")
		(net "XP3R3V_FPGA")
	)
	(via
		(at 114.34699 -45.322998)
		(size 0.4572)
		(drill 0.2032)
		(layers "F.Cu" "B.Cu")
		(net "XP3R3V_FPGA")
	)
	(via
		(at 81.8388 -85.979)
		(size 0.4572)
		(drill 0.2032)
		(layers "F.Cu" "B.Cu")
		(net "XP3R3V_FPGA")
	)
	(via
		(at 125.73 -87.884)
		(size 0.508)
		(drill 0.254)
		(layers "F.Cu" "B.Cu")
		(net "XP3R3V_FPGA")
	)
	(via
		(at 86.7156 -82.169)
		(size 0.508)
		(drill 0.254)
		(layers "F.Cu" "B.Cu")
		(net "XP3R3V_FPGA")
	)
	(via
		(at 125.984 -41.402)
		(size 0.508)
		(drill 0.254)
		(layers "F.Cu" "B.Cu")
		(net "XP3R3V_FPGA")
	)
	(via
		(at 22.4536 -39.3446)
		(size 0.508)
		(drill 0.254)
		(layers "F.Cu" "B.Cu")
		(net "XP3R3V_FPGA")
	)
	(via
		(at 117.729 -23.368)
		(size 0.508)
		(drill 0.254)
		(layers "F.Cu" "B.Cu")
		(net "XP3R3V_FPGA")
	)
	(via
		(at 111.633 -63.5)
		(size 0.508)
		(drill 0.254)
		(layers "F.Cu" "B.Cu")
		(net "XP3R3V_FPGA")
	)
	(via
		(at 148.59 -57.531)
		(size 0.508)
		(drill 0.254)
		(layers "F.Cu" "B.Cu")
		(net "XP3R3V_FPGA")
	)
	(via
		(at 156.083 -101.092)
		(size 0.508)
		(drill 0.254)
		(layers "F.Cu" "B.Cu")
		(net "XP3R3V_FPGA")
	)
	(via
		(at 107.569 -105.537)
		(size 0.508)
		(drill 0.254)
		(layers "F.Cu" "B.Cu")
		(net "XP3R3V_FPGA")
	)
	(via
		(at 88.678512 -47.403512)
		(size 0.508)
		(drill 0.254)
		(layers "F.Cu" "B.Cu")
		(net "XP3R3V_FPGA")
	)
	(via
		(at 104.347264 -52.322984)
		(size 0.4572)
		(drill 0.2032)
		(layers "F.Cu" "B.Cu")
		(net "XP3R3V_FPGA")
	)
	(via
		(at 100.347018 -54.32298)
		(size 0.4572)
		(drill 0.2032)
		(layers "F.Cu" "B.Cu")
		(net "XP3R3V_FPGA")
	)
	(via
		(at 140.081 -15.137638)
		(size 0.508)
		(drill 0.254)
		(layers "F.Cu" "B.Cu")
		(net "XP3R3V_FPGA")
	)
	(via
		(at 84.709 -65.7606)
		(size 0.508)
		(drill 0.254)
		(layers "F.Cu" "B.Cu")
		(net "XP3R3V_FPGA")
	)
	(via
		(at 3.175 -53.213)
		(size 0.508)
		(drill 0.254)
		(layers "F.Cu" "B.Cu")
		(net "XP3R3V_FPGA")
	)
	(via
		(at 107.9246 -74.3966)
		(size 0.508)
		(drill 0.254)
		(layers "F.Cu" "B.Cu")
		(net "XP3R3V_FPGA")
	)
	(via
		(at 88.646 -75.057)
		(size 0.508)
		(drill 0.254)
		(layers "F.Cu" "B.Cu")
		(net "XP3R3V_FPGA")
	)
	(via
		(at 151.765 -107.1626)
		(size 0.508)
		(drill 0.254)
		(layers "F.Cu" "B.Cu")
		(net "XP3R3V_FPGA")
	)
	(via
		(at 118.346982 -53.322982)
		(size 0.4572)
		(drill 0.2032)
		(layers "F.Cu" "B.Cu")
		(net "XP3R3V_FPGA")
	)
	(via
		(at 118.237 -19.939)
		(size 0.508)
		(drill 0.254)
		(layers "F.Cu" "B.Cu")
		(net "XP3R3V_FPGA")
	)
	(via
		(at 4.064 -75.565)
		(size 0.508)
		(drill 0.254)
		(layers "F.Cu" "B.Cu")
		(net "XP3R3V_FPGA")
	)
	(via
		(at 140.462 -27.559)
		(size 0.508)
		(drill 0.254)
		(layers "F.Cu" "B.Cu")
		(net "XP3R3V_FPGA")
	)
	(via
		(at 157.988 -32.274002)
		(size 0.508)
		(drill 0.254)
		(layers "F.Cu" "B.Cu")
		(net "XP3R3V_FPGA")
	)
	(via
		(at 112.346994 -51.322986)
		(size 0.4572)
		(drill 0.2032)
		(layers "F.Cu" "B.Cu")
		(net "XP3R3V_FPGA")
	)
	(via
		(at 110.346998 -47.322994)
		(size 0.4572)
		(drill 0.2032)
		(layers "F.Cu" "B.Cu")
		(net "XP3R3V_FPGA")
	)
	(via
		(at 162.0266 -29.6926)
		(size 0.508)
		(drill 0.254)
		(layers "F.Cu" "B.Cu")
		(net "XP3R3V_FPGA")
	)
	(via
		(at 96.393 -60.325)
		(size 0.508)
		(drill 0.254)
		(layers "F.Cu" "B.Cu")
		(net "XP3R3V_FPGA")
	)
	(via
		(at 112.522 -98.171)
		(size 0.4572)
		(drill 0.2032)
		(layers "F.Cu" "B.Cu")
		(net "XP3R3V_FPGA")
	)
	(via
		(at 117.983 -75.819)
		(size 0.508)
		(drill 0.254)
		(layers "F.Cu" "B.Cu")
		(net "XP3R3V_FPGA")
	)
	(via
		(at 40.767 -19.177)
		(size 0.508)
		(drill 0.254)
		(layers "F.Cu" "B.Cu")
		(net "XP3R3V_FPGA")
	)
	(via
		(at 102.347268 -48.322992)
		(size 0.4572)
		(drill 0.2032)
		(layers "F.Cu" "B.Cu")
		(net "XP3R3V_FPGA")
	)
	(via
		(at 9.4996 -71.8566)
		(size 0.508)
		(drill 0.254)
		(layers "F.Cu" "B.Cu")
		(net "XP3R3V_FPGA")
	)
	(via
		(at 155.9814 -60.0456)
		(size 0.508)
		(drill 0.254)
		(layers "F.Cu" "B.Cu")
		(net "XP3R3V_FPGA")
	)
	(via
		(at 164.338 -27.432)
		(size 0.508)
		(drill 0.254)
		(layers "F.Cu" "B.Cu")
		(net "XP3R3V_FPGA")
	)
	(via
		(at 40.767 -18.161)
		(size 0.508)
		(drill 0.254)
		(layers "F.Cu" "B.Cu")
		(net "XP3R3V_FPGA")
	)
	(via
		(at 13.068808 -55.8546)
		(size 0.508)
		(drill 0.254)
		(layers "F.Cu" "B.Cu")
		(net "XP3R3V_FPGA")
	)
	(via
		(at 19.812 -74.041)
		(size 0.508)
		(drill 0.254)
		(layers "F.Cu" "B.Cu")
		(net "XP3R3V_FPGA")
	)
	(via
		(at 128.0033 -33.909)
		(size 0.508)
		(drill 0.254)
		(layers "F.Cu" "B.Cu")
		(net "XP3R3V_FPGA")
	)
	(via
		(at 38.93058 -14.8336)
		(size 0.508)
		(drill 0.254)
		(layers "F.Cu" "B.Cu")
		(net "XP3R3V_FPGA")
	)
	(via
		(at 20.8534 -20.1422)
		(size 0.508)
		(drill 0.254)
		(layers "F.Cu" "B.Cu")
		(net "XP3R3V_FPGA")
	)
	(via
		(at 31.75 -19.431)
		(size 0.508)
		(drill 0.254)
		(layers "F.Cu" "B.Cu")
		(net "XP3R3V_FPGA")
	)
	(via
		(at 118.346982 -42.323258)
		(size 0.4572)
		(drill 0.2032)
		(layers "F.Cu" "B.Cu")
		(net "XP3R3V_FPGA")
	)
	(via
		(at 57.023 -76.708)
		(size 0.4572)
		(drill 0.2032)
		(layers "F.Cu" "B.Cu")
		(net "XP3R3V_FPGA")
	)
	(via
		(at 12.827 -26.6192)
		(size 0.508)
		(drill 0.254)
		(layers "F.Cu" "B.Cu")
		(net "XP3R3V_FPGA")
	)
	(via
		(at 137.668 -75.2983)
		(size 0.508)
		(drill 0.254)
		(layers "F.Cu" "B.Cu")
		(net "XP3R3V_FPGA")
	)
	(via
		(at 119.34698 -50.322988)
		(size 0.4572)
		(drill 0.2032)
		(layers "F.Cu" "B.Cu")
		(net "XP3R3V_FPGA")
	)
	(via
		(at 94.234 -82.804)
		(size 0.508)
		(drill 0.254)
		(layers "F.Cu" "B.Cu")
		(net "XP3R3V_FPGA")
	)
	(via
		(at 116.205 -63.5)
		(size 0.508)
		(drill 0.254)
		(layers "F.Cu" "B.Cu")
		(net "XP3R3V_FPGA")
	)
	(via
		(at 109.728 -100.711)
		(size 0.4572)
		(drill 0.2032)
		(layers "F.Cu" "B.Cu")
		(net "XP3R3V_FPGA")
	)
	(via
		(at 22.4282 -41.6306)
		(size 0.4572)
		(drill 0.2032)
		(layers "F.Cu" "B.Cu")
		(net "XP3R3V_FPGA")
	)
	(via
		(at 123.19 -51.495706)
		(size 0.508)
		(drill 0.254)
		(layers "F.Cu" "B.Cu")
		(net "XP3R3V_FPGA")
	)
	(via
		(at 157.1371 -63.3222)
		(size 0.508)
		(drill 0.254)
		(layers "F.Cu" "B.Cu")
		(net "XP3R3V_FPGA")
	)
	(via
		(at 105.347262 -49.32299)
		(size 0.4572)
		(drill 0.2032)
		(layers "F.Cu" "B.Cu")
		(net "XP3R3V_FPGA")
	)
	(via
		(at 114.34699 -55.322978)
		(size 0.4572)
		(drill 0.2032)
		(layers "F.Cu" "B.Cu")
		(net "XP3R3V_FPGA")
	)
	(via
		(at 117.346984 -46.322996)
		(size 0.4572)
		(drill 0.2032)
		(layers "F.Cu" "B.Cu")
		(net "XP3R3V_FPGA")
	)
	(via
		(at 133.731 -17.145)
		(size 0.508)
		(drill 0.254)
		(layers "F.Cu" "B.Cu")
		(net "XP3R3V_FPGA")
	)
	(via
		(at 135.382 -20.828)
		(size 0.508)
		(drill 0.254)
		(layers "F.Cu" "B.Cu")
		(net "XP3R3V_FPGA")
	)
	(segment
		(start 119.2276 -24.511)
		(end 118.872 -24.511)
		(width 0.381)
		(layer "B.Cu")
		(net "XP3R3V_FPGA")
	)
	(segment
		(start 114.34699 -55.322978)
		(end 114.21999 -55.449978)
		(width 0.381)
		(layer "B.Cu")
		(net "XP3R3V_FPGA")
	)
	(segment
		(start 107.2896 -105.2576)
		(end 107.569 -105.537)
		(width 0.381)
		(layer "B.Cu")
		(net "XP3R3V_FPGA")
	)
	(segment
		(start 148.971 -64.643)
		(end 142.84198 -64.643)
		(width 0.381)
		(layer "B.Cu")
		(net "XP3R3V_FPGA")
	)
	(segment
		(start 117.846856 -45.823124)
		(end 117.84711 -45.823124)
		(width 0.381)
		(layer "B.Cu")
		(net "XP3R3V_FPGA")
	)
	(segment
		(start 105.847134 -49.822862)
		(end 105.847134 -49.823116)
		(width 0.381)
		(layer "B.Cu")
		(net "XP3R3V_FPGA")
	)
	(segment
		(start 20.0152 -22.7584)
		(end 19.4056 -22.1488)
		(width 0.381)
		(layer "B.Cu")
		(net "XP3R3V_FPGA")
	)
	(segment
		(start 82.296 -56.0705)
		(end 82.296 -56.388)
		(width 0.381)
		(layer "B.Cu")
		(net "XP3R3V_FPGA")
	)
	(segment
		(start 123.250706 -51.435)
		(end 123.19 -51.495706)
		(width 0.381)
		(layer "B.Cu")
		(net "XP3R3V_FPGA")
	)
	(segment
		(start 113.346992 -48.322992)
		(end 112.84712 -48.822864)
		(width 0.381)
		(layer "B.Cu")
		(net "XP3R3V_FPGA")
	)
	(segment
		(start 16.46936 -60.37326)
		(end 17.1069 -61.0108)
		(width 0.381)
		(layer "B.Cu")
		(net "XP3R3V_FPGA")
	)
	(segment
		(start 141.097 -15.4432)
		(end 140.4112 -15.4432)
		(width 0.381)
		(layer "B.Cu")
		(net "XP3R3V_FPGA")
	)
	(segment
		(start 118.847108 -53.823108)
		(end 118.346982 -53.322982)
		(width 0.381)
		(layer "B.Cu")
		(net "XP3R3V_FPGA")
	)
	(segment
		(start 140.4112 -15.4432)
		(end 140.105638 -15.137638)
		(width 0.381)
		(layer "B.Cu")
		(net "XP3R3V_FPGA")
	)
	(segment
		(start 105.918 -87.0966)
		(end 105.918 -85.725)
		(width 0.381)
		(layer "B.Cu")
		(net "XP3R3V_FPGA")
	)
	(segment
		(start 63.7286 -60.325)
		(end 63.0174 -60.325)
		(width 0.381)
		(layer "B.Cu")
		(net "XP3R3V_FPGA")
	)
	(segment
		(start 5.0546 -75.565)
		(end 4.064 -75.565)
		(width 0.381)
		(layer "B.Cu")
		(net "XP3R3V_FPGA")
	)
	(segment
		(start 104.847136 -49.823116)
		(end 105.347262 -49.32299)
		(width 0.381)
		(layer "B.Cu")
		(net "XP3R3V_FPGA")
	)
	(segment
		(start 133.731 -19.177)
		(end 135.382 -20.828)
		(width 0.381)
		(layer "B.Cu")
		(net "XP3R3V_FPGA")
	)
	(segment
		(start 109.8296 -75.565)
		(end 108.6612 -74.3966)
		(width 0.381)
		(layer "B.Cu")
		(net "XP3R3V_FPGA")
	)
	(segment
		(start 155.067 -49.276)
		(end 154.79649 -49.54651)
		(width 0.381)
		(layer "B.Cu")
		(net "XP3R3V_FPGA")
	)
	(segment
		(start 89.027 -46.5074)
		(end 89.027 -47.055024)
		(width 0.381)
		(layer "B.Cu")
		(net "XP3R3V_FPGA")
	)
	(segment
		(start 140.8176 -69.1134)
		(end 140.8176 -67.945)
		(width 0.381)
		(layer "B.Cu")
		(net "XP3R3V_FPGA")
	)
	(segment
		(start 20.0152 -23.1394)
		(end 20.0152 -22.7584)
		(width 0.381)
		(layer "B.Cu")
		(net "XP3R3V_FPGA")
	)
	(segment
		(start 116.847112 -46.822868)
		(end 117.346984 -46.322996)
		(width 0.381)
		(layer "B.Cu")
		(net "XP3R3V_FPGA")
	)
	(segment
		(start 126.7206 -87.757)
		(end 125.857 -87.757)
		(width 0.381)
		(layer "B.Cu")
		(net "XP3R3V_FPGA")
	)
	(segment
		(start 114.34699 -45.322998)
		(end 114.34699 -44.863004)
		(width 0.381)
		(layer "B.Cu")
		(net "XP3R3V_FPGA")
	)
	(segment
		(start 100.9142 -83.5914)
		(end 100.9142 -85.2932)
		(width 0.381)
		(layer "B.Cu")
		(net "XP3R3V_FPGA")
	)
	(segment
		(start 85.6234 -57.658)
		(end 85.6234 -57.277)
		(width 0.381)
		(layer "B.Cu")
		(net "XP3R3V_FPGA")
	)
	(segment
		(start 86.8426 -57.277)
		(end 85.6234 -57.277)
		(width 0.381)
		(layer "B.Cu")
		(net "XP3R3V_FPGA")
	)
	(segment
		(start 82.296 -56.388)
		(end 83.947 -58.039)
		(width 0.381)
		(layer "B.Cu")
		(net "XP3R3V_FPGA")
	)
	(segment
		(start 125.2855 -86.219284)
		(end 125.843284 -85.6615)
		(width 0.381)
		(layer "B.Cu")
		(net "XP3R3V_FPGA")
	)
	(segment
		(start 86.233 -72.7456)
		(end 86.233 -71.628)
		(width 0.381)
		(layer "B.Cu")
		(net "XP3R3V_FPGA")
	)
	(segment
		(start 137.16 -77.851)
		(end 138.3792 -77.851)
		(width 0.381)
		(layer "B.Cu")
		(net "XP3R3V_FPGA")
	)
	(segment
		(start 15.41018 -66.24066)
		(end 15.41018 -62.81928)
		(width 0.381)
		(layer "B.Cu")
		(net "XP3R3V_FPGA")
	)
	(segment
		(start 150.2918 -63.3222)
		(end 148.971 -64.643)
		(width 0.381)
		(layer "B.Cu")
		(net "XP3R3V_FPGA")
	)
	(segment
		(start 155.067 -48.387)
		(end 155.067 -49.276)
		(width 0.381)
		(layer "B.Cu")
		(net "XP3R3V_FPGA")
	)
	(segment
		(start 150.343108 -48.031654)
		(end 150.876762 -47.498)
		(width 0.381)
		(layer "B.Cu")
		(net "XP3R3V_FPGA")
	)
	(segment
		(start 97.5106 -96.774)
		(end 97.5106 -97.6884)
		(width 0.381)
		(layer "B.Cu")
		(net "XP3R3V_FPGA")
	)
	(segment
		(start 116.346986 -49.32299)
		(end 116.846858 -48.823118)
		(width 0.381)
		(layer "B.Cu")
		(net "XP3R3V_FPGA")
	)
	(segment
		(start 103.347266 -55.322978)
		(end 103.347266 -56.190134)
		(width 0.381)
		(layer "B.Cu")
		(net "XP3R3V_FPGA")
	)
	(segment
		(start 21.59 -39.3446)
		(end 22.4536 -39.3446)
		(width 0.381)
		(layer "B.Cu")
		(net "XP3R3V_FPGA")
	)
	(segment
		(start 100.9142 -85.2932)
		(end 101.092 -85.471)
		(width 0.381)
		(layer "B.Cu")
		(net "XP3R3V_FPGA")
	)
	(segment
		(start 133.731 -17.145)
		(end 133.731 -19.177)
		(width 0.381)
		(layer "B.Cu")
		(net "XP3R3V_FPGA")
	)
	(segment
		(start 82.7024 -85.979)
		(end 81.8388 -85.979)
		(width 0.381)
		(layer "B.Cu")
		(net "XP3R3V_FPGA")
	)
	(segment
		(start 31.75 -19.431)
		(end 32.21228 -19.431)
		(width 0.381)
		(layer "B.Cu")
		(net "XP3R3V_FPGA")
	)
	(segment
		(start 147.066 -107.1626)
		(end 148.336 -107.1626)
		(width 0.381)
		(layer "B.Cu")
		(net "XP3R3V_FPGA")
	)
	(segment
		(start 104.847136 -51.823112)
		(end 104.347264 -52.322984)
		(width 0.381)
		(layer "B.Cu")
		(net "XP3R3V_FPGA")
	)
	(segment
		(start 7.493 -78.105)
		(end 6.1214 -78.105)
		(width 0.381)
		(layer "B.Cu")
		(net "XP3R3V_FPGA")
	)
	(segment
		(start 115.346988 -52.322984)
		(end 114.847116 -52.822856)
		(width 0.381)
		(layer "B.Cu")
		(net "XP3R3V_FPGA")
	)
	(segment
		(start 103.347266 -56.190134)
		(end 103.2764 -56.261)
		(width 0.381)
		(layer "B.Cu")
		(net "XP3R3V_FPGA")
	)
	(segment
		(start 107.2896 -103.251)
		(end 107.2896 -104.521)
		(width 0.381)
		(layer "B.Cu")
		(net "XP3R3V_FPGA")
	)
	(segment
		(start 21.6154 -16.891)
		(end 21.6154 -16.637)
		(width 0.381)
		(layer "B.Cu")
		(net "XP3R3V_FPGA")
	)
	(segment
		(start 103.505 -57.15)
		(end 103.505 -58.7375)
		(width 0.381)
		(layer "B.Cu")
		(net "XP3R3V_FPGA")
	)
	(segment
		(start 133.3246 -25.6286)
		(end 135.255 -27.559)
		(width 0.381)
		(layer "B.Cu")
		(net "XP3R3V_FPGA")
	)
	(segment
		(start 125.73 -87.884)
		(end 125.2855 -87.4395)
		(width 0.381)
		(layer "B.Cu")
		(net "XP3R3V_FPGA")
	)
	(segment
		(start 107.2896 -104.521)
		(end 107.2896 -105.2576)
		(width 0.381)
		(layer "B.Cu")
		(net "XP3R3V_FPGA")
	)
	(segment
		(start 125.857 -44.831)
		(end 125.1204 -44.831)
		(width 0.381)
		(layer "B.Cu")
		(net "XP3R3V_FPGA")
	)
	(segment
		(start 108.347256 -50.322988)
		(end 108.494068 -50.4698)
		(width 0.381)
		(layer "B.Cu")
		(net "XP3R3V_FPGA")
	)
	(segment
		(start 62.625986 -58.0898)
		(end 62.625986 -59.700414)
		(width 0.254)
		(layer "B.Cu")
		(net "XP3R3V_FPGA")
	)
	(segment
		(start 18.161 -61.0108)
		(end 17.1958 -61.0108)
		(width 0.381)
		(layer "B.Cu")
		(net "XP3R3V_FPGA")
	)
	(segment
		(start 121.412 -47.322994)
		(end 120.346978 -47.322994)
		(width 0.381)
		(layer "B.Cu")
		(net "XP3R3V_FPGA")
	)
	(segment
		(start 154.79649 -49.54651)
		(end 154.153108 -49.54651)
		(width 0.381)
		(layer "B.Cu")
		(net "XP3R3V_FPGA")
	)
	(segment
		(start 116.847112 -49.823116)
		(end 116.346986 -49.32299)
		(width 0.381)
		(layer "B.Cu")
		(net "XP3R3V_FPGA")
	)
	(segment
		(start 100.847398 -50.823114)
		(end 100.847144 -50.823114)
		(width 0.381)
		(layer "B.Cu")
		(net "XP3R3V_FPGA")
	)
	(segment
		(start 124.0536 -51.435)
		(end 123.250706 -51.435)
		(width 0.381)
		(layer "B.Cu")
		(net "XP3R3V_FPGA")
	)
	(segment
		(start 157.1371 -63.3222)
		(end 150.2918 -63.3222)
		(width 0.381)
		(layer "B.Cu")
		(net "XP3R3V_FPGA")
	)
	(segment
		(start 21.59 -60.2488)
		(end 21.7678 -60.071)
		(width 0.381)
		(layer "B.Cu")
		(net "XP3R3V_FPGA")
	)
	(segment
		(start 102.84714 -48.823118)
		(end 102.84714 -48.822864)
		(width 0.381)
		(layer "B.Cu")
		(net "XP3R3V_FPGA")
	)
	(segment
		(start 144.018 -107.1626)
		(end 147.066 -107.1626)
		(width 0.381)
		(layer "B.Cu")
		(net "XP3R3V_FPGA")
	)
	(segment
		(start 100.84689 -51.823112)
		(end 100.847144 -51.823112)
		(width 0.381)
		(layer "B.Cu")
		(net "XP3R3V_FPGA")
	)
	(segment
		(start 63.7286 -62.0014)
		(end 63.7286 -60.325)
		(width 0.381)
		(layer "B.Cu")
		(net "XP3R3V_FPGA")
	)
	(segment
		(start 5.0546 -74.295)
		(end 5.0546 -75.565)
		(width 0.381)
		(layer "B.Cu")
		(net "XP3R3V_FPGA")
	)
	(segment
		(start 119.847106 -50.823114)
		(end 119.34698 -50.322988)
		(width 0.381)
		(layer "B.Cu")
		(net "XP3R3V_FPGA")
	)
	(segment
		(start 32.51708 -19.1262)
		(end 33.2486 -19.1262)
		(width 0.381)
		(layer "B.Cu")
		(net "XP3R3V_FPGA")
	)
	(segment
		(start 138.3792 -77.851)
		(end 138.4808 -77.7494)
		(width 0.381)
		(layer "B.Cu")
		(net "XP3R3V_FPGA")
	)
	(segment
		(start 150.343108 -48.47971)
		(end 150.343108 -48.031654)
		(width 0.381)
		(layer "B.Cu")
		(net "XP3R3V_FPGA")
	)
	(segment
		(start 18.8214 -74.041)
		(end 19.812 -74.041)
		(width 0.381)
		(layer "B.Cu")
		(net "XP3R3V_FPGA")
	)
	(segment
		(start 106.555032 -46.530768)
		(end 106.555032 -46.531022)
		(width 0.381)
		(layer "B.Cu")
		(net "XP3R3V_FPGA")
	)
	(segment
		(start 77.9272 -82.804)
		(end 78.8924 -82.804)
		(width 0.381)
		(layer "B.Cu")
		(net "XP3R3V_FPGA")
	)
	(segment
		(start 21.844 -16.4084)
		(end 21.844 -16.0274)
		(width 0.381)
		(layer "B.Cu")
		(net "XP3R3V_FPGA")
	)
	(segment
		(start 131.826 -80.645)
		(end 131.826 -78.105)
		(width 0.381)
		(layer "B.Cu")
		(net "XP3R3V_FPGA")
	)
	(segment
		(start 29.81452 -16.73098)
		(end 29.81452 -16.72844)
		(width 0.381)
		(layer "B.Cu")
		(net "XP3R3V_FPGA")
	)
	(segment
		(start 138.049 -107.1626)
		(end 141.097 -107.1626)
		(width 0.381)
		(layer "B.Cu")
		(net "XP3R3V_FPGA")
	)
	(segment
		(start 111.847122 -54.823106)
		(end 111.346996 -54.32298)
		(width 0.381)
		(layer "B.Cu")
		(net "XP3R3V_FPGA")
	)
	(segment
		(start 32.21228 -19.431)
		(end 32.51708 -19.1262)
		(width 0.381)
		(layer "B.Cu")
		(net "XP3R3V_FPGA")
	)
	(segment
		(start 133.3246 -25.146)
		(end 133.3246 -25.6286)
		(width 0.381)
		(layer "B.Cu")
		(net "XP3R3V_FPGA")
	)
	(segment
		(start 82.7024 -81.407)
		(end 81.8388 -81.407)
		(width 0.381)
		(layer "B.Cu")
		(net "XP3R3V_FPGA")
	)
	(segment
		(start 95.0976 -85.598)
		(end 93.98 -85.598)
		(width 0.381)
		(layer "B.Cu")
		(net "XP3R3V_FPGA")
	)
	(segment
		(start 100.347018 -54.32298)
		(end 99.847146 -53.823108)
		(width 0.381)
		(layer "B.Cu")
		(net "XP3R3V_FPGA")
	)
	(segment
		(start 116.205 -62.5094)
		(end 115.062 -62.5094)
		(width 0.381)
		(layer "B.Cu")
		(net "XP3R3V_FPGA")
	)
	(segment
		(start 152.883108 -49.54651)
		(end 154.153108 -49.54651)
		(width 0.381)
		(layer "B.Cu")
		(net "XP3R3V_FPGA")
	)
	(segment
		(start 110.5916 -100.711)
		(end 109.728 -100.711)
		(width 0.381)
		(layer "B.Cu")
		(net "XP3R3V_FPGA")
	)
	(segment
		(start 9.3853 -76.92136)
		(end 8.67664 -76.92136)
		(width 0.381)
		(layer "B.Cu")
		(net "XP3R3V_FPGA")
	)
	(segment
		(start 63.246 -73.7362)
		(end 63.246 -62.484)
		(width 0.381)
		(layer "B.Cu")
		(net "XP3R3V_FPGA")
	)
	(segment
		(start 141.097 -107.1626)
		(end 144.018 -107.1626)
		(width 0.381)
		(layer "B.Cu")
		(net "XP3R3V_FPGA")
	)
	(segment
		(start 63.246 -62.484)
		(end 63.7286 -62.0014)
		(width 0.381)
		(layer "B.Cu")
		(net "XP3R3V_FPGA")
	)
	(segment
		(start 142.84198 -64.643)
		(end 142.748 -64.73698)
		(width 0.381)
		(layer "B.Cu")
		(net "XP3R3V_FPGA")
	)
	(segment
		(start 14.6558 -17.9324)
		(end 14.6558 -17.7038)
		(width 0.381)
		(layer "B.Cu")
		(net "XP3R3V_FPGA")
	)
	(segment
		(start 125.843284 -85.6615)
		(end 126.8095 -85.6615)
		(width 0.381)
		(layer "B.Cu")
		(net "XP3R3V_FPGA")
	)
	(segment
		(start 125.857 -87.757)
		(end 125.73 -87.884)
		(width 0.381)
		(layer "B.Cu")
		(net "XP3R3V_FPGA")
	)
	(segment
		(start 109.683804 -46.6598)
		(end 109.3724 -46.6598)
		(width 0.381)
		(layer "B.Cu")
		(net "XP3R3V_FPGA")
	)
	(segment
		(start 17.1196 -57.6834)
		(end 16.46936 -58.33364)
		(width 0.381)
		(layer "B.Cu")
		(net "XP3R3V_FPGA")
	)
	(segment
		(start 102.84714 -48.822864)
		(end 102.347268 -48.322992)
		(width 0.381)
		(layer "B.Cu")
		(net "XP3R3V_FPGA")
	)
	(segment
		(start 117.84711 -46.823122)
		(end 117.346984 -46.322996)
		(width 0.381)
		(layer "B.Cu")
		(net "XP3R3V_FPGA")
	)
	(segment
		(start 62.625986 -59.700414)
		(end 62.5094 -59.817)
		(width 0.254)
		(layer "B.Cu")
		(net "XP3R3V_FPGA")
	)
	(segment
		(start 155.956 -107.1626)
		(end 153.0858 -107.1626)
		(width 0.381)
		(layer "B.Cu")
		(net "XP3R3V_FPGA")
	)
	(segment
		(start 8.509 -71.8566)
		(end 9.4996 -71.8566)
		(width 0.381)
		(layer "B.Cu")
		(net "XP3R3V_FPGA")
	)
	(segment
		(start 116.847112 -46.823122)
		(end 116.847112 -46.822868)
		(width 0.381)
		(layer "B.Cu")
		(net "XP3R3V_FPGA")
	)
	(segment
		(start 8.67664 -76.92136)
		(end 7.493 -78.105)
		(width 0.381)
		(layer "B.Cu")
		(net "XP3R3V_FPGA")
	)
	(segment
		(start 114.21999 -55.449978)
		(end 114.21999 -56.388)
		(width 0.381)
		(layer "B.Cu")
		(net "XP3R3V_FPGA")
	)
	(segment
		(start 138.4808 -71.4502)
		(end 137.4648 -71.4502)
		(width 0.381)
		(layer "B.Cu")
		(net "XP3R3V_FPGA")
	)
	(segment
		(start 118.872 -24.511)
		(end 117.729 -23.368)
		(width 0.381)
		(layer "B.Cu")
		(net "XP3R3V_FPGA")
	)
	(segment
		(start 106.34726 -46.322996)
		(end 106.555032 -46.530768)
		(width 0.381)
		(layer "B.Cu")
		(net "XP3R3V_FPGA")
	)
	(segment
		(start 95.0976 -82.169)
		(end 95.0976 -83.312)
		(width 0.381)
		(layer "B.Cu")
		(net "XP3R3V_FPGA")
	)
	(segment
		(start 112.84712 -48.822864)
		(end 112.84712 -48.823118)
		(width 0.381)
		(layer "B.Cu")
		(net "XP3R3V_FPGA")
	)
	(segment
		(start 99.846892 -46.823122)
		(end 99.34702 -47.322994)
		(width 0.381)
		(layer "B.Cu")
		(net "XP3R3V_FPGA")
	)
	(segment
		(start 88.519 -74.93)
		(end 88.519 -73.8124)
		(width 0.381)
		(layer "B.Cu")
		(net "XP3R3V_FPGA")
	)
	(segment
		(start 132.994654 -106.705654)
		(end 132.6134 -106.3244)
		(width 0.381)
		(layer "B.Cu")
		(net "XP3R3V_FPGA")
	)
	(segment
		(start 29.81452 -16.72844)
		(end 28.27782 -15.19174)
		(width 0.381)
		(layer "B.Cu")
		(net "XP3R3V_FPGA")
	)
	(segment
		(start 135.255 -27.559)
		(end 140.462 -27.559)
		(width 0.381)
		(layer "B.Cu")
		(net "XP3R3V_FPGA")
	)
	(segment
		(start 137.4648 -71.4502)
		(end 137.414 -71.501)
		(width 0.381)
		(layer "B.Cu")
		(net "XP3R3V_FPGA")
	)
	(segment
		(start 111.633 -62.5094)
		(end 111.633 -63.5)
		(width 0.381)
		(layer "B.Cu")
		(net "XP3R3V_FPGA")
	)
	(segment
		(start 101.847142 -48.823118)
		(end 102.347268 -48.322992)
		(width 0.381)
		(layer "B.Cu")
		(net "XP3R3V_FPGA")
	)
	(segment
		(start 116.205 -62.5094)
		(end 116.205 -63.5)
		(width 0.381)
		(layer "B.Cu")
		(net "XP3R3V_FPGA")
	)
	(segment
		(start 21.844 -20.0914)
		(end 20.9042 -20.0914)
		(width 0.381)
		(layer "B.Cu")
		(net "XP3R3V_FPGA")
	)
	(segment
		(start 15.41018 -62.81928)
		(end 17.1958 -61.03366)
		(width 0.381)
		(layer "B.Cu")
		(net "XP3R3V_FPGA")
	)
	(segment
		(start 82.7024 -84.836)
		(end 82.7024 -85.979)
		(width 0.381)
		(layer "B.Cu")
		(net "XP3R3V_FPGA")
	)
	(segment
		(start 6.1214 -78.105)
		(end 6.1214 -78.9686)
		(width 0.381)
		(layer "B.Cu")
		(net "XP3R3V_FPGA")
	)
	(segment
		(start 138.4808 -75.2983)
		(end 137.668 -75.2983)
		(width 0.381)
		(layer "B.Cu")
		(net "XP3R3V_FPGA")
	)
	(segment
		(start 133.9342 -106.705654)
		(end 132.994654 -106.705654)
		(width 0.381)
		(layer "B.Cu")
		(net "XP3R3V_FPGA")
	)
	(segment
		(start 105.918 -85.725)
		(end 106.045 -85.598)
		(width 0.381)
		(layer "B.Cu")
		(net "XP3R3V_FPGA")
	)
	(segment
		(start 114.34699 -44.863004)
		(end 114.632994 -44.577)
		(width 0.381)
		(layer "B.Cu")
		(net "XP3R3V_FPGA")
	)
	(segment
		(start 13.86586 -67.78498)
		(end 15.41018 -66.24066)
		(width 0.381)
		(layer "B.Cu")
		(net "XP3R3V_FPGA")
	)
	(segment
		(start 20.9042 -20.0914)
		(end 20.8534 -20.1422)
		(width 0.381)
		(layer "B.Cu")
		(net "XP3R3V_FPGA")
	)
	(segment
		(start 21.59 -61.0108)
		(end 21.59 -60.2488)
		(width 0.381)
		(layer "B.Cu")
		(net "XP3R3V_FPGA")
	)
	(segment
		(start 153.0858 -107.1626)
		(end 151.765 -107.1626)
		(width 0.381)
		(layer "B.Cu")
		(net "XP3R3V_FPGA")
	)
	(segment
		(start 63.0174 -60.325)
		(end 62.5094 -59.817)
		(width 0.381)
		(layer "B.Cu")
		(net "XP3R3V_FPGA")
	)
	(segment
		(start 17.1069 -61.0108)
		(end 17.1958 -61.0108)
		(width 0.381)
		(layer "B.Cu")
		(net "XP3R3V_FPGA")
	)
	(segment
		(start 114.847116 -52.822856)
		(end 114.847116 -52.82311)
		(width 0.381)
		(layer "B.Cu")
		(net "XP3R3V_FPGA")
	)
	(segment
		(start 99.847146 -53.823108)
		(end 99.846892 -53.823108)
		(width 0.381)
		(layer "B.Cu")
		(net "XP3R3V_FPGA")
	)
	(segment
		(start 117.346984 -46.322996)
		(end 117.846856 -45.823124)
		(width 0.381)
		(layer "B.Cu")
		(net "XP3R3V_FPGA")
	)
	(segment
		(start 99.846892 -54.823106)
		(end 100.347018 -54.32298)
		(width 0.381)
		(layer "B.Cu")
		(net "XP3R3V_FPGA")
	)
	(segment
		(start 85.2424 -58.039)
		(end 85.6234 -57.658)
		(width 0.381)
		(layer "B.Cu")
		(net "XP3R3V_FPGA")
	)
	(segment
		(start 88.646 -75.057)
		(end 88.519 -74.93)
		(width 0.381)
		(layer "B.Cu")
		(net "XP3R3V_FPGA")
	)
	(segment
		(start 21.6154 -16.637)
		(end 21.844 -16.4084)
		(width 0.381)
		(layer "B.Cu")
		(net "XP3R3V_FPGA")
	)
	(segment
		(start 116.846858 -48.823118)
		(end 116.847112 -48.823118)
		(width 0.381)
		(layer "B.Cu")
		(net "XP3R3V_FPGA")
	)
	(segment
		(start 125.1204 -41.402)
		(end 125.984 -41.402)
		(width 0.381)
		(layer "B.Cu")
		(net "XP3R3V_FPGA")
	)
	(segment
		(start 89.027 -47.055024)
		(end 88.678512 -47.403512)
		(width 0.381)
		(layer "B.Cu")
		(net "XP3R3V_FPGA")
	)
	(segment
		(start 101.34727 -51.322986)
		(end 100.847398 -50.823114)
		(width 0.381)
		(layer "B.Cu")
		(net "XP3R3V_FPGA")
	)
	(segment
		(start 125.1204 -50.165)
		(end 126.111 -50.165)
		(width 0.381)
		(layer "B.Cu")
		(net "XP3R3V_FPGA")
	)
	(segment
		(start 114.847116 -45.823124)
		(end 114.34699 -45.322998)
		(width 0.381)
		(layer "B.Cu")
		(net "XP3R3V_FPGA")
	)
	(segment
		(start 94.742 -83.312)
		(end 94.234 -82.804)
		(width 0.381)
		(layer "B.Cu")
		(net "XP3R3V_FPGA")
	)
	(segment
		(start 77.9272 -85.09)
		(end 78.8924 -85.09)
		(width 0.381)
		(layer "B.Cu")
		(net "XP3R3V_FPGA")
	)
	(segment
		(start 117.84711 -42.82313)
		(end 118.346982 -42.323258)
		(width 0.381)
		(layer "B.Cu")
		(net "XP3R3V_FPGA")
	)
	(segment
		(start 95.0976 -83.312)
		(end 94.742 -83.312)
		(width 0.381)
		(layer "B.Cu")
		(net "XP3R3V_FPGA")
	)
	(segment
		(start 15.2654 -18.542)
		(end 14.6558 -17.9324)
		(width 0.381)
		(layer "B.Cu")
		(net "XP3R3V_FPGA")
	)
	(segment
		(start 107.347258 -53.322982)
		(end 107.84713 -53.822854)
		(width 0.381)
		(layer "B.Cu")
		(net "XP3R3V_FPGA")
	)
	(segment
		(start 110.346998 -47.322994)
		(end 109.683804 -46.6598)
		(width 0.381)
		(layer "B.Cu")
		(net "XP3R3V_FPGA")
	)
	(segment
		(start 18.8722 -23.1394)
		(end 20.0152 -23.1394)
		(width 0.381)
		(layer "B.Cu")
		(net "XP3R3V_FPGA")
	)
	(segment
		(start 113.846864 -48.822864)
		(end 113.346992 -48.322992)
		(width 0.381)
		(layer "B.Cu")
		(net "XP3R3V_FPGA")
	)
	(segment
		(start 126.238 -44.45)
		(end 125.857 -44.831)
		(width 0.381)
		(layer "B.Cu")
		(net "XP3R3V_FPGA")
	)
	(segment
		(start 15.1384 -15.2908)
		(end 15.4686 -15.621)
		(width 0.4572)
		(layer "B.Cu")
		(net "XP3R3V_FPGA")
	)
	(segment
		(start 109.475524 -48.194468)
		(end 110.346998 -47.322994)
		(width 0.381)
		(layer "B.Cu")
		(net "XP3R3V_FPGA")
	)
	(segment
		(start 89.0524 -83.312)
		(end 90.17 -83.312)
		(width 0.381)
		(layer "B.Cu")
		(net "XP3R3V_FPGA")
	)
	(segment
		(start 138.049 -107.1626)
		(end 138.049 -105.8164)
		(width 0.381)
		(layer "B.Cu")
		(net "XP3R3V_FPGA")
	)
	(segment
		(start 22.7584 -61.0108)
		(end 21.59 -61.0108)
		(width 0.381)
		(layer "B.Cu")
		(net "XP3R3V_FPGA")
	)
	(segment
		(start 105.347262 -49.32299)
		(end 105.847134 -49.822862)
		(width 0.381)
		(layer "B.Cu")
		(net "XP3R3V_FPGA")
	)
	(segment
		(start 83.947 -58.039)
		(end 85.2424 -58.039)
		(width 0.381)
		(layer "B.Cu")
		(net "XP3R3V_FPGA")
	)
	(segment
		(start 109.475524 -48.20412)
		(end 109.475524 -48.194468)
		(width 0.381)
		(layer "B.Cu")
		(net "XP3R3V_FPGA")
	)
	(segment
		(start 100.847144 -51.823112)
		(end 101.34727 -51.322986)
		(width 0.381)
		(layer "B.Cu")
		(net "XP3R3V_FPGA")
	)
	(segment
		(start 132.6134 -106.3244)
		(end 132.6134 -105.791)
		(width 0.381)
		(layer "B.Cu")
		(net "XP3R3V_FPGA")
	)
	(segment
		(start 136.525 -77.216)
		(end 137.16 -77.851)
		(width 0.381)
		(layer "B.Cu")
		(net "XP3R3V_FPGA")
	)
	(segment
		(start 89.0524 -85.598)
		(end 90.17 -85.598)
		(width 0.381)
		(layer "B.Cu")
		(net "XP3R3V_FPGA")
	)
	(segment
		(start 108.6612 -74.3966)
		(end 107.9246 -74.3966)
		(width 0.381)
		(layer "B.Cu")
		(net "XP3R3V_FPGA")
	)
	(segment
		(start 15.4686 -15.621)
		(end 16.129 -15.621)
		(width 0.4572)
		(layer "B.Cu")
		(net "XP3R3V_FPGA")
	)
	(segment
		(start 22.4282 -41.6306)
		(end 21.59 -41.6306)
		(width 0.381)
		(layer "B.Cu")
		(net "XP3R3V_FPGA")
	)
	(segment
		(start 101.092 -87.0966)
		(end 101.092 -85.471)
		(width 0.381)
		(layer "B.Cu")
		(net "XP3R3V_FPGA")
	)
	(segment
		(start 107.84713 -53.822854)
		(end 107.84713 -53.823108)
		(width 0.381)
		(layer "B.Cu")
		(net "XP3R3V_FPGA")
	)
	(segment
		(start 106.555032 -46.531022)
		(end 106.847132 -46.823122)
		(width 0.381)
		(layer "B.Cu")
		(net "XP3R3V_FPGA")
	)
	(segment
		(start 108.494068 -50.4698)
		(end 109.22 -50.4698)
		(width 0.381)
		(layer "B.Cu")
		(net "XP3R3V_FPGA")
	)
	(segment
		(start 126.8095 -85.6615)
		(end 131.826 -80.645)
		(width 0.381)
		(layer "B.Cu")
		(net "XP3R3V_FPGA")
	)
	(segment
		(start 125.2855 -87.4395)
		(end 125.2855 -86.219284)
		(width 0.381)
		(layer "B.Cu")
		(net "XP3R3V_FPGA")
	)
	(segment
		(start 103.505 -58.7375)
		(end 103.8225 -59.055)
		(width 0.381)
		(layer "B.Cu")
		(net "XP3R3V_FPGA")
	)
	(segment
		(start 140.105638 -15.137638)
		(end 140.081 -15.137638)
		(width 0.381)
		(layer "B.Cu")
		(net "XP3R3V_FPGA")
	)
	(segment
		(start 17.1958 -61.03366)
		(end 17.1958 -61.0108)
		(width 0.381)
		(layer "B.Cu")
		(net "XP3R3V_FPGA")
	)
	(segment
		(start 16.46936 -58.33364)
		(end 16.46936 -60.37326)
		(width 0.381)
		(layer "B.Cu")
		(net "XP3R3V_FPGA")
	)
	(segment
		(start 110.871 -105.41)
		(end 113.538 -108.077)
		(width 0.381)
		(layer "In2.Cu")
		(net "XP3R3V_FPGA")
	)
	(segment
		(start 97.917 -85.598)
		(end 93.98 -85.598)
		(width 0.381)
		(layer "In2.Cu")
		(net "XP3R3V_FPGA")
	)
	(segment
		(start 22.6314 -74.041)
		(end 19.812 -74.041)
		(width 0.381)
		(layer "In2.Cu")
		(net "XP3R3V_FPGA")
	)
	(segment
		(start 105.41 -84.963)
		(end 102.743 -84.963)
		(width 0.381)
		(layer "In2.Cu")
		(net "XP3R3V_FPGA")
	)
	(segment
		(start 98.298 -85.217)
		(end 97.917 -85.598)
		(width 0.381)
		(layer "In2.Cu")
		(net "XP3R3V_FPGA")
	)
	(segment
		(start 78.8924 -85.09)
		(end 78.0796 -84.2772)
		(width 0.381)
		(layer "In2.Cu")
		(net "XP3R3V_FPGA")
	)
	(segment
		(start 90.297 -83.185)
		(end 93.853 -83.185)
		(width 0.381)
		(layer "In2.Cu")
		(net "XP3R3V_FPGA")
	)
	(segment
		(start 142.748 -64.73698)
		(end 142.748 -66.0146)
		(width 0.381)
		(layer "In2.Cu")
		(net "XP3R3V_FPGA")
	)
	(segment
		(start 89.027 -82.169)
		(end 90.17 -83.312)
		(width 0.381)
		(layer "In2.Cu")
		(net "XP3R3V_FPGA")
	)
	(segment
		(start 24.461216 -75.057)
		(end 24.397716 -74.9935)
		(width 0.381)
		(layer "In2.Cu")
		(net "XP3R3V_FPGA")
	)
	(segment
		(start 17.1958 -61.0108)
		(end 20.828 -61.0108)
		(width 0.381)
		(layer "In2.Cu")
		(net "XP3R3V_FPGA")
	)
	(segment
		(start 102.743 -84.963)
		(end 102.235 -85.471)
		(width 0.381)
		(layer "In2.Cu")
		(net "XP3R3V_FPGA")
	)
	(segment
		(start 35.5854 -77.9526)
		(end 35.1663 -77.5335)
		(width 0.381)
		(layer "In2.Cu")
		(net "XP3R3V_FPGA")
	)
	(segment
		(start 78.0796 -83.2104)
		(end 78.486 -82.804)
		(width 0.381)
		(layer "In2.Cu")
		(net "XP3R3V_FPGA")
	)
	(segment
		(start 136.407144 -76.559156)
		(end 137.668 -75.2983)
		(width 0.381)
		(layer "In2.Cu")
		(net "XP3R3V_FPGA")
	)
	(segment
		(start 137.414 -71.3486)
		(end 140.8176 -67.945)
		(width 0.381)
		(layer "In2.Cu")
		(net "XP3R3V_FPGA")
	)
	(segment
		(start 131.699 -105.791)
		(end 132.6134 -105.791)
		(width 0.381)
		(layer "In2.Cu")
		(net "XP3R3V_FPGA")
	)
	(segment
		(start 112.268 -98.171)
		(end 109.728 -100.711)
		(width 0.381)
		(layer "In2.Cu")
		(net "XP3R3V_FPGA")
	)
	(segment
		(start 113.538 -108.077)
		(end 129.413 -108.077)
		(width 0.381)
		(layer "In2.Cu")
		(net "XP3R3V_FPGA")
	)
	(segment
		(start 111.4806 -97.1296)
		(end 112.522 -98.171)
		(width 0.381)
		(layer "In2.Cu")
		(net "XP3R3V_FPGA")
	)
	(segment
		(start 137.7315 -72.1233)
		(end 137.414 -71.8058)
		(width 0.381)
		(layer "In2.Cu")
		(net "XP3R3V_FPGA")
	)
	(segment
		(start 112.522 -98.171)
		(end 112.268 -98.171)
		(width 0.381)
		(layer "In2.Cu")
		(net "XP3R3V_FPGA")
	)
	(segment
		(start 100.838 -85.217)
		(end 98.298 -85.217)
		(width 0.381)
		(layer "In2.Cu")
		(net "XP3R3V_FPGA")
	)
	(segment
		(start 101.854 -97.282)
		(end 101.854 -96.901)
		(width 0.381)
		(layer "In2.Cu")
		(net "XP3R3V_FPGA")
	)
	(segment
		(start 90.17 -83.312)
		(end 90.297 -83.185)
		(width 0.381)
		(layer "In2.Cu")
		(net "XP3R3V_FPGA")
	)
	(segment
		(start 106.045 -85.598)
		(end 105.41 -84.963)
		(width 0.381)
		(layer "In2.Cu")
		(net "XP3R3V_FPGA")
	)
	(segment
		(start 136.407144 -77.098144)
		(end 136.407144 -76.559156)
		(width 0.381)
		(layer "In2.Cu")
		(net "XP3R3V_FPGA")
	)
	(segment
		(start 90.932 -85.217)
		(end 93.599 -85.217)
		(width 0.381)
		(layer "In2.Cu")
		(net "XP3R3V_FPGA")
	)
	(segment
		(start 24.397716 -74.9935)
		(end 23.5839 -74.9935)
		(width 0.381)
		(layer "In2.Cu")
		(net "XP3R3V_FPGA")
	)
	(segment
		(start 137.7315 -75.2348)
		(end 137.7315 -72.1233)
		(width 0.381)
		(layer "In2.Cu")
		(net "XP3R3V_FPGA")
	)
	(segment
		(start 109.982 -95.758)
		(end 111.3536 -97.1296)
		(width 0.381)
		(layer "In2.Cu")
		(net "XP3R3V_FPGA")
	)
	(segment
		(start 107.569 -105.537)
		(end 108.331 -104.775)
		(width 0.381)
		(layer "In2.Cu")
		(net "XP3R3V_FPGA")
	)
	(segment
		(start 136.525 -77.216)
		(end 136.407144 -77.098144)
		(width 0.381)
		(layer "In2.Cu")
		(net "XP3R3V_FPGA")
	)
	(segment
		(start 35.1663 -77.5335)
		(end 35.103308 -77.5335)
		(width 0.381)
		(layer "In2.Cu")
		(net "XP3R3V_FPGA")
	)
	(segment
		(start 90.17 -85.598)
		(end 90.551 -85.598)
		(width 0.381)
		(layer "In2.Cu")
		(net "XP3R3V_FPGA")
	)
	(segment
		(start 115.189 -96.901)
		(end 113.792 -96.901)
		(width 0.381)
		(layer "In2.Cu")
		(net "XP3R3V_FPGA")
	)
	(segment
		(start 100.965 -98.171)
		(end 101.854 -97.282)
		(width 0.381)
		(layer "In2.Cu")
		(net "XP3R3V_FPGA")
	)
	(segment
		(start 109.728 -100.711)
		(end 110.871 -101.854)
		(width 0.381)
		(layer "In2.Cu")
		(net "XP3R3V_FPGA")
	)
	(segment
		(start 35.103308 -77.5335)
		(end 34.608008 -77.0382)
		(width 0.381)
		(layer "In2.Cu")
		(net "XP3R3V_FPGA")
	)
	(segment
		(start 20.828 -61.0108)
		(end 21.7678 -60.071)
		(width 0.381)
		(layer "In2.Cu")
		(net "XP3R3V_FPGA")
	)
	(segment
		(start 137.668 -75.2983)
		(end 137.7315 -75.2348)
		(width 0.381)
		(layer "In2.Cu")
		(net "XP3R3V_FPGA")
	)
	(segment
		(start 101.854 -96.901)
		(end 102.997 -95.758)
		(width 0.381)
		(layer "In2.Cu")
		(net "XP3R3V_FPGA")
	)
	(segment
		(start 142.748 -66.0146)
		(end 140.8176 -67.945)
		(width 0.381)
		(layer "In2.Cu")
		(net "XP3R3V_FPGA")
	)
	(segment
		(start 30.0482 -77.0382)
		(end 28.067 -75.057)
		(width 0.381)
		(layer "In2.Cu")
		(net "XP3R3V_FPGA")
	)
	(segment
		(start 28.067 -75.057)
		(end 24.461216 -75.057)
		(width 0.381)
		(layer "In2.Cu")
		(net "XP3R3V_FPGA")
	)
	(segment
		(start 34.608008 -77.0382)
		(end 30.0482 -77.0382)
		(width 0.381)
		(layer "In2.Cu")
		(net "XP3R3V_FPGA")
	)
	(segment
		(start 113.792 -96.901)
		(end 112.522 -98.171)
		(width 0.381)
		(layer "In2.Cu")
		(net "XP3R3V_FPGA")
	)
	(segment
		(start 137.414 -71.501)
		(end 137.414 -71.3486)
		(width 0.381)
		(layer "In2.Cu")
		(net "XP3R3V_FPGA")
	)
	(segment
		(start 101.092 -85.471)
		(end 100.838 -85.217)
		(width 0.381)
		(layer "In2.Cu")
		(net "XP3R3V_FPGA")
	)
	(segment
		(start 90.551 -85.598)
		(end 90.932 -85.217)
		(width 0.381)
		(layer "In2.Cu")
		(net "XP3R3V_FPGA")
	)
	(segment
		(start 93.853 -83.185)
		(end 94.234 -82.804)
		(width 0.381)
		(layer "In2.Cu")
		(net "XP3R3V_FPGA")
	)
	(segment
		(start 110.871 -101.854)
		(end 110.871 -105.41)
		(width 0.381)
		(layer "In2.Cu")
		(net "XP3R3V_FPGA")
	)
	(segment
		(start 109.22 -100.711)
		(end 109.728 -100.711)
		(width 0.381)
		(layer "In2.Cu")
		(net "XP3R3V_FPGA")
	)
	(segment
		(start 111.3536 -97.1296)
		(end 111.4806 -97.1296)
		(width 0.381)
		(layer "In2.Cu")
		(net "XP3R3V_FPGA")
	)
	(segment
		(start 78.486 -82.804)
		(end 78.8924 -82.804)
		(width 0.381)
		(layer "In2.Cu")
		(net "XP3R3V_FPGA")
	)
	(segment
		(start 108.331 -104.775)
		(end 108.331 -101.6)
		(width 0.381)
		(layer "In2.Cu")
		(net "XP3R3V_FPGA")
	)
	(segment
		(start 98.8314 -97.6884)
		(end 99.314 -98.171)
		(width 0.381)
		(layer "In2.Cu")
		(net "XP3R3V_FPGA")
	)
	(segment
		(start 93.599 -85.217)
		(end 93.98 -85.598)
		(width 0.381)
		(layer "In2.Cu")
		(net "XP3R3V_FPGA")
	)
	(segment
		(start 129.413 -108.077)
		(end 131.699 -105.791)
		(width 0.381)
		(layer "In2.Cu")
		(net "XP3R3V_FPGA")
	)
	(segment
		(start 86.7156 -82.169)
		(end 89.027 -82.169)
		(width 0.381)
		(layer "In2.Cu")
		(net "XP3R3V_FPGA")
	)
	(segment
		(start 78.0796 -84.2772)
		(end 78.0796 -83.2104)
		(width 0.381)
		(layer "In2.Cu")
		(net "XP3R3V_FPGA")
	)
	(segment
		(start 102.997 -95.758)
		(end 109.982 -95.758)
		(width 0.381)
		(layer "In2.Cu")
		(net "XP3R3V_FPGA")
	)
	(segment
		(start 108.331 -101.6)
		(end 109.22 -100.711)
		(width 0.381)
		(layer "In2.Cu")
		(net "XP3R3V_FPGA")
	)
	(segment
		(start 102.235 -85.471)
		(end 101.092 -85.471)
		(width 0.381)
		(layer "In2.Cu")
		(net "XP3R3V_FPGA")
	)
	(segment
		(start 97.5106 -97.6884)
		(end 98.8314 -97.6884)
		(width 0.381)
		(layer "In2.Cu")
		(net "XP3R3V_FPGA")
	)
	(segment
		(start 137.414 -71.8058)
		(end 137.414 -71.501)
		(width 0.381)
		(layer "In2.Cu")
		(net "XP3R3V_FPGA")
	)
	(segment
		(start 23.5839 -74.9935)
		(end 22.6314 -74.041)
		(width 0.381)
		(layer "In2.Cu")
		(net "XP3R3V_FPGA")
	)
	(segment
		(start 99.314 -98.171)
		(end 100.965 -98.171)
		(width 0.381)
		(layer "In2.Cu")
		(net "XP3R3V_FPGA")
	)
	(segment
		(start 118.729506 -21.447506)
		(end 118.237 -20.955)
		(width 0.381)
		(layer "In7.Cu")
		(net "XP3R3V_FPGA")
	)
	(segment
		(start 118.237 -20.955)
		(end 118.237 -19.939)
		(width 0.381)
		(layer "In7.Cu")
		(net "XP3R3V_FPGA")
	)
	(segment
		(start 89.789 -85.598)
		(end 90.17 -85.598)
		(width 0.381)
		(layer "In7.Cu")
		(net "XP3R3V_FPGA")
	)
	(segment
		(start 151.765 -107.1626)
		(end 151.765 -106.299)
		(width 0.381)
		(layer "In7.Cu")
		(net "XP3R3V_FPGA")
	)
	(segment
		(start 136.3726 -107.1626)
		(end 135.001 -105.791)
		(width 0.381)
		(layer "In7.Cu")
		(net "XP3R3V_FPGA")
	)
	(segment
		(start 128.905 -34.925)
		(end 128.905 -40.64)
		(width 0.381)
		(layer "In7.Cu")
		(net "XP3R3V_FPGA")
	)
	(segment
		(start 117.729 -23.368)
		(end 117.729 -22.987)
		(width 0.381)
		(layer "In7.Cu")
		(net "XP3R3V_FPGA")
	)
	(segment
		(start 90.17 -83.312)
		(end 89.408 -84.074)
		(width 0.381)
		(layer "In7.Cu")
		(net "XP3R3V_FPGA")
	)
	(segment
		(start 81.8388 -85.979)
		(end 79.7814 -85.979)
		(width 0.381)
		(layer "In7.Cu")
		(net "XP3R3V_FPGA")
	)
	(segment
		(start 154.813 -102.362)
		(end 156.083 -101.092)
		(width 0.381)
		(layer "In7.Cu")
		(net "XP3R3V_FPGA")
	)
	(segment
		(start 39.7002 -14.8336)
		(end 43.5864 -18.7198)
		(width 0.381)
		(layer "In7.Cu")
		(net "XP3R3V_FPGA")
	)
	(segment
		(start 125.984 -41.45026)
		(end 125.984 -41.402)
		(width 0.381)
		(layer "In7.Cu")
		(net "XP3R3V_FPGA")
	)
	(segment
		(start 43.5864 -18.7198)
		(end 46.92396 -18.7198)
		(width 0.381)
		(layer "In7.Cu")
		(net "XP3R3V_FPGA")
	)
	(segment
		(start 79.7814 -85.979)
		(end 78.8924 -85.09)
		(width 0.381)
		(layer "In7.Cu")
		(net "XP3R3V_FPGA")
	)
	(segment
		(start 151.765 -106.299)
		(end 154.813 -103.251)
		(width 0.381)
		(layer "In7.Cu")
		(net "XP3R3V_FPGA")
	)
	(segment
		(start 127.4445 -42.1005)
		(end 126.63424 -42.1005)
		(width 0.381)
		(layer "In7.Cu")
		(net "XP3R3V_FPGA")
	)
	(segment
		(start 38.93058 -14.8336)
		(end 39.7002 -14.8336)
		(width 0.381)
		(layer "In7.Cu")
		(net "XP3R3V_FPGA")
	)
	(segment
		(start 148.336 -107.1626)
		(end 151.765 -107.1626)
		(width 0.381)
		(layer "In7.Cu")
		(net "XP3R3V_FPGA")
	)
	(segment
		(start 117.729 -22.987)
		(end 118.729506 -21.986494)
		(width 0.381)
		(layer "In7.Cu")
		(net "XP3R3V_FPGA")
	)
	(segment
		(start 94.869 -62.738)
		(end 94.869 -64.2366)
		(width 0.381)
		(layer "In7.Cu")
		(net "XP3R3V_FPGA")
	)
	(segment
		(start 128.905 -40.64)
		(end 127.4445 -42.1005)
		(width 0.381)
		(layer "In7.Cu")
		(net "XP3R3V_FPGA")
	)
	(segment
		(start 51.943 -17.2847)
		(end 52.01158 -17.21612)
		(width 0.381)
		(layer "In7.Cu")
		(net "XP3R3V_FPGA")
	)
	(segment
		(start 128.0033 -34.0233)
		(end 128.905 -34.925)
		(width 0.381)
		(layer "In7.Cu")
		(net "XP3R3V_FPGA")
	)
	(segment
		(start 126.63424 -42.1005)
		(end 125.984 -41.45026)
		(width 0.381)
		(layer "In7.Cu")
		(net "XP3R3V_FPGA")
	)
	(segment
		(start 89.408 -85.217)
		(end 89.789 -85.598)
		(width 0.381)
		(layer "In7.Cu")
		(net "XP3R3V_FPGA")
	)
	(segment
		(start 22.1488 -60.071)
		(end 21.7678 -60.071)
		(width 0.381)
		(layer "In7.Cu")
		(net "XP3R3V_FPGA")
	)
	(segment
		(start 126.365 -26.035)
		(end 128.524 -26.035)
		(width 0.381)
		(layer "In7.Cu")
		(net "XP3R3V_FPGA")
	)
	(segment
		(start 128.0033 -33.909)
		(end 128.0033 -34.0233)
		(width 0.381)
		(layer "In7.Cu")
		(net "XP3R3V_FPGA")
	)
	(segment
		(start 89.408 -84.074)
		(end 89.408 -85.217)
		(width 0.381)
		(layer "In7.Cu")
		(net "XP3R3V_FPGA")
	)
	(segment
		(start 135.001 -105.791)
		(end 132.6134 -105.791)
		(width 0.381)
		(layer "In7.Cu")
		(net "XP3R3V_FPGA")
	)
	(segment
		(start 46.3804 -73.533)
		(end 45.1612 -72.3138)
		(width 0.381)
		(layer "In7.Cu")
		(net "XP3R3V_FPGA")
	)
	(segment
		(start 129.413 -25.146)
		(end 133.3246 -25.146)
		(width 0.381)
		(layer "In7.Cu")
		(net "XP3R3V_FPGA")
	)
	(segment
		(start 128.524 -26.035)
		(end 129.413 -25.146)
		(width 0.381)
		(layer "In7.Cu")
		(net "XP3R3V_FPGA")
	)
	(segment
		(start 154.813 -103.251)
		(end 154.813 -102.362)
		(width 0.381)
		(layer "In7.Cu")
		(net "XP3R3V_FPGA")
	)
	(segment
		(start 117.729 -23.368)
		(end 117.89918 -23.53818)
		(width 0.381)
		(layer "In7.Cu")
		(net "XP3R3V_FPGA")
	)
	(segment
		(start 25.9588 -66.929)
		(end 25.9588 -63.881)
		(width 0.381)
		(layer "In7.Cu")
		(net "XP3R3V_FPGA")
	)
	(segment
		(start 45.1612 -72.3138)
		(end 31.3436 -72.3138)
		(width 0.381)
		(layer "In7.Cu")
		(net "XP3R3V_FPGA")
	)
	(segment
		(start 25.9588 -63.881)
		(end 22.1488 -60.071)
		(width 0.381)
		(layer "In7.Cu")
		(net "XP3R3V_FPGA")
	)
	(segment
		(start 121.031 -25.019)
		(end 125.349 -25.019)
		(width 0.381)
		(layer "In7.Cu")
		(net "XP3R3V_FPGA")
	)
	(segment
		(start 117.89918 -23.53818)
		(end 119.55018 -23.53818)
		(width 0.381)
		(layer "In7.Cu")
		(net "XP3R3V_FPGA")
	)
	(segment
		(start 148.336 -107.1626)
		(end 136.3726 -107.1626)
		(width 0.381)
		(layer "In7.Cu")
		(net "XP3R3V_FPGA")
	)
	(segment
		(start 48.35906 -17.2847)
		(end 51.943 -17.2847)
		(width 0.381)
		(layer "In7.Cu")
		(net "XP3R3V_FPGA")
	)
	(segment
		(start 119.55018 -23.53818)
		(end 121.031 -25.019)
		(width 0.381)
		(layer "In7.Cu")
		(net "XP3R3V_FPGA")
	)
	(segment
		(start 118.729506 -21.986494)
		(end 118.729506 -21.447506)
		(width 0.381)
		(layer "In7.Cu")
		(net "XP3R3V_FPGA")
	)
	(segment
		(start 46.92396 -18.7198)
		(end 48.35906 -17.2847)
		(width 0.381)
		(layer "In7.Cu")
		(net "XP3R3V_FPGA")
	)
	(segment
		(start 31.3436 -72.3138)
		(end 25.9588 -66.929)
		(width 0.381)
		(layer "In7.Cu")
		(net "XP3R3V_FPGA")
	)
	(segment
		(start 125.349 -25.019)
		(end 126.365 -26.035)
		(width 0.381)
		(layer "In7.Cu")
		(net "XP3R3V_FPGA")
	)
	(segment
		(start 94.869 -64.2366)
		(end 95.4532 -64.8208)
		(width 0.381)
		(layer "In7.Cu")
		(net "XP3R3V_FPGA")
	)
	(segment
		(start 110.847124 -33.822894)
		(end 111.346996 -33.323022)
		(width 0.381)
		(layer "F.Cu")
		(net "XP2R5V_FPGA")
	)
	(segment
		(start 116.847112 -35.82289)
		(end 117.346984 -35.323018)
		(width 0.381)
		(layer "F.Cu")
		(net "XP2R5V_FPGA")
	)
	(segment
		(start 94.7674 -26.924)
		(end 94.7928 -26.924)
		(width 0.381)
		(layer "F.Cu")
		(net "XP2R5V_FPGA")
	)
	(segment
		(start 94.8944 -93.4974)
		(end 92.964 -91.567)
		(width 0.381)
		(layer "F.Cu")
		(net "XP2R5V_FPGA")
	)
	(segment
		(start 93.769688 -26.118312)
		(end 94.029276 -26.3779)
		(width 0.381)
		(layer "F.Cu")
		(net "XP2R5V_FPGA")
	)
	(segment
		(start 127.98044 -31.5341)
		(end 127.5461 -31.5341)
		(width 0.381)
		(layer "F.Cu")
		(net "XP2R5V_FPGA")
	)
	(segment
		(start 112.84712 -37.82314)
		(end 113.346992 -37.323268)
		(width 0.381)
		(layer "F.Cu")
		(net "XP2R5V_FPGA")
	)
	(segment
		(start 117.475 -29.464)
		(end 116.9416 -28.9306)
		(width 0.381)
		(layer "F.Cu")
		(net "XP2R5V_FPGA")
	)
	(segment
		(start 117.475 -29.718)
		(end 117.475 -29.464)
		(width 0.381)
		(layer "F.Cu")
		(net "XP2R5V_FPGA")
	)
	(segment
		(start 118.847108 -39.823136)
		(end 119.34698 -39.323264)
		(width 0.381)
		(layer "F.Cu")
		(net "XP2R5V_FPGA")
	)
	(segment
		(start 105.847134 -38.823138)
		(end 105.347262 -38.323266)
		(width 0.381)
		(layer "F.Cu")
		(net "XP2R5V_FPGA")
	)
	(segment
		(start 94.2213 -26.3779)
		(end 94.7674 -26.924)
		(width 0.381)
		(layer "F.Cu")
		(net "XP2R5V_FPGA")
	)
	(segment
		(start 127.5461 -31.5341)
		(end 126.9746 -32.1056)
		(width 0.381)
		(layer "F.Cu")
		(net "XP2R5V_FPGA")
	)
	(segment
		(start 119.847106 -36.823142)
		(end 120.346978 -36.32327)
		(width 0.381)
		(layer "F.Cu")
		(net "XP2R5V_FPGA")
	)
	(segment
		(start 100.84689 -33.822894)
		(end 100.347018 -33.323022)
		(width 0.381)
		(layer "F.Cu")
		(net "XP2R5V_FPGA")
	)
	(segment
		(start 106.847132 -35.82289)
		(end 106.34726 -35.323018)
		(width 0.381)
		(layer "F.Cu")
		(net "XP2R5V_FPGA")
	)
	(segment
		(start 94.8944 -97.4344)
		(end 94.8944 -93.4974)
		(width 0.381)
		(layer "F.Cu")
		(net "XP2R5V_FPGA")
	)
	(segment
		(start 93.9292 -27.813)
		(end 93.80474 -27.813)
		(width 0.381)
		(layer "F.Cu")
		(net "XP2R5V_FPGA")
	)
	(segment
		(start 115.062 -28.9306)
		(end 116.459 -28.9306)
		(width 0.381)
		(layer "F.Cu")
		(net "XP2R5V_FPGA")
	)
	(segment
		(start 94.029276 -26.3779)
		(end 94.2213 -26.3779)
		(width 0.381)
		(layer "F.Cu")
		(net "XP2R5V_FPGA")
	)
	(segment
		(start 115.847114 -38.823138)
		(end 116.346986 -38.323266)
		(width 0.381)
		(layer "F.Cu")
		(net "XP2R5V_FPGA")
	)
	(segment
		(start 94.8182 -26.924)
		(end 93.9292 -27.813)
		(width 0.381)
		(layer "F.Cu")
		(net "XP2R5V_FPGA")
	)
	(segment
		(start 96.393 -98.933)
		(end 94.8944 -97.4344)
		(width 0.381)
		(layer "F.Cu")
		(net "XP2R5V_FPGA")
	)
	(segment
		(start 116.9416 -28.9306)
		(end 116.459 -28.9306)
		(width 0.381)
		(layer "F.Cu")
		(net "XP2R5V_FPGA")
	)
	(segment
		(start 94.7928 -26.924)
		(end 94.8182 -26.924)
		(width 0.381)
		(layer "F.Cu")
		(net "XP2R5V_FPGA")
	)
	(segment
		(start 127.55626 -32.68726)
		(end 127.9906 -32.68726)
		(width 0.381)
		(layer "F.Cu")
		(net "XP2R5V_FPGA")
	)
	(segment
		(start 137.2616 -19.1516)
		(end 137.2616 -17.526)
		(width 0.381)
		(layer "F.Cu")
		(net "XP2R5V_FPGA")
	)
	(segment
		(start 103.847138 -34.822892)
		(end 103.347266 -34.32302)
		(width 0.381)
		(layer "F.Cu")
		(net "XP2R5V_FPGA")
	)
	(segment
		(start 138.303 -20.193)
		(end 137.2616 -19.1516)
		(width 0.381)
		(layer "F.Cu")
		(net "XP2R5V_FPGA")
	)
	(segment
		(start 113.847118 -34.822892)
		(end 114.34699 -34.32302)
		(width 0.381)
		(layer "F.Cu")
		(net "XP2R5V_FPGA")
	)
	(segment
		(start 96.393 -106.045)
		(end 96.393 -98.933)
		(width 0.381)
		(layer "F.Cu")
		(net "XP2R5V_FPGA")
	)
	(segment
		(start 109.847126 -36.823142)
		(end 110.346998 -36.32327)
		(width 0.381)
		(layer "F.Cu")
		(net "XP2R5V_FPGA")
	)
	(segment
		(start 126.9746 -32.1056)
		(end 127.55626 -32.68726)
		(width 0.381)
		(layer "F.Cu")
		(net "XP2R5V_FPGA")
	)
	(segment
		(start 92.964 -91.567)
		(end 92.964 -89.1159)
		(width 0.381)
		(layer "F.Cu")
		(net "XP2R5V_FPGA")
	)
	(via
		(at 117.475 -29.718)
		(size 0.508)
		(drill 0.254)
		(layers "F.Cu" "B.Cu")
		(net "XP2R5V_FPGA")
	)
	(via
		(at 100.347018 -33.323022)
		(size 0.4572)
		(drill 0.2032)
		(layers "F.Cu" "B.Cu")
		(net "XP2R5V_FPGA")
	)
	(via
		(at 139.446 -19.868642)
		(size 0.508)
		(drill 0.254)
		(layers "F.Cu" "B.Cu")
		(net "XP2R5V_FPGA")
	)
	(via
		(at 127.9906 -32.68726)
		(size 0.508)
		(drill 0.254)
		(layers "F.Cu" "B.Cu")
		(net "XP2R5V_FPGA")
	)
	(via
		(at 96.393 -106.045)
		(size 0.508)
		(drill 0.254)
		(layers "F.Cu" "B.Cu")
		(net "XP2R5V_FPGA")
	)
	(via
		(at 93.769688 -26.118312)
		(size 0.508)
		(drill 0.254)
		(layers "F.Cu" "B.Cu")
		(net "XP2R5V_FPGA")
	)
	(via
		(at 116.346986 -38.323266)
		(size 0.4572)
		(drill 0.2032)
		(layers "F.Cu" "B.Cu")
		(net "XP2R5V_FPGA")
	)
	(via
		(at 113.919 -25.527)
		(size 0.508)
		(drill 0.254)
		(layers "F.Cu" "B.Cu")
		(net "XP2R5V_FPGA")
	)
	(via
		(at 117.346984 -35.323018)
		(size 0.4572)
		(drill 0.2032)
		(layers "F.Cu" "B.Cu")
		(net "XP2R5V_FPGA")
	)
	(via
		(at 110.346998 -36.32327)
		(size 0.4572)
		(drill 0.2032)
		(layers "F.Cu" "B.Cu")
		(net "XP2R5V_FPGA")
	)
	(via
		(at 93.80474 -27.813)
		(size 0.508)
		(drill 0.254)
		(layers "F.Cu" "B.Cu")
		(net "XP2R5V_FPGA")
	)
	(via
		(at 127.98044 -31.5341)
		(size 0.508)
		(drill 0.254)
		(layers "F.Cu" "B.Cu")
		(net "XP2R5V_FPGA")
	)
	(via
		(at 103.347266 -34.32302)
		(size 0.4572)
		(drill 0.2032)
		(layers "F.Cu" "B.Cu")
		(net "XP2R5V_FPGA")
	)
	(via
		(at 153.416 -101.092)
		(size 0.508)
		(drill 0.254)
		(layers "F.Cu" "B.Cu")
		(net "XP2R5V_FPGA")
	)
	(via
		(at 119.34698 -39.323264)
		(size 0.4572)
		(drill 0.2032)
		(layers "F.Cu" "B.Cu")
		(net "XP2R5V_FPGA")
	)
	(via
		(at 113.346992 -37.323268)
		(size 0.4572)
		(drill 0.2032)
		(layers "F.Cu" "B.Cu")
		(net "XP2R5V_FPGA")
	)
	(via
		(at 140.97 -102.108)
		(size 0.508)
		(drill 0.254)
		(layers "F.Cu" "B.Cu")
		(net "XP2R5V_FPGA")
	)
	(via
		(at 120.346978 -36.32327)
		(size 0.4572)
		(drill 0.2032)
		(layers "F.Cu" "B.Cu")
		(net "XP2R5V_FPGA")
	)
	(via
		(at 78.867 -81.534)
		(size 0.508)
		(drill 0.254)
		(layers "F.Cu" "B.Cu")
		(net "XP2R5V_FPGA")
	)
	(via
		(at 106.34726 -35.323018)
		(size 0.4572)
		(drill 0.2032)
		(layers "F.Cu" "B.Cu")
		(net "XP2R5V_FPGA")
	)
	(via
		(at 114.34699 -34.32302)
		(size 0.4572)
		(drill 0.2032)
		(layers "F.Cu" "B.Cu")
		(net "XP2R5V_FPGA")
	)
	(via
		(at 105.347262 -38.323266)
		(size 0.4572)
		(drill 0.2032)
		(layers "F.Cu" "B.Cu")
		(net "XP2R5V_FPGA")
	)
	(via
		(at 139.5476 -20.7264)
		(size 0.508)
		(drill 0.254)
		(layers "F.Cu" "B.Cu")
		(net "XP2R5V_FPGA")
	)
	(via
		(at 111.346996 -33.323022)
		(size 0.4572)
		(drill 0.2032)
		(layers "F.Cu" "B.Cu")
		(net "XP2R5V_FPGA")
	)
	(via
		(at 92.964 -89.1159)
		(size 0.508)
		(drill 0.254)
		(layers "F.Cu" "B.Cu")
		(net "XP2R5V_FPGA")
	)
	(via
		(at 138.2522 -22.1234)
		(size 0.508)
		(drill 0.254)
		(layers "F.Cu" "B.Cu")
		(net "XP2R5V_FPGA")
	)
	(segment
		(start 116.346986 -38.323266)
		(end 116.846858 -38.823138)
		(width 0.381)
		(layer "B.Cu")
		(net "XP2R5V_FPGA")
	)
	(segment
		(start 93.80474 -27.813)
		(end 93.93174 -27.686)
		(width 0.381)
		(layer "B.Cu")
		(net "XP2R5V_FPGA")
	)
	(segment
		(start 109.836204 -36.32327)
		(end 110.346998 -36.32327)
		(width 0.381)
		(layer "B.Cu")
		(net "XP2R5V_FPGA")
	)
	(segment
		(start 109.4486 -36.710874)
		(end 109.836204 -36.32327)
		(width 0.381)
		(layer "B.Cu")
		(net "XP2R5V_FPGA")
	)
	(segment
		(start 93.987112 -26.118312)
		(end 94.7928 -26.924)
		(width 0.381)
		(layer "B.Cu")
		(net "XP2R5V_FPGA")
	)
	(segment
		(start 105.847134 -37.823394)
		(end 105.347262 -38.323266)
		(width 0.381)
		(layer "B.Cu")
		(net "XP2R5V_FPGA")
	)
	(segment
		(start 114.846608 -34.822638)
		(end 114.847116 -34.822638)
		(width 0.381)
		(layer "B.Cu")
		(net "XP2R5V_FPGA")
	)
	(segment
		(start 105.847134 -38.823138)
		(end 105.347262 -38.323266)
		(width 0.381)
		(layer "B.Cu")
		(net "XP2R5V_FPGA")
	)
	(segment
		(start 77.9272 -81.534)
		(end 78.867 -81.534)
		(width 0.381)
		(layer "B.Cu")
		(net "XP2R5V_FPGA")
	)
	(segment
		(start 112.141 -27.4066)
		(end 113.0554 -27.4066)
		(width 0.381)
		(layer "B.Cu")
		(net "XP2R5V_FPGA")
	)
	(segment
		(start 113.919 -26.543)
		(end 113.919 -25.527)
		(width 0.381)
		(layer "B.Cu")
		(net "XP2R5V_FPGA")
	)
	(segment
		(start 118.847108 -39.823136)
		(end 119.34698 -39.323264)
		(width 0.381)
		(layer "B.Cu")
		(net "XP2R5V_FPGA")
	)
	(segment
		(start 105.847134 -37.82314)
		(end 105.847134 -37.823394)
		(width 0.381)
		(layer "B.Cu")
		(net "XP2R5V_FPGA")
	)
	(segment
		(start 103.347266 -34.32302)
		(end 102.847394 -34.822892)
		(width 0.381)
		(layer "B.Cu")
		(net "XP2R5V_FPGA")
	)
	(segment
		(start 110.346998 -36.32327)
		(end 110.84687 -36.823142)
		(width 0.381)
		(layer "B.Cu")
		(net "XP2R5V_FPGA")
	)
	(segment
		(start 127.9906 -32.68726)
		(end 127.58166 -32.68726)
		(width 0.381)
		(layer "B.Cu")
		(net "XP2R5V_FPGA")
	)
	(segment
		(start 140.4366 -103.378)
		(end 140.4366 -102.6414)
		(width 0.381)
		(layer "B.Cu")
		(net "XP2R5V_FPGA")
	)
	(segment
		(start 127.98044 -31.5341)
		(end 127.5207 -31.5341)
		(width 0.381)
		(layer "B.Cu")
		(net "XP2R5V_FPGA")
	)
	(segment
		(start 99.524566 -32.857694)
		(end 99.88169 -32.857694)
		(width 0.381)
		(layer "B.Cu")
		(net "XP2R5V_FPGA")
	)
	(segment
		(start 116.847112 -35.82289)
		(end 117.346984 -35.323018)
		(width 0.381)
		(layer "B.Cu")
		(net "XP2R5V_FPGA")
	)
	(segment
		(start 106.847132 -35.82289)
		(end 106.34726 -35.323018)
		(width 0.381)
		(layer "B.Cu")
		(net "XP2R5V_FPGA")
	)
	(segment
		(start 127.58166 -32.68726)
		(end 126.9746 -32.0802)
		(width 0.381)
		(layer "B.Cu")
		(net "XP2R5V_FPGA")
	)
	(segment
		(start 110.998 -27.4066)
		(end 112.141 -27.4066)
		(width 0.381)
		(layer "B.Cu")
		(net "XP2R5V_FPGA")
	)
	(segment
		(start 127.5207 -31.5341)
		(end 126.9746 -32.0802)
		(width 0.381)
		(layer "B.Cu")
		(net "XP2R5V_FPGA")
	)
	(segment
		(start 110.84687 -36.823142)
		(end 110.847124 -36.823142)
		(width 0.381)
		(layer "B.Cu")
		(net "XP2R5V_FPGA")
	)
	(segment
		(start 120.397778 -36.27247)
		(end 121.073164 -36.27247)
		(width 0.381)
		(layer "B.Cu")
		(net "XP2R5V_FPGA")
	)
	(segment
		(start 113.0554 -27.4066)
		(end 113.919 -26.543)
		(width 0.381)
		(layer "B.Cu")
		(net "XP2R5V_FPGA")
	)
	(segment
		(start 102.847394 -34.822892)
		(end 102.84714 -34.822892)
		(width 0.381)
		(layer "B.Cu")
		(net "XP2R5V_FPGA")
	)
	(segment
		(start 113.346992 -37.323268)
		(end 112.84712 -36.823396)
		(width 0.381)
		(layer "B.Cu")
		(net "XP2R5V_FPGA")
	)
	(segment
		(start 112.84712 -36.823396)
		(end 112.84712 -36.823142)
		(width 0.381)
		(layer "B.Cu")
		(net "XP2R5V_FPGA")
	)
	(segment
		(start 140.4366 -102.6414)
		(end 140.97 -102.108)
		(width 0.381)
		(layer "B.Cu")
		(net "XP2R5V_FPGA")
	)
	(segment
		(start 111.346996 -33.323022)
		(end 111.846868 -33.822894)
		(width 0.381)
		(layer "B.Cu")
		(net "XP2R5V_FPGA")
	)
	(segment
		(start 93.93174 -27.686)
		(end 94.0308 -27.686)
		(width 0.381)
		(layer "B.Cu")
		(net "XP2R5V_FPGA")
	)
	(segment
		(start 94.0308 -27.686)
		(end 94.7928 -26.924)
		(width 0.381)
		(layer "B.Cu")
		(net "XP2R5V_FPGA")
	)
	(segment
		(start 99.88169 -32.857694)
		(end 100.347018 -33.323022)
		(width 0.381)
		(layer "B.Cu")
		(net "XP2R5V_FPGA")
	)
	(segment
		(start 114.34699 -34.32302)
		(end 114.846608 -34.822638)
		(width 0.381)
		(layer "B.Cu")
		(net "XP2R5V_FPGA")
	)
	(segment
		(start 120.346978 -36.32327)
		(end 120.397778 -36.27247)
		(width 0.381)
		(layer "B.Cu")
		(net "XP2R5V_FPGA")
	)
	(segment
		(start 116.846858 -38.823138)
		(end 116.847112 -38.823138)
		(width 0.381)
		(layer "B.Cu")
		(net "XP2R5V_FPGA")
	)
	(segment
		(start 93.769688 -26.118312)
		(end 93.987112 -26.118312)
		(width 0.381)
		(layer "B.Cu")
		(net "XP2R5V_FPGA")
	)
	(segment
		(start 111.846868 -33.822894)
		(end 111.847122 -33.822894)
		(width 0.381)
		(layer "B.Cu")
		(net "XP2R5V_FPGA")
	)
	(segment
		(start 135.89 -109.347)
		(end 155.702 -109.347)
		(width 0.381)
		(layer "In2.Cu")
		(net "XP2R5V_FPGA")
	)
	(segment
		(start 147.193 -88.773)
		(end 147.193 -83.2358)
		(width 0.381)
		(layer "In2.Cu")
		(net "XP2R5V_FPGA")
	)
	(segment
		(start 165.227 -24.638)
		(end 162.814 -22.225)
		(width 0.381)
		(layer "In2.Cu")
		(net "XP2R5V_FPGA")
	)
	(segment
		(start 146.812 -100.076)
		(end 145.796 -99.06)
		(width 0.381)
		(layer "In2.Cu")
		(net "XP2R5V_FPGA")
	)
	(segment
		(start 145.796 -95.504)
		(end 145.415 -95.123)
		(width 0.381)
		(layer "In2.Cu")
		(net "XP2R5V_FPGA")
	)
	(segment
		(start 160.147 -53.086254)
		(end 160.147 -49.779936)
		(width 0.381)
		(layer "In2.Cu")
		(net "XP2R5V_FPGA")
	)
	(segment
		(start 163.2712 -78.9686)
		(end 163.2712 -64.9732)
		(width 0.381)
		(layer "In2.Cu")
		(net "XP2R5V_FPGA")
	)
	(segment
		(start 160.782 -53.721254)
		(end 160.147 -53.086254)
		(width 0.381)
		(layer "In2.Cu")
		(net "XP2R5V_FPGA")
	)
	(segment
		(start 150.1648 -80.264)
		(end 161.9758 -80.264)
		(width 0.381)
		(layer "In2.Cu")
		(net "XP2R5V_FPGA")
	)
	(segment
		(start 155.702 -109.347)
		(end 157.226 -107.823)
		(width 0.381)
		(layer "In2.Cu")
		(net "XP2R5V_FPGA")
	)
	(segment
		(start 144.526 -22.86)
		(end 143.637 -23.749)
		(width 0.381)
		(layer "In2.Cu")
		(net "XP2R5V_FPGA")
	)
	(segment
		(start 139.8778 -23.749)
		(end 138.2522 -22.1234)
		(width 0.381)
		(layer "In2.Cu")
		(net "XP2R5V_FPGA")
	)
	(segment
		(start 162.052 -58.42)
		(end 160.782 -57.15)
		(width 0.381)
		(layer "In2.Cu")
		(net "XP2R5V_FPGA")
	)
	(segment
		(start 143.637 -23.749)
		(end 139.8778 -23.749)
		(width 0.381)
		(layer "In2.Cu")
		(net "XP2R5V_FPGA")
	)
	(segment
		(start 99.1616 -108.8136)
		(end 135.3566 -108.8136)
		(width 0.381)
		(layer "In2.Cu")
		(net "XP2R5V_FPGA")
	)
	(segment
		(start 96.393 -106.045)
		(end 99.1616 -108.8136)
		(width 0.381)
		(layer "In2.Cu")
		(net "XP2R5V_FPGA")
	)
	(segment
		(start 135.3566 -108.8136)
		(end 135.89 -109.347)
		(width 0.381)
		(layer "In2.Cu")
		(net "XP2R5V_FPGA")
	)
	(segment
		(start 161.9758 -80.264)
		(end 163.2712 -78.9686)
		(width 0.381)
		(layer "In2.Cu")
		(net "XP2R5V_FPGA")
	)
	(segment
		(start 143.777716 -101.6635)
		(end 152.8445 -101.6635)
		(width 0.381)
		(layer "In2.Cu")
		(net "XP2R5V_FPGA")
	)
	(segment
		(start 162.052 -63.754)
		(end 162.052 -58.42)
		(width 0.381)
		(layer "In2.Cu")
		(net "XP2R5V_FPGA")
	)
	(segment
		(start 152.527 -18.923)
		(end 148.59 -22.86)
		(width 0.381)
		(layer "In2.Cu")
		(net "XP2R5V_FPGA")
	)
	(segment
		(start 160.147 -49.779936)
		(end 165.227 -44.699936)
		(width 0.381)
		(layer "In2.Cu")
		(net "XP2R5V_FPGA")
	)
	(segment
		(start 162.814 -22.225)
		(end 162.814 -21.971)
		(width 0.381)
		(layer "In2.Cu")
		(net "XP2R5V_FPGA")
	)
	(segment
		(start 163.2712 -64.9732)
		(end 162.052 -63.754)
		(width 0.381)
		(layer "In2.Cu")
		(net "XP2R5V_FPGA")
	)
	(segment
		(start 152.8445 -101.6635)
		(end 153.416 -101.092)
		(width 0.381)
		(layer "In2.Cu")
		(net "XP2R5V_FPGA")
	)
	(segment
		(start 157.226 -107.823)
		(end 157.226 -104.902)
		(width 0.381)
		(layer "In2.Cu")
		(net "XP2R5V_FPGA")
	)
	(segment
		(start 157.226 -104.902)
		(end 153.416 -101.092)
		(width 0.381)
		(layer "In2.Cu")
		(net "XP2R5V_FPGA")
	)
	(segment
		(start 162.814 -21.971)
		(end 159.766 -18.923)
		(width 0.381)
		(layer "In2.Cu")
		(net "XP2R5V_FPGA")
	)
	(segment
		(start 141.732 -102.87)
		(end 142.571216 -102.87)
		(width 0.381)
		(layer "In2.Cu")
		(net "XP2R5V_FPGA")
	)
	(segment
		(start 165.227 -44.699936)
		(end 165.227 -24.638)
		(width 0.381)
		(layer "In2.Cu")
		(net "XP2R5V_FPGA")
	)
	(segment
		(start 148.59 -22.86)
		(end 144.526 -22.86)
		(width 0.381)
		(layer "In2.Cu")
		(net "XP2R5V_FPGA")
	)
	(segment
		(start 145.415 -90.551)
		(end 147.193 -88.773)
		(width 0.381)
		(layer "In2.Cu")
		(net "XP2R5V_FPGA")
	)
	(segment
		(start 153.416 -101.092)
		(end 152.4 -100.076)
		(width 0.381)
		(layer "In2.Cu")
		(net "XP2R5V_FPGA")
	)
	(segment
		(start 140.97 -102.108)
		(end 141.732 -102.87)
		(width 0.381)
		(layer "In2.Cu")
		(net "XP2R5V_FPGA")
	)
	(segment
		(start 147.193 -83.2358)
		(end 150.1648 -80.264)
		(width 0.381)
		(layer "In2.Cu")
		(net "XP2R5V_FPGA")
	)
	(segment
		(start 145.415 -95.123)
		(end 145.415 -90.551)
		(width 0.381)
		(layer "In2.Cu")
		(net "XP2R5V_FPGA")
	)
	(segment
		(start 160.782 -57.15)
		(end 160.782 -53.721254)
		(width 0.381)
		(layer "In2.Cu")
		(net "XP2R5V_FPGA")
	)
	(segment
		(start 152.4 -100.076)
		(end 146.812 -100.076)
		(width 0.381)
		(layer "In2.Cu")
		(net "XP2R5V_FPGA")
	)
	(segment
		(start 159.766 -18.923)
		(end 152.527 -18.923)
		(width 0.381)
		(layer "In2.Cu")
		(net "XP2R5V_FPGA")
	)
	(segment
		(start 145.796 -99.06)
		(end 145.796 -95.504)
		(width 0.381)
		(layer "In2.Cu")
		(net "XP2R5V_FPGA")
	)
	(segment
		(start 142.571216 -102.87)
		(end 143.777716 -101.6635)
		(width 0.381)
		(layer "In2.Cu")
		(net "XP2R5V_FPGA")
	)
	(segment
		(start 85.1535 -80.7085)
		(end 86.6775 -80.7085)
		(width 0.381)
		(layer "In7.Cu")
		(net "XP2R5V_FPGA")
	)
	(segment
		(start 87.884 -84.709)
		(end 91.059 -87.884)
		(width 0.381)
		(layer "In7.Cu")
		(net "XP2R5V_FPGA")
	)
	(segment
		(start 91.059 -87.884)
		(end 91.7321 -87.884)
		(width 0.381)
		(layer "In7.Cu")
		(net "XP2R5V_FPGA")
	)
	(segment
		(start 78.867 -81.534)
		(end 79.502 -81.534)
		(width 0.381)
		(layer "In7.Cu")
		(net "XP2R5V_FPGA")
	)
	(segment
		(start 87.884 -81.915)
		(end 87.884 -84.709)
		(width 0.381)
		(layer "In7.Cu")
		(net "XP2R5V_FPGA")
	)
	(segment
		(start 86.6775 -80.7085)
		(end 87.884 -81.915)
		(width 0.381)
		(layer "In7.Cu")
		(net "XP2R5V_FPGA")
	)
	(segment
		(start 91.7321 -87.884)
		(end 92.964 -89.1159)
		(width 0.381)
		(layer "In7.Cu")
		(net "XP2R5V_FPGA")
	)
	(segment
		(start 79.502 -81.534)
		(end 80.772 -80.264)
		(width 0.381)
		(layer "In7.Cu")
		(net "XP2R5V_FPGA")
	)
	(segment
		(start 84.709 -80.264)
		(end 85.1535 -80.7085)
		(width 0.381)
		(layer "In7.Cu")
		(net "XP2R5V_FPGA")
	)
	(segment
		(start 80.772 -80.264)
		(end 84.709 -80.264)
		(width 0.381)
		(layer "In7.Cu")
		(net "XP2R5V_FPGA")
	)
	(segment
		(start 127.1016 -65.8876)
		(end 125.984 -65.8876)
		(width 0.4572)
		(layer "F.Cu")
		(net "XP1R8V_VIN")
	)
	(via
		(at 127.254 -66.929)
		(size 0.508)
		(drill 0.254)
		(layers "F.Cu" "B.Cu")
		(net "XP1R8V_VIN")
	)
	(segment
		(start 128.227582 -69.758052)
		(end 127.10287 -69.758052)
		(width 0.3048)
		(layer "F.Cu")
		(net "XP1R8V_SS")
	)
	(segment
		(start 127.10287 -69.758052)
		(end 126.325122 -70.5358)
		(width 0.3048)
		(layer "F.Cu")
		(net "XP1R8V_SS")
	)
	(segment
		(start 127 -70.814946)
		(end 126.604268 -70.814946)
		(width 0.3048)
		(layer "F.Cu")
		(net "XP1R8V_SS")
	)
	(segment
		(start 126.604268 -70.814946)
		(end 126.325122 -70.5358)
		(width 0.3048)
		(layer "F.Cu")
		(net "XP1R8V_SS")
	)
	(via
		(at 127 -70.814946)
		(size 0.4572)
		(drill 0.2032)
		(layers "F.Cu" "B.Cu")
		(net "XP1R8V_SS")
	)
	(segment
		(start 133.35 -69.215)
		(end 133.847078 -69.215)
		(width 0.11938)
		(layer "F.Cu")
		(net "XP1R8V_PG_R")
	)
	(segment
		(start 132.7404 -70.1548)
		(end 133.096 -69.7992)
		(width 0.11938)
		(layer "F.Cu")
		(net "XP1R8V_PG_R")
	)
	(segment
		(start 131.843526 -69.257926)
		(end 132.7404 -70.1548)
		(width 0.11938)
		(layer "F.Cu")
		(net "XP1R8V_PG_R")
	)
	(segment
		(start 133.096 -69.7992)
		(end 133.096 -69.469)
		(width 0.11938)
		(layer "F.Cu")
		(net "XP1R8V_PG_R")
	)
	(segment
		(start 133.858 -70.3326)
		(end 133.858 -69.225922)
		(width 0.11938)
		(layer "F.Cu")
		(net "XP1R8V_PG_R")
	)
	(segment
		(start 133.096 -69.469)
		(end 133.35 -69.215)
		(width 0.11938)
		(layer "F.Cu")
		(net "XP1R8V_PG_R")
	)
	(segment
		(start 131.258818 -69.257926)
		(end 131.843526 -69.257926)
		(width 0.11938)
		(layer "F.Cu")
		(net "XP1R8V_PG_R")
	)
	(segment
		(start 133.858 -69.225922)
		(end 133.847078 -69.215)
		(width 0.11938)
		(layer "F.Cu")
		(net "XP1R8V_PG_R")
	)
	(segment
		(start 135.001 -70.3326)
		(end 133.858 -70.3326)
		(width 0.11938)
		(layer "F.Cu")
		(net "XP1R8V_PG_R")
	)
	(via
		(at 132.7404 -70.1548)
		(size 0.4572)
		(drill 0.2032)
		(layers "F.Cu" "B.Cu")
		(net "XP1R8V_PG_R")
	)
	(segment
		(start 107.84713 -44.823126)
		(end 107.347258 -45.322998)
		(width 0.381)
		(layer "F.Cu")
		(net "XP1R8V_FPGA_VCCAUX")
	)
	(segment
		(start 107.84713 -42.82313)
		(end 107.347258 -42.323258)
		(width 0.381)
		(layer "F.Cu")
		(net "XP1R8V_FPGA_VCCAUX")
	)
	(segment
		(start 111.847122 -44.823126)
		(end 112.346994 -45.322998)
		(width 0.381)
		(layer "F.Cu")
		(net "XP1R8V_FPGA_VCCAUX")
	)
	(segment
		(start 112.84712 -43.823128)
		(end 113.346992 -43.323256)
		(width 0.381)
		(layer "F.Cu")
		(net "XP1R8V_FPGA_VCCAUX")
	)
	(segment
		(start 109.847126 -44.823126)
		(end 110.346998 -45.322998)
		(width 0.381)
		(layer "F.Cu")
		(net "XP1R8V_FPGA_VCCAUX")
	)
	(segment
		(start 105.847134 -44.823126)
		(end 105.347262 -45.322998)
		(width 0.381)
		(layer "F.Cu")
		(net "XP1R8V_FPGA_VCCAUX")
	)
	(segment
		(start 102.84714 -44.823126)
		(end 102.347268 -45.322998)
		(width 0.381)
		(layer "F.Cu")
		(net "XP1R8V_FPGA_VCCAUX")
	)
	(via
		(at 113.346992 -43.323256)
		(size 0.4572)
		(drill 0.2032)
		(layers "F.Cu" "B.Cu")
		(net "XP1R8V_FPGA_VCCAUX")
	)
	(via
		(at 95.885 -56.769)
		(size 0.508)
		(drill 0.254)
		(layers "F.Cu" "B.Cu")
		(net "XP1R8V_FPGA_VCCAUX")
	)
	(via
		(at 112.346994 -45.322998)
		(size 0.4572)
		(drill 0.2032)
		(layers "F.Cu" "B.Cu")
		(net "XP1R8V_FPGA_VCCAUX")
	)
	(via
		(at 107.347258 -42.323258)
		(size 0.4572)
		(drill 0.2032)
		(layers "F.Cu" "B.Cu")
		(net "XP1R8V_FPGA_VCCAUX")
	)
	(via
		(at 95.885 -57.531)
		(size 0.508)
		(drill 0.254)
		(layers "F.Cu" "B.Cu")
		(net "XP1R8V_FPGA_VCCAUX")
	)
	(via
		(at 95.885 -55.499)
		(size 0.508)
		(drill 0.254)
		(layers "F.Cu" "B.Cu")
		(net "XP1R8V_FPGA_VCCAUX")
	)
	(via
		(at 95.885 -56.134)
		(size 0.508)
		(drill 0.254)
		(layers "F.Cu" "B.Cu")
		(net "XP1R8V_FPGA_VCCAUX")
	)
	(via
		(at 110.346998 -45.322998)
		(size 0.4572)
		(drill 0.2032)
		(layers "F.Cu" "B.Cu")
		(net "XP1R8V_FPGA_VCCAUX")
	)
	(via
		(at 107.347258 -45.322998)
		(size 0.4572)
		(drill 0.2032)
		(layers "F.Cu" "B.Cu")
		(net "XP1R8V_FPGA_VCCAUX")
	)
	(via
		(at 102.347268 -45.322998)
		(size 0.4572)
		(drill 0.2032)
		(layers "F.Cu" "B.Cu")
		(net "XP1R8V_FPGA_VCCAUX")
	)
	(via
		(at 105.347262 -45.322998)
		(size 0.4572)
		(drill 0.2032)
		(layers "F.Cu" "B.Cu")
		(net "XP1R8V_FPGA_VCCAUX")
	)
	(segment
		(start 112.84712 -42.823384)
		(end 112.84712 -42.82313)
		(width 0.381)
		(layer "B.Cu")
		(net "XP1R8V_FPGA_VCCAUX")
	)
	(segment
		(start 102.84714 -45.82287)
		(end 102.84714 -45.823124)
		(width 0.381)
		(layer "B.Cu")
		(net "XP1R8V_FPGA_VCCAUX")
	)
	(segment
		(start 113.346992 -43.323256)
		(end 112.84712 -42.823384)
		(width 0.381)
		(layer "B.Cu")
		(net "XP1R8V_FPGA_VCCAUX")
	)
	(segment
		(start 107.7214 -44.45)
		(end 107.7214 -44.948856)
		(width 0.381)
		(layer "B.Cu")
		(net "XP1R8V_FPGA_VCCAUX")
	)
	(segment
		(start 112.346994 -45.322998)
		(end 112.346994 -44.577)
		(width 0.381)
		(layer "B.Cu")
		(net "XP1R8V_FPGA_VCCAUX")
	)
	(segment
		(start 110.346998 -45.322998)
		(end 110.871 -44.798996)
		(width 0.381)
		(layer "B.Cu")
		(net "XP1R8V_FPGA_VCCAUX")
	)
	(segment
		(start 107.84713 -45.82287)
		(end 107.84713 -45.823124)
		(width 0.381)
		(layer "B.Cu")
		(net "XP1R8V_FPGA_VCCAUX")
	)
	(segment
		(start 107.347258 -45.322998)
		(end 107.84713 -45.82287)
		(width 0.381)
		(layer "B.Cu")
		(net "XP1R8V_FPGA_VCCAUX")
	)
	(segment
		(start 105.347262 -45.322998)
		(end 105.156 -45.131736)
		(width 0.381)
		(layer "B.Cu")
		(net "XP1R8V_FPGA_VCCAUX")
	)
	(segment
		(start 106.847132 -41.823132)
		(end 107.347258 -42.323258)
		(width 0.381)
		(layer "B.Cu")
		(net "XP1R8V_FPGA_VCCAUX")
	)
	(segment
		(start 105.156 -45.131736)
		(end 105.156 -44.45)
		(width 0.381)
		(layer "B.Cu")
		(net "XP1R8V_FPGA_VCCAUX")
	)
	(segment
		(start 110.871 -44.798996)
		(end 110.871 -44.2214)
		(width 0.381)
		(layer "B.Cu")
		(net "XP1R8V_FPGA_VCCAUX")
	)
	(segment
		(start 102.347268 -45.322998)
		(end 102.84714 -45.82287)
		(width 0.381)
		(layer "B.Cu")
		(net "XP1R8V_FPGA_VCCAUX")
	)
	(segment
		(start 107.7214 -44.948856)
		(end 107.347258 -45.322998)
		(width 0.381)
		(layer "B.Cu")
		(net "XP1R8V_FPGA_VCCAUX")
	)
	(segment
		(start 110.847124 -45.823124)
		(end 110.346998 -45.322998)
		(width 0.381)
		(layer "B.Cu")
		(net "XP1R8V_FPGA_VCCAUX")
	)
	(segment
		(start 133.3754 -74.0156)
		(end 117.7544 -74.0156)
		(width 0.11938)
		(layer "F.Cu")
		(net "XP1R8V_FPGA_PG")
	)
	(segment
		(start 117.7544 -74.0156)
		(end 117.0432 -74.7268)
		(width 0.11938)
		(layer "F.Cu")
		(net "XP1R8V_FPGA_PG")
	)
	(segment
		(start 135.001 -71.3994)
		(end 135.001 -72.39)
		(width 0.11938)
		(layer "F.Cu")
		(net "XP1R8V_FPGA_PG")
	)
	(segment
		(start 135.001 -72.39)
		(end 134.874 -72.517)
		(width 0.11938)
		(layer "F.Cu")
		(net "XP1R8V_FPGA_PG")
	)
	(segment
		(start 134.874 -72.517)
		(end 133.3754 -74.0156)
		(width 0.11938)
		(layer "F.Cu")
		(net "XP1R8V_FPGA_PG")
	)
	(via
		(at 134.874 -72.517)
		(size 0.508)
		(drill 0.254)
		(layers "F.Cu" "B.Cu")
		(net "XP1R8V_FPGA_PG")
	)
	(via
		(at 117.0432 -74.7268)
		(size 0.508)
		(drill 0.254)
		(layers "F.Cu" "B.Cu")
		(net "XP1R8V_FPGA_PG")
	)
	(via
		(at 107.95 -96.774)
		(size 0.508)
		(drill 0.254)
		(layers "F.Cu" "B.Cu")
		(net "XP1R8V_FPGA_PG")
	)
	(via
		(at 35.179 -98.425)
		(size 0.4572)
		(drill 0.2032)
		(layers "F.Cu" "B.Cu")
		(net "XP1R8V_FPGA_PG")
	)
	(segment
		(start 108.204 -86.995254)
		(end 108.585 -86.614254)
		(width 0.11938)
		(layer "B.Cu")
		(net "XP1R8V_FPGA_PG")
	)
	(segment
		(start 108.204 -96.52)
		(end 108.204 -86.995254)
		(width 0.11938)
		(layer "B.Cu")
		(net "XP1R8V_FPGA_PG")
	)
	(segment
		(start 114.046 -75.946)
		(end 115.45951 -75.946)
		(width 0.11938)
		(layer "B.Cu")
		(net "XP1R8V_FPGA_PG")
	)
	(segment
		(start 146.431 -24.892)
		(end 146.685 -24.638)
		(width 0.11938)
		(layer "B.Cu")
		(net "XP1R8V_FPGA_PG")
	)
	(segment
		(start 117.0432 -74.7268)
		(end 116.0526 -74.7268)
		(width 0.11938)
		(layer "B.Cu")
		(net "XP1R8V_FPGA_PG")
	)
	(segment
		(start 111.379 -79.629)
		(end 111.379 -78.613)
		(width 0.11938)
		(layer "B.Cu")
		(net "XP1R8V_FPGA_PG")
	)
	(segment
		(start 108.585 -82.423)
		(end 111.379 -79.629)
		(width 0.11938)
		(layer "B.Cu")
		(net "XP1R8V_FPGA_PG")
	)
	(segment
		(start 116.0526 -74.7268)
		(end 115.9764 -74.803)
		(width 0.11938)
		(layer "B.Cu")
		(net "XP1R8V_FPGA_PG")
	)
	(segment
		(start 146.685 -24.638)
		(end 146.685 -20.2184)
		(width 0.11938)
		(layer "B.Cu")
		(net "XP1R8V_FPGA_PG")
	)
	(segment
		(start 111.379 -78.613)
		(end 114.046 -75.946)
		(width 0.11938)
		(layer "B.Cu")
		(net "XP1R8V_FPGA_PG")
	)
	(segment
		(start 115.45951 -75.946)
		(end 115.9764 -75.42911)
		(width 0.11938)
		(layer "B.Cu")
		(net "XP1R8V_FPGA_PG")
	)
	(segment
		(start 35.179 -98.425)
		(end 35.433 -98.679)
		(width 0.11938)
		(layer "B.Cu")
		(net "XP1R8V_FPGA_PG")
	)
	(segment
		(start 107.95 -96.774)
		(end 108.204 -96.52)
		(width 0.11938)
		(layer "B.Cu")
		(net "XP1R8V_FPGA_PG")
	)
	(segment
		(start 35.433 -98.679)
		(end 36.0426 -98.679)
		(width 0.11938)
		(layer "B.Cu")
		(net "XP1R8V_FPGA_PG")
	)
	(segment
		(start 108.585 -86.614254)
		(end 108.585 -82.423)
		(width 0.11938)
		(layer "B.Cu")
		(net "XP1R8V_FPGA_PG")
	)
	(segment
		(start 36.0426 -98.679)
		(end 36.449 -99.0854)
		(width 0.11938)
		(layer "B.Cu")
		(net "XP1R8V_FPGA_PG")
	)
	(segment
		(start 115.9764 -75.42911)
		(end 115.9764 -74.803)
		(width 0.11938)
		(layer "B.Cu")
		(net "XP1R8V_FPGA_PG")
	)
	(segment
		(start 34.417 -94.361)
		(end 35.7505 -93.0275)
		(width 0.127)
		(layer "In2.Cu")
		(net "XP1R8V_FPGA_PG")
	)
	(segment
		(start 35.7505 -93.0275)
		(end 46.533054 -93.0275)
		(width 0.127)
		(layer "In2.Cu")
		(net "XP1R8V_FPGA_PG")
	)
	(segment
		(start 89.057988 -90.678)
		(end 93.98 -95.600012)
		(width 0.127)
		(layer "In2.Cu")
		(net "XP1R8V_FPGA_PG")
	)
	(segment
		(start 35.052 -98.298)
		(end 35.052 -97.028)
		(width 0.127)
		(layer "In2.Cu")
		(net "XP1R8V_FPGA_PG")
	)
	(segment
		(start 35.179 -98.425)
		(end 35.052 -98.298)
		(width 0.127)
		(layer "In2.Cu")
		(net "XP1R8V_FPGA_PG")
	)
	(segment
		(start 96.266 -100.076)
		(end 101.229414 -100.076)
		(width 0.127)
		(layer "In2.Cu")
		(net "XP1R8V_FPGA_PG")
	)
	(segment
		(start 73.66 -90.678)
		(end 89.057988 -90.678)
		(width 0.127)
		(layer "In2.Cu")
		(net "XP1R8V_FPGA_PG")
	)
	(segment
		(start 93.98 -95.600012)
		(end 93.98 -97.79)
		(width 0.127)
		(layer "In2.Cu")
		(net "XP1R8V_FPGA_PG")
	)
	(segment
		(start 106.426 -98.298)
		(end 107.95 -96.774)
		(width 0.127)
		(layer "In2.Cu")
		(net "XP1R8V_FPGA_PG")
	)
	(segment
		(start 70.104 -94.234)
		(end 73.66 -90.678)
		(width 0.127)
		(layer "In2.Cu")
		(net "XP1R8V_FPGA_PG")
	)
	(segment
		(start 93.98 -97.79)
		(end 96.266 -100.076)
		(width 0.127)
		(layer "In2.Cu")
		(net "XP1R8V_FPGA_PG")
	)
	(segment
		(start 34.417 -96.393)
		(end 34.417 -94.361)
		(width 0.127)
		(layer "In2.Cu")
		(net "XP1R8V_FPGA_PG")
	)
	(segment
		(start 103.007414 -98.298)
		(end 106.426 -98.298)
		(width 0.127)
		(layer "In2.Cu")
		(net "XP1R8V_FPGA_PG")
	)
	(segment
		(start 47.739554 -94.234)
		(end 70.104 -94.234)
		(width 0.127)
		(layer "In2.Cu")
		(net "XP1R8V_FPGA_PG")
	)
	(segment
		(start 35.052 -97.028)
		(end 34.417 -96.393)
		(width 0.127)
		(layer "In2.Cu")
		(net "XP1R8V_FPGA_PG")
	)
	(segment
		(start 101.229414 -100.076)
		(end 103.007414 -98.298)
		(width 0.127)
		(layer "In2.Cu")
		(net "XP1R8V_FPGA_PG")
	)
	(segment
		(start 46.533054 -93.0275)
		(end 47.739554 -94.234)
		(width 0.127)
		(layer "In2.Cu")
		(net "XP1R8V_FPGA_PG")
	)
	(segment
		(start 127.508 -55.985918)
		(end 127.508 -53.634386)
		(width 0.127)
		(layer "In7.Cu")
		(net "XP1R8V_FPGA_PG")
	)
	(segment
		(start 134.874 -70.5104)
		(end 136.144 -69.2404)
		(width 0.127)
		(layer "In7.Cu")
		(net "XP1R8V_FPGA_PG")
	)
	(segment
		(start 139.0396 -66.0654)
		(end 139.0396 -64.873632)
		(width 0.127)
		(layer "In7.Cu")
		(net "XP1R8V_FPGA_PG")
	)
	(segment
		(start 127.0635 -51.749452)
		(end 126.746 -51.431952)
		(width 0.127)
		(layer "In7.Cu")
		(net "XP1R8V_FPGA_PG")
	)
	(segment
		(start 139.145772 -24.892)
		(end 146.431 -24.892)
		(width 0.127)
		(layer "In7.Cu")
		(net "XP1R8V_FPGA_PG")
	)
	(segment
		(start 134.514082 -62.992)
		(end 127.508 -55.985918)
		(width 0.127)
		(layer "In7.Cu")
		(net "XP1R8V_FPGA_PG")
	)
	(segment
		(start 127.0635 -53.189886)
		(end 127.0635 -51.749452)
		(width 0.127)
		(layer "In7.Cu")
		(net "XP1R8V_FPGA_PG")
	)
	(segment
		(start 127.508 -53.634386)
		(end 127.0635 -53.189886)
		(width 0.127)
		(layer "In7.Cu")
		(net "XP1R8V_FPGA_PG")
	)
	(segment
		(start 127.127 -44.45)
		(end 131.826 -39.751)
		(width 0.127)
		(layer "In7.Cu")
		(net "XP1R8V_FPGA_PG")
	)
	(segment
		(start 126.746 -48.4505)
		(end 127.127 -48.0695)
		(width 0.127)
		(layer "In7.Cu")
		(net "XP1R8V_FPGA_PG")
	)
	(segment
		(start 138.555984 -64.390016)
		(end 137.796016 -64.390016)
		(width 0.127)
		(layer "In7.Cu")
		(net "XP1R8V_FPGA_PG")
	)
	(segment
		(start 134.874 -72.517)
		(end 134.874 -70.5104)
		(width 0.127)
		(layer "In7.Cu")
		(net "XP1R8V_FPGA_PG")
	)
	(segment
		(start 131.826 -32.211772)
		(end 139.145772 -24.892)
		(width 0.127)
		(layer "In7.Cu")
		(net "XP1R8V_FPGA_PG")
	)
	(segment
		(start 127.127 -48.0695)
		(end 127.127 -44.45)
		(width 0.127)
		(layer "In7.Cu")
		(net "XP1R8V_FPGA_PG")
	)
	(segment
		(start 126.746 -51.431952)
		(end 126.746 -48.4505)
		(width 0.127)
		(layer "In7.Cu")
		(net "XP1R8V_FPGA_PG")
	)
	(segment
		(start 137.796016 -64.390016)
		(end 136.398 -62.992)
		(width 0.127)
		(layer "In7.Cu")
		(net "XP1R8V_FPGA_PG")
	)
	(segment
		(start 139.0396 -64.873632)
		(end 138.555984 -64.390016)
		(width 0.127)
		(layer "In7.Cu")
		(net "XP1R8V_FPGA_PG")
	)
	(segment
		(start 136.144 -68.961)
		(end 139.0396 -66.0654)
		(width 0.127)
		(layer "In7.Cu")
		(net "XP1R8V_FPGA_PG")
	)
	(segment
		(start 131.826 -39.751)
		(end 131.826 -32.211772)
		(width 0.127)
		(layer "In7.Cu")
		(net "XP1R8V_FPGA_PG")
	)
	(segment
		(start 136.398 -62.992)
		(end 134.514082 -62.992)
		(width 0.127)
		(layer "In7.Cu")
		(net "XP1R8V_FPGA_PG")
	)
	(segment
		(start 136.144 -69.2404)
		(end 136.144 -68.961)
		(width 0.127)
		(layer "In7.Cu")
		(net "XP1R8V_FPGA_PG")
	)
	(segment
		(start 135.6614 -64.516)
		(end 135.763 -64.4144)
		(width 0.381)
		(layer "F.Cu")
		(net "XP1R8V_FPGA")
	)
	(segment
		(start 133.1722 -66.4718)
		(end 133.3246 -66.3194)
		(width 0.3048)
		(layer "F.Cu")
		(net "XP1R8V_FPGA")
	)
	(segment
		(start 133.731 -64.516)
		(end 135.6614 -64.516)
		(width 0.381)
		(layer "F.Cu")
		(net "XP1R8V_FPGA")
	)
	(segment
		(start 133.3246 -66.3194)
		(end 134.0612 -66.3194)
		(width 0.3048)
		(layer "F.Cu")
		(net "XP1R8V_FPGA")
	)
	(via
		(at 25.146 -66.04635)
		(size 0.508)
		(drill 0.254)
		(layers "F.Cu" "B.Cu")
		(net "XP1R8V_FPGA")
	)
	(via
		(at 90.297 -56.642)
		(size 0.508)
		(drill 0.254)
		(layers "F.Cu" "B.Cu")
		(net "XP1R8V_FPGA")
	)
	(via
		(at 25.019 -65.191894)
		(size 0.508)
		(drill 0.254)
		(layers "F.Cu" "B.Cu")
		(net "XP1R8V_FPGA")
	)
	(via
		(at 132.588 -62.738)
		(size 0.508)
		(drill 0.254)
		(layers "F.Cu" "B.Cu")
		(net "XP1R8V_FPGA")
	)
	(via
		(at 90.297 -55.372)
		(size 0.508)
		(drill 0.254)
		(layers "F.Cu" "B.Cu")
		(net "XP1R8V_FPGA")
	)
	(via
		(at 133.0706 -65.3034)
		(size 0.508)
		(drill 0.254)
		(layers "F.Cu" "B.Cu")
		(net "XP1R8V_FPGA")
	)
	(via
		(at 90.297 -57.277)
		(size 0.508)
		(drill 0.254)
		(layers "F.Cu" "B.Cu")
		(net "XP1R8V_FPGA")
	)
	(via
		(at 90.297 -56.007)
		(size 0.508)
		(drill 0.254)
		(layers "F.Cu" "B.Cu")
		(net "XP1R8V_FPGA")
	)
	(via
		(at 133.1722 -66.4718)
		(size 0.508)
		(drill 0.254)
		(layers "F.Cu" "B.Cu")
		(net "XP1R8V_FPGA")
	)
	(via
		(at 133.4516 -62.738)
		(size 0.508)
		(drill 0.254)
		(layers "F.Cu" "B.Cu")
		(net "XP1R8V_FPGA")
	)
	(segment
		(start 132.6896 -68.7578)
		(end 131.258818 -68.7578)
		(width 0.3048)
		(layer "F.Cu")
		(net "XP1R8V_FB")
	)
	(segment
		(start 134.0612 -67.3862)
		(end 135.3312 -67.3862)
		(width 0.3048)
		(layer "F.Cu")
		(net "XP1R8V_FB")
	)
	(segment
		(start 132.6896 -68.7578)
		(end 134.0612 -67.3862)
		(width 0.3048)
		(layer "F.Cu")
		(net "XP1R8V_FB")
	)
	(via
		(at 132.6896 -68.7578)
		(size 0.4572)
		(drill 0.2032)
		(layers "F.Cu" "B.Cu")
		(net "XP1R8V_FB")
	)
	(segment
		(start 134.0612 -67.3862)
		(end 132.6896 -68.7578)
		(width 0.3048)
		(layer "B.Cu")
		(net "XP1R8V_FB")
	)
	(segment
		(start 126.0094 -68.2244)
		(end 126.0094 -66.9798)
		(width 0.11938)
		(layer "F.Cu")
		(net "XP1R8V_EN_R")
	)
	(segment
		(start 126.0094 -66.9798)
		(end 125.984 -66.9544)
		(width 0.11938)
		(layer "F.Cu")
		(net "XP1R8V_EN_R")
	)
	(segment
		(start 127.525526 -69.257926)
		(end 127.127 -68.8594)
		(width 0.11938)
		(layer "F.Cu")
		(net "XP1R8V_EN_R")
	)
	(segment
		(start 126.0094 -68.2244)
		(end 126.39929 -68.61429)
		(width 0.11938)
		(layer "F.Cu")
		(net "XP1R8V_EN_R")
	)
	(segment
		(start 126.88189 -68.61429)
		(end 127.127 -68.8594)
		(width 0.11938)
		(layer "F.Cu")
		(net "XP1R8V_EN_R")
	)
	(segment
		(start 126.39929 -68.61429)
		(end 126.88189 -68.61429)
		(width 0.11938)
		(layer "F.Cu")
		(net "XP1R8V_EN_R")
	)
	(segment
		(start 128.227582 -69.257926)
		(end 127.525526 -69.257926)
		(width 0.11938)
		(layer "F.Cu")
		(net "XP1R8V_EN_R")
	)
	(segment
		(start 126.0094 -68.2244)
		(end 124.1806 -68.2244)
		(width 0.11938)
		(layer "F.Cu")
		(net "XP1R8V_EN_R")
	)
	(via
		(at 127.127 -68.8594)
		(size 0.4572)
		(drill 0.2032)
		(layers "F.Cu" "B.Cu")
		(net "XP1R8V_EN_R")
	)
	(segment
		(start 126.0094 -68.2244)
		(end 126.492 -68.2244)
		(width 0.11938)
		(layer "B.Cu")
		(net "XP1R8V_EN_R")
	)
	(segment
		(start 126.492 -68.2244)
		(end 127.127 -68.8594)
		(width 0.11938)
		(layer "B.Cu")
		(net "XP1R8V_EN_R")
	)
	(via
		(at 96.3422 -77.47)
		(size 0.4572)
		(drill 0.2032)
		(layers "F.Cu" "B.Cu")
		(net "XP1R2V_VIN")
	)
	(segment
		(start 96.3422 -78.5368)
		(end 96.3422 -77.47)
		(width 0.3048)
		(layer "B.Cu")
		(net "XP1R2V_VIN")
	)
	(segment
		(start 101.1428 -77.648054)
		(end 101.1428 -78.221078)
		(width 0.3048)
		(layer "F.Cu")
		(net "XP1R2V_SS")
	)
	(segment
		(start 100.833174 -77.338428)
		(end 101.1428 -77.648054)
		(width 0.3048)
		(layer "F.Cu")
		(net "XP1R2V_SS")
	)
	(segment
		(start 100.365052 -76.318618)
		(end 100.365052 -76.870306)
		(width 0.3048)
		(layer "F.Cu")
		(net "XP1R2V_SS")
	)
	(segment
		(start 100.365052 -76.870306)
		(end 100.833174 -77.338428)
		(width 0.3048)
		(layer "F.Cu")
		(net "XP1R2V_SS")
	)
	(via
		(at 100.833174 -77.338428)
		(size 0.508)
		(drill 0.254)
		(layers "F.Cu" "B.Cu")
		(net "XP1R2V_SS")
	)
	(segment
		(start 100.2792 -71.933054)
		(end 100.2792 -71.4502)
		(width 0.11938)
		(layer "F.Cu")
		(net "XP1R2V_PG_R")
	)
	(segment
		(start 99.864926 -73.287382)
		(end 99.864926 -72.347328)
		(width 0.11938)
		(layer "F.Cu")
		(net "XP1R2V_PG_R")
	)
	(segment
		(start 99.7204 -68.072)
		(end 99.7204 -69.215)
		(width 0.11938)
		(layer "F.Cu")
		(net "XP1R2V_PG_R")
	)
	(segment
		(start 99.864926 -72.347328)
		(end 100.2792 -71.933054)
		(width 0.11938)
		(layer "F.Cu")
		(net "XP1R2V_PG_R")
	)
	(segment
		(start 100.2792 -71.4502)
		(end 100.2792 -71.3232)
		(width 0.11938)
		(layer "F.Cu")
		(net "XP1R2V_PG_R")
	)
	(segment
		(start 100.115878 -71.159878)
		(end 100.115878 -70.4596)
		(width 0.11938)
		(layer "F.Cu")
		(net "XP1R2V_PG_R")
	)
	(segment
		(start 100.2792 -71.3232)
		(end 100.115878 -71.159878)
		(width 0.11938)
		(layer "F.Cu")
		(net "XP1R2V_PG_R")
	)
	(segment
		(start 99.7204 -70.064122)
		(end 100.115878 -70.4596)
		(width 0.11938)
		(layer "F.Cu")
		(net "XP1R2V_PG_R")
	)
	(segment
		(start 99.7204 -69.215)
		(end 99.7204 -70.064122)
		(width 0.11938)
		(layer "F.Cu")
		(net "XP1R2V_PG_R")
	)
	(via
		(at 100.2792 -71.4502)
		(size 0.508)
		(drill 0.254)
		(layers "F.Cu" "B.Cu")
		(net "XP1R2V_PG_R")
	)
	(segment
		(start 116.713 -64.897)
		(end 110.998 -64.897)
		(width 0.11938)
		(layer "F.Cu")
		(net "XP1R2V_FPGA_PG")
	)
	(segment
		(start 117.348 -67.183)
		(end 117.348 -65.532)
		(width 0.11938)
		(layer "F.Cu")
		(net "XP1R2V_FPGA_PG")
	)
	(segment
		(start 118.4402 -69.2912)
		(end 117.983 -68.834)
		(width 0.11938)
		(layer "F.Cu")
		(net "XP1R2V_FPGA_PG")
	)
	(segment
		(start 102.5652 -67.437)
		(end 100.7872 -69.215)
		(width 0.11938)
		(layer "F.Cu")
		(net "XP1R2V_FPGA_PG")
	)
	(segment
		(start 117.983 -68.834)
		(end 117.983 -67.818)
		(width 0.11938)
		(layer "F.Cu")
		(net "XP1R2V_FPGA_PG")
	)
	(segment
		(start 117.983 -67.818)
		(end 117.348 -67.183)
		(width 0.11938)
		(layer "F.Cu")
		(net "XP1R2V_FPGA_PG")
	)
	(segment
		(start 110.998 -64.897)
		(end 108.458 -67.437)
		(width 0.11938)
		(layer "F.Cu")
		(net "XP1R2V_FPGA_PG")
	)
	(segment
		(start 124.1806 -69.2912)
		(end 122.7074 -69.2912)
		(width 0.11938)
		(layer "F.Cu")
		(net "XP1R2V_FPGA_PG")
	)
	(segment
		(start 108.458 -67.437)
		(end 102.5652 -67.437)
		(width 0.11938)
		(layer "F.Cu")
		(net "XP1R2V_FPGA_PG")
	)
	(segment
		(start 117.348 -65.532)
		(end 116.713 -64.897)
		(width 0.11938)
		(layer "F.Cu")
		(net "XP1R2V_FPGA_PG")
	)
	(segment
		(start 122.7074 -69.2912)
		(end 118.4402 -69.2912)
		(width 0.11938)
		(layer "F.Cu")
		(net "XP1R2V_FPGA_PG")
	)
	(segment
		(start 96.012 -70.4596)
		(end 96.0374 -70.485)
		(width 0.381)
		(layer "F.Cu")
		(net "XP1R2V_FPGA")
	)
	(segment
		(start 96.9264 -71.2216)
		(end 97.0788 -71.374)
		(width 0.381)
		(layer "F.Cu")
		(net "XP1R2V_FPGA")
	)
	(segment
		(start 96.9264 -70.485)
		(end 96.9264 -71.2216)
		(width 0.381)
		(layer "F.Cu")
		(net "XP1R2V_FPGA")
	)
	(segment
		(start 96.0374 -70.485)
		(end 96.9264 -70.485)
		(width 0.381)
		(layer "F.Cu")
		(net "XP1R2V_FPGA")
	)
	(via
		(at 96.012 -71.374)
		(size 0.508)
		(drill 0.254)
		(layers "F.Cu" "B.Cu")
		(net "XP1R2V_FPGA")
	)
	(via
		(at 88.9 -35.941)
		(size 0.508)
		(drill 0.254)
		(layers "F.Cu" "B.Cu")
		(net "XP1R2V_FPGA")
	)
	(via
		(at 95.123 -70.104)
		(size 0.508)
		(drill 0.254)
		(layers "F.Cu" "B.Cu")
		(net "XP1R2V_FPGA")
	)
	(via
		(at 90.17 -35.941)
		(size 0.508)
		(drill 0.254)
		(layers "F.Cu" "B.Cu")
		(net "XP1R2V_FPGA")
	)
	(via
		(at 88.265 -35.941)
		(size 0.508)
		(drill 0.254)
		(layers "F.Cu" "B.Cu")
		(net "XP1R2V_FPGA")
	)
	(via
		(at 93.98 -70.104)
		(size 0.508)
		(drill 0.254)
		(layers "F.Cu" "B.Cu")
		(net "XP1R2V_FPGA")
	)
	(via
		(at 97.0788 -71.374)
		(size 0.508)
		(drill 0.254)
		(layers "F.Cu" "B.Cu")
		(net "XP1R2V_FPGA")
	)
	(via
		(at 89.535 -35.941)
		(size 0.508)
		(drill 0.254)
		(layers "F.Cu" "B.Cu")
		(net "XP1R2V_FPGA")
	)
	(segment
		(start 98.9076 -71.3994)
		(end 97.9932 -70.485)
		(width 0.3048)
		(layer "F.Cu")
		(net "XP1R2V_FB")
	)
	(segment
		(start 99.3648 -71.8566)
		(end 98.9076 -71.3994)
		(width 0.3048)
		(layer "F.Cu")
		(net "XP1R2V_FB")
	)
	(segment
		(start 99.3648 -73.287382)
		(end 99.3648 -71.8566)
		(width 0.3048)
		(layer "F.Cu")
		(net "XP1R2V_FB")
	)
	(segment
		(start 97.9932 -69.215)
		(end 97.9932 -70.485)
		(width 0.381)
		(layer "F.Cu")
		(net "XP1R2V_FB")
	)
	(segment
		(start 97.9932 -69.215)
		(end 97.9932 -68.072)
		(width 0.381)
		(layer "F.Cu")
		(net "XP1R2V_FB")
	)
	(via
		(at 98.9076 -71.3994)
		(size 0.508)
		(drill 0.254)
		(layers "F.Cu" "B.Cu")
		(net "XP1R2V_FB")
	)
	(segment
		(start 99.864926 -76.318618)
		(end 99.864926 -77.020674)
		(width 0.11938)
		(layer "F.Cu")
		(net "XP1R2V_EN_R")
	)
	(segment
		(start 99.864926 -77.020674)
		(end 99.4664 -77.4192)
		(width 0.11938)
		(layer "F.Cu")
		(net "XP1R2V_EN_R")
	)
	(segment
		(start 99.22129 -78.14691)
		(end 99.22129 -77.66431)
		(width 0.11938)
		(layer "F.Cu")
		(net "XP1R2V_EN_R")
	)
	(segment
		(start 99.22129 -77.66431)
		(end 99.4664 -77.4192)
		(width 0.11938)
		(layer "F.Cu")
		(net "XP1R2V_EN_R")
	)
	(segment
		(start 98.8314 -78.5368)
		(end 99.22129 -78.14691)
		(width 0.11938)
		(layer "F.Cu")
		(net "XP1R2V_EN_R")
	)
	(segment
		(start 98.8314 -78.5368)
		(end 97.409 -78.5368)
		(width 0.11938)
		(layer "F.Cu")
		(net "XP1R2V_EN_R")
	)
	(via
		(at 99.4664 -77.4192)
		(size 0.4572)
		(drill 0.2032)
		(layers "F.Cu" "B.Cu")
		(net "XP1R2V_EN_R")
	)
	(segment
		(start 98.8314 -78.0542)
		(end 99.4664 -77.4192)
		(width 0.11938)
		(layer "B.Cu")
		(net "XP1R2V_EN_R")
	)
	(segment
		(start 98.8314 -78.5368)
		(end 97.409 -78.5368)
		(width 0.11938)
		(layer "B.Cu")
		(net "XP1R2V_EN_R")
	)
	(segment
		(start 98.8314 -78.5368)
		(end 98.8314 -78.0542)
		(width 0.11938)
		(layer "B.Cu")
		(net "XP1R2V_EN_R")
	)
	(via
		(at 140.8684 -51.4096)
		(size 0.508)
		(drill 0.254)
		(layers "F.Cu" "B.Cu")
		(net "XP1R0V_SW")
	)
	(via
		(at 141.9606 -51.435)
		(size 0.508)
		(drill 0.254)
		(layers "F.Cu" "B.Cu")
		(net "XP1R0V_SW")
	)
	(segment
		(start 141.9606 -50.292)
		(end 141.9606 -51.435)
		(width 0.381)
		(layer "B.Cu")
		(net "XP1R0V_SW")
	)
	(segment
		(start 139.954 -51.4096)
		(end 140.8684 -51.4096)
		(width 0.381)
		(layer "B.Cu")
		(net "XP1R0V_SW")
	)
	(segment
		(start 141.355064 -56.386984)
		(end 141.355064 -58.043064)
		(width 0.254)
		(layer "F.Cu")
		(net "XP1R0V_SS")
	)
	(segment
		(start 142.24 -58.928)
		(end 142.24 -59.0296)
		(width 0.254)
		(layer "F.Cu")
		(net "XP1R0V_SS")
	)
	(segment
		(start 141.355064 -58.043064)
		(end 142.24 -58.928)
		(width 0.254)
		(layer "F.Cu")
		(net "XP1R0V_SS")
	)
	(segment
		(start 143.311118 -56.7182)
		(end 144.765522 -56.7182)
		(width 0.3048)
		(layer "F.Cu")
		(net "XP1R0V_RT")
	)
	(segment
		(start 144.765522 -56.7182)
		(end 145.2118 -56.7182)
		(width 0.3048)
		(layer "F.Cu")
		(net "XP1R0V_RT")
	)
	(segment
		(start 142.979902 -56.386984)
		(end 143.311118 -56.7182)
		(width 0.3048)
		(layer "F.Cu")
		(net "XP1R0V_RT")
	)
	(segment
		(start 145.2118 -56.7182)
		(end 145.5166 -57.023)
		(width 0.3048)
		(layer "F.Cu")
		(net "XP1R0V_RT")
	)
	(via
		(at 144.765522 -56.7182)
		(size 0.508)
		(drill 0.254)
		(layers "F.Cu" "B.Cu")
		(net "XP1R0V_RT")
	)
	(segment
		(start 138.811 -59.0296)
		(end 138.811 -58.341514)
		(width 0.11938)
		(layer "F.Cu")
		(net "XP1R0V_PG")
	)
	(segment
		(start 139.954 -59.171078)
		(end 138.952478 -59.171078)
		(width 0.11938)
		(layer "F.Cu")
		(net "XP1R0V_PG")
	)
	(segment
		(start 138.811 -58.341514)
		(end 139.232132 -57.920382)
		(width 0.11938)
		(layer "F.Cu")
		(net "XP1R0V_PG")
	)
	(segment
		(start 140.230098 -56.922416)
		(end 139.232132 -57.920382)
		(width 0.11938)
		(layer "F.Cu")
		(net "XP1R0V_PG")
	)
	(segment
		(start 140.230098 -56.386984)
		(end 140.230098 -56.922416)
		(width 0.11938)
		(layer "F.Cu")
		(net "XP1R0V_PG")
	)
	(segment
		(start 138.952478 -59.171078)
		(end 138.811 -59.0296)
		(width 0.11938)
		(layer "F.Cu")
		(net "XP1R0V_PG")
	)
	(via
		(at 139.232132 -57.920382)
		(size 0.4572)
		(drill 0.2032)
		(layers "F.Cu" "B.Cu")
		(net "XP1R0V_PG")
	)
	(segment
		(start 137.9474 -57.785)
		(end 138.0744 -57.912)
		(width 0.11938)
		(layer "B.Cu")
		(net "XP1R0V_PG")
	)
	(segment
		(start 139.22375 -57.912)
		(end 139.232132 -57.920382)
		(width 0.11938)
		(layer "B.Cu")
		(net "XP1R0V_PG")
	)
	(segment
		(start 138.0744 -57.912)
		(end 139.22375 -57.912)
		(width 0.11938)
		(layer "B.Cu")
		(net "XP1R0V_PG")
	)
	(segment
		(start 111.847122 -42.82313)
		(end 112.346994 -42.323258)
		(width 0.381)
		(layer "F.Cu")
		(net "XP1R0V_FPGA_VCCINT")
	)
	(segment
		(start 105.847134 -40.823134)
		(end 105.347262 -40.323262)
		(width 0.381)
		(layer "F.Cu")
		(net "XP1R0V_FPGA_VCCINT")
	)
	(segment
		(start 112.84712 -41.823132)
		(end 113.346992 -41.32326)
		(width 0.381)
		(layer "F.Cu")
		(net "XP1R0V_FPGA_VCCINT")
	)
	(segment
		(start 113.847118 -40.823134)
		(end 114.34699 -40.323262)
		(width 0.381)
		(layer "F.Cu")
		(net "XP1R0V_FPGA_VCCINT")
	)
	(segment
		(start 110.847124 -43.823128)
		(end 111.346996 -43.323256)
		(width 0.381)
		(layer "F.Cu")
		(net "XP1R0V_FPGA_VCCINT")
	)
	(segment
		(start 112.84712 -39.823136)
		(end 113.346992 -39.323264)
		(width 0.381)
		(layer "F.Cu")
		(net "XP1R0V_FPGA_VCCINT")
	)
	(segment
		(start 105.847134 -42.82313)
		(end 105.347262 -42.323258)
		(width 0.381)
		(layer "F.Cu")
		(net "XP1R0V_FPGA_VCCINT")
	)
	(segment
		(start 110.847124 -39.823136)
		(end 111.346996 -39.323264)
		(width 0.381)
		(layer "F.Cu")
		(net "XP1R0V_FPGA_VCCINT")
	)
	(segment
		(start 107.84713 -40.823134)
		(end 107.347258 -40.323262)
		(width 0.381)
		(layer "F.Cu")
		(net "XP1R0V_FPGA_VCCINT")
	)
	(segment
		(start 108.847128 -43.823128)
		(end 108.347256 -43.323256)
		(width 0.381)
		(layer "F.Cu")
		(net "XP1R0V_FPGA_VCCINT")
	)
	(segment
		(start 109.847126 -40.823134)
		(end 110.346998 -40.323262)
		(width 0.381)
		(layer "F.Cu")
		(net "XP1R0V_FPGA_VCCINT")
	)
	(segment
		(start 106.847132 -41.823132)
		(end 106.34726 -41.32326)
		(width 0.381)
		(layer "F.Cu")
		(net "XP1R0V_FPGA_VCCINT")
	)
	(segment
		(start 113.847118 -42.82313)
		(end 114.34699 -42.323258)
		(width 0.381)
		(layer "F.Cu")
		(net "XP1R0V_FPGA_VCCINT")
	)
	(segment
		(start 106.847132 -43.823128)
		(end 106.34726 -43.323256)
		(width 0.381)
		(layer "F.Cu")
		(net "XP1R0V_FPGA_VCCINT")
	)
	(segment
		(start 108.847128 -39.823136)
		(end 108.347256 -39.323264)
		(width 0.381)
		(layer "F.Cu")
		(net "XP1R0V_FPGA_VCCINT")
	)
	(segment
		(start 111.847122 -40.823134)
		(end 112.346994 -40.323262)
		(width 0.381)
		(layer "F.Cu")
		(net "XP1R0V_FPGA_VCCINT")
	)
	(segment
		(start 106.847132 -39.823136)
		(end 106.34726 -39.323264)
		(width 0.381)
		(layer "F.Cu")
		(net "XP1R0V_FPGA_VCCINT")
	)
	(via
		(at 111.346996 -39.323264)
		(size 0.4572)
		(drill 0.2032)
		(layers "F.Cu" "B.Cu")
		(net "XP1R0V_FPGA_VCCINT")
	)
	(via
		(at 130.683 -38.354)
		(size 0.508)
		(drill 0.254)
		(layers "F.Cu" "B.Cu")
		(net "XP1R0V_FPGA_VCCINT")
	)
	(via
		(at 110.346998 -40.323262)
		(size 0.4572)
		(drill 0.2032)
		(layers "F.Cu" "B.Cu")
		(net "XP1R0V_FPGA_VCCINT")
	)
	(via
		(at 106.34726 -41.32326)
		(size 0.4572)
		(drill 0.2032)
		(layers "F.Cu" "B.Cu")
		(net "XP1R0V_FPGA_VCCINT")
	)
	(via
		(at 130.683 -37.592)
		(size 0.508)
		(drill 0.254)
		(layers "F.Cu" "B.Cu")
		(net "XP1R0V_FPGA_VCCINT")
	)
	(via
		(at 106.34726 -39.323264)
		(size 0.4572)
		(drill 0.2032)
		(layers "F.Cu" "B.Cu")
		(net "XP1R0V_FPGA_VCCINT")
	)
	(via
		(at 130.683 -36.576)
		(size 0.508)
		(drill 0.254)
		(layers "F.Cu" "B.Cu")
		(net "XP1R0V_FPGA_VCCINT")
	)
	(via
		(at 111.346996 -43.323256)
		(size 0.4572)
		(drill 0.2032)
		(layers "F.Cu" "B.Cu")
		(net "XP1R0V_FPGA_VCCINT")
	)
	(via
		(at 105.347262 -40.323262)
		(size 0.4572)
		(drill 0.2032)
		(layers "F.Cu" "B.Cu")
		(net "XP1R0V_FPGA_VCCINT")
	)
	(via
		(at 114.34699 -42.323258)
		(size 0.4572)
		(drill 0.2032)
		(layers "F.Cu" "B.Cu")
		(net "XP1R0V_FPGA_VCCINT")
	)
	(via
		(at 108.347256 -43.323256)
		(size 0.4572)
		(drill 0.2032)
		(layers "F.Cu" "B.Cu")
		(net "XP1R0V_FPGA_VCCINT")
	)
	(via
		(at 113.346992 -41.32326)
		(size 0.4572)
		(drill 0.2032)
		(layers "F.Cu" "B.Cu")
		(net "XP1R0V_FPGA_VCCINT")
	)
	(via
		(at 107.347258 -40.323262)
		(size 0.4572)
		(drill 0.2032)
		(layers "F.Cu" "B.Cu")
		(net "XP1R0V_FPGA_VCCINT")
	)
	(via
		(at 106.34726 -43.323256)
		(size 0.4572)
		(drill 0.2032)
		(layers "F.Cu" "B.Cu")
		(net "XP1R0V_FPGA_VCCINT")
	)
	(via
		(at 113.346992 -39.323264)
		(size 0.4572)
		(drill 0.2032)
		(layers "F.Cu" "B.Cu")
		(net "XP1R0V_FPGA_VCCINT")
	)
	(via
		(at 108.347256 -39.323264)
		(size 0.4572)
		(drill 0.2032)
		(layers "F.Cu" "B.Cu")
		(net "XP1R0V_FPGA_VCCINT")
	)
	(via
		(at 105.347262 -42.323258)
		(size 0.4572)
		(drill 0.2032)
		(layers "F.Cu" "B.Cu")
		(net "XP1R0V_FPGA_VCCINT")
	)
	(via
		(at 112.346994 -40.323262)
		(size 0.4572)
		(drill 0.2032)
		(layers "F.Cu" "B.Cu")
		(net "XP1R0V_FPGA_VCCINT")
	)
	(via
		(at 112.346994 -42.323258)
		(size 0.4572)
		(drill 0.2032)
		(layers "F.Cu" "B.Cu")
		(net "XP1R0V_FPGA_VCCINT")
	)
	(via
		(at 114.34699 -40.323262)
		(size 0.4572)
		(drill 0.2032)
		(layers "F.Cu" "B.Cu")
		(net "XP1R0V_FPGA_VCCINT")
	)
	(via
		(at 130.683 -39.116)
		(size 0.508)
		(drill 0.254)
		(layers "F.Cu" "B.Cu")
		(net "XP1R0V_FPGA_VCCINT")
	)
	(via
		(at 130.683 -39.878)
		(size 0.508)
		(drill 0.254)
		(layers "F.Cu" "B.Cu")
		(net "XP1R0V_FPGA_VCCINT")
	)
	(segment
		(start 114.846862 -42.82313)
		(end 114.847116 -42.82313)
		(width 0.381)
		(layer "B.Cu")
		(net "XP1R0V_FPGA_VCCINT")
	)
	(segment
		(start 110.847124 -39.823136)
		(end 111.346996 -39.323264)
		(width 0.381)
		(layer "B.Cu")
		(net "XP1R0V_FPGA_VCCINT")
	)
	(segment
		(start 107.84713 -40.823134)
		(end 107.347258 -40.323262)
		(width 0.381)
		(layer "B.Cu")
		(net "XP1R0V_FPGA_VCCINT")
	)
	(segment
		(start 113.847118 -40.823134)
		(end 113.346992 -41.32326)
		(width 0.381)
		(layer "B.Cu")
		(net "XP1R0V_FPGA_VCCINT")
	)
	(segment
		(start 111.847122 -40.823134)
		(end 112.346994 -40.323262)
		(width 0.381)
		(layer "B.Cu")
		(net "XP1R0V_FPGA_VCCINT")
	)
	(segment
		(start 110.84687 -40.823134)
		(end 110.847124 -40.823134)
		(width 0.381)
		(layer "B.Cu")
		(net "XP1R0V_FPGA_VCCINT")
	)
	(segment
		(start 108.347256 -43.323256)
		(end 108.719112 -42.9514)
		(width 0.381)
		(layer "B.Cu")
		(net "XP1R0V_FPGA_VCCINT")
	)
	(segment
		(start 106.34726 -39.323264)
		(end 106.847132 -38.823392)
		(width 0.381)
		(layer "B.Cu")
		(net "XP1R0V_FPGA_VCCINT")
	)
	(segment
		(start 111.847122 -42.82313)
		(end 112.346994 -42.323258)
		(width 0.381)
		(layer "B.Cu")
		(net "XP1R0V_FPGA_VCCINT")
	)
	(segment
		(start 106.34726 -41.32326)
		(end 105.847388 -41.823132)
		(width 0.381)
		(layer "B.Cu")
		(net "XP1R0V_FPGA_VCCINT")
	)
	(segment
		(start 106.847132 -38.823392)
		(end 106.847132 -38.823138)
		(width 0.381)
		(layer "B.Cu")
		(net "XP1R0V_FPGA_VCCINT")
	)
	(segment
		(start 112.84712 -39.823136)
		(end 113.346992 -39.323264)
		(width 0.381)
		(layer "B.Cu")
		(net "XP1R0V_FPGA_VCCINT")
	)
	(segment
		(start 114.34699 -42.323258)
		(end 114.846862 -42.82313)
		(width 0.381)
		(layer "B.Cu")
		(net "XP1R0V_FPGA_VCCINT")
	)
	(segment
		(start 105.847388 -41.823132)
		(end 105.847134 -41.823132)
		(width 0.381)
		(layer "B.Cu")
		(net "XP1R0V_FPGA_VCCINT")
	)
	(segment
		(start 110.346998 -40.323262)
		(end 110.84687 -40.823134)
		(width 0.381)
		(layer "B.Cu")
		(net "XP1R0V_FPGA_VCCINT")
	)
	(segment
		(start 104.84739 -42.82313)
		(end 104.847136 -42.82313)
		(width 0.381)
		(layer "B.Cu")
		(net "XP1R0V_FPGA_VCCINT")
	)
	(segment
		(start 108.368592 -39.3446)
		(end 109.347 -39.3446)
		(width 0.381)
		(layer "B.Cu")
		(net "XP1R0V_FPGA_VCCINT")
	)
	(segment
		(start 106.847132 -39.823136)
		(end 106.34726 -39.323264)
		(width 0.381)
		(layer "B.Cu")
		(net "XP1R0V_FPGA_VCCINT")
	)
	(segment
		(start 107.84713 -42.82313)
		(end 108.347256 -43.323256)
		(width 0.381)
		(layer "B.Cu")
		(net "XP1R0V_FPGA_VCCINT")
	)
	(segment
		(start 105.347262 -42.323258)
		(end 104.84739 -42.82313)
		(width 0.381)
		(layer "B.Cu")
		(net "XP1R0V_FPGA_VCCINT")
	)
	(segment
		(start 108.719112 -42.9514)
		(end 109.347 -42.9514)
		(width 0.381)
		(layer "B.Cu")
		(net "XP1R0V_FPGA_VCCINT")
	)
	(segment
		(start 113.346992 -41.32326)
		(end 112.84712 -41.823132)
		(width 0.381)
		(layer "B.Cu")
		(net "XP1R0V_FPGA_VCCINT")
	)
	(segment
		(start 108.347256 -39.323264)
		(end 108.368592 -39.3446)
		(width 0.381)
		(layer "B.Cu")
		(net "XP1R0V_FPGA_VCCINT")
	)
	(segment
		(start 105.847134 -40.823134)
		(end 105.347262 -40.323262)
		(width 0.381)
		(layer "B.Cu")
		(net "XP1R0V_FPGA_VCCINT")
	)
	(segment
		(start 96.3422 -78.5368)
		(end 95.377 -78.5368)
		(width 0.11938)
		(layer "F.Cu")
		(net "XP1R0V_FPGA_PG")
	)
	(segment
		(start 146.304 -62.611)
		(end 145.923 -62.992)
		(width 0.11938)
		(layer "F.Cu")
		(net "XP1R0V_FPGA_PG")
	)
	(segment
		(start 141.7066 -62.992)
		(end 138.811 -60.0964)
		(width 0.11938)
		(layer "F.Cu")
		(net "XP1R0V_FPGA_PG")
	)
	(segment
		(start 145.923 -62.992)
		(end 141.7066 -62.992)
		(width 0.11938)
		(layer "F.Cu")
		(net "XP1R0V_FPGA_PG")
	)
	(via
		(at 95.377 -78.5368)
		(size 0.508)
		(drill 0.254)
		(layers "F.Cu" "B.Cu")
		(net "XP1R0V_FPGA_PG")
	)
	(via
		(at 107.02544 -91.43238)
		(size 0.4572)
		(drill 0.2032)
		(layers "F.Cu" "B.Cu")
		(net "XP1R0V_FPGA_PG")
	)
	(segment
		(start 93.15831 -80.70469)
		(end 95.3262 -78.5368)
		(width 0.11938)
		(layer "B.Cu")
		(net "XP1R0V_FPGA_PG")
	)
	(segment
		(start 107.02544 -91.43238)
		(end 104.51846 -88.9254)
		(width 0.11938)
		(layer "B.Cu")
		(net "XP1R0V_FPGA_PG")
	)
	(segment
		(start 101.5238 -90.043)
		(end 100.56876 -90.043)
		(width 0.11938)
		(layer "B.Cu")
		(net "XP1R0V_FPGA_PG")
	)
	(segment
		(start 97.194878 -89.111582)
		(end 96.348296 -88.265)
		(width 0.11938)
		(layer "B.Cu")
		(net "XP1R0V_FPGA_PG")
	)
	(segment
		(start 99.637342 -89.111582)
		(end 97.194878 -89.111582)
		(width 0.11938)
		(layer "B.Cu")
		(net "XP1R0V_FPGA_PG")
	)
	(segment
		(start 95.3262 -78.5368)
		(end 95.377 -78.5368)
		(width 0.11938)
		(layer "B.Cu")
		(net "XP1R0V_FPGA_PG")
	)
	(segment
		(start 93.15831 -85.91931)
		(end 93.15831 -80.70469)
		(width 0.11938)
		(layer "B.Cu")
		(net "XP1R0V_FPGA_PG")
	)
	(segment
		(start 95.504 -88.265)
		(end 93.15831 -85.91931)
		(width 0.11938)
		(layer "B.Cu")
		(net "XP1R0V_FPGA_PG")
	)
	(segment
		(start 100.56876 -90.043)
		(end 99.637342 -89.111582)
		(width 0.11938)
		(layer "B.Cu")
		(net "XP1R0V_FPGA_PG")
	)
	(segment
		(start 104.51846 -88.9254)
		(end 102.6414 -88.9254)
		(width 0.11938)
		(layer "B.Cu")
		(net "XP1R0V_FPGA_PG")
	)
	(segment
		(start 96.348296 -88.265)
		(end 95.504 -88.265)
		(width 0.11938)
		(layer "B.Cu")
		(net "XP1R0V_FPGA_PG")
	)
	(segment
		(start 102.6414 -88.9254)
		(end 101.5238 -90.043)
		(width 0.11938)
		(layer "B.Cu")
		(net "XP1R0V_FPGA_PG")
	)
	(segment
		(start 130.5052 -78.0288)
		(end 132.0419 -76.4921)
		(width 0.127)
		(layer "In7.Cu")
		(net "XP1R0V_FPGA_PG")
	)
	(segment
		(start 114.173 -90.297)
		(end 115.062 -89.408)
		(width 0.127)
		(layer "In7.Cu")
		(net "XP1R0V_FPGA_PG")
	)
	(segment
		(start 107.02544 -91.43238)
		(end 107.43438 -91.43238)
		(width 0.127)
		(layer "In7.Cu")
		(net "XP1R0V_FPGA_PG")
	)
	(segment
		(start 107.43438 -91.43238)
		(end 108.331 -92.329)
		(width 0.127)
		(layer "In7.Cu")
		(net "XP1R0V_FPGA_PG")
	)
	(segment
		(start 108.331 -92.329)
		(end 110.49 -92.329)
		(width 0.127)
		(layer "In7.Cu")
		(net "XP1R0V_FPGA_PG")
	)
	(segment
		(start 120.736868 -89.408)
		(end 120.863868 -89.535)
		(width 0.127)
		(layer "In7.Cu")
		(net "XP1R0V_FPGA_PG")
	)
	(segment
		(start 138.5189 -76.4921)
		(end 140.462 -74.549)
		(width 0.127)
		(layer "In7.Cu")
		(net "XP1R0V_FPGA_PG")
	)
	(segment
		(start 140.462 -74.549)
		(end 140.462 -72.009254)
		(width 0.127)
		(layer "In7.Cu")
		(net "XP1R0V_FPGA_PG")
	)
	(segment
		(start 132.0419 -76.4921)
		(end 138.5189 -76.4921)
		(width 0.127)
		(layer "In7.Cu")
		(net "XP1R0V_FPGA_PG")
	)
	(segment
		(start 129.30886 -87.5665)
		(end 130.5052 -86.37016)
		(width 0.127)
		(layer "In7.Cu")
		(net "XP1R0V_FPGA_PG")
	)
	(segment
		(start 128.373632 -87.5665)
		(end 129.30886 -87.5665)
		(width 0.127)
		(layer "In7.Cu")
		(net "XP1R0V_FPGA_PG")
	)
	(segment
		(start 112.522 -90.297)
		(end 114.173 -90.297)
		(width 0.127)
		(layer "In7.Cu")
		(net "XP1R0V_FPGA_PG")
	)
	(segment
		(start 120.863868 -89.535)
		(end 126.405132 -89.535)
		(width 0.127)
		(layer "In7.Cu")
		(net "XP1R0V_FPGA_PG")
	)
	(segment
		(start 130.5052 -86.37016)
		(end 130.5052 -78.0288)
		(width 0.127)
		(layer "In7.Cu")
		(net "XP1R0V_FPGA_PG")
	)
	(segment
		(start 145.3261 -63.5889)
		(end 146.304 -62.611)
		(width 0.127)
		(layer "In7.Cu")
		(net "XP1R0V_FPGA_PG")
	)
	(segment
		(start 145.3261 -67.145154)
		(end 145.3261 -63.5889)
		(width 0.127)
		(layer "In7.Cu")
		(net "XP1R0V_FPGA_PG")
	)
	(segment
		(start 115.062 -89.408)
		(end 120.736868 -89.408)
		(width 0.127)
		(layer "In7.Cu")
		(net "XP1R0V_FPGA_PG")
	)
	(segment
		(start 110.49 -92.329)
		(end 112.522 -90.297)
		(width 0.127)
		(layer "In7.Cu")
		(net "XP1R0V_FPGA_PG")
	)
	(segment
		(start 126.405132 -89.535)
		(end 128.373632 -87.5665)
		(width 0.127)
		(layer "In7.Cu")
		(net "XP1R0V_FPGA_PG")
	)
	(segment
		(start 140.462 -72.009254)
		(end 145.3261 -67.145154)
		(width 0.127)
		(layer "In7.Cu")
		(net "XP1R0V_FPGA_PG")
	)
	(segment
		(start 102.84714 -40.823134)
		(end 102.347268 -40.323262)
		(width 0.381)
		(layer "F.Cu")
		(net "XP1R0V_FPGA_MGTAVCC")
	)
	(segment
		(start 103.847138 -41.823132)
		(end 103.347266 -41.32326)
		(width 0.381)
		(layer "F.Cu")
		(net "XP1R0V_FPGA_MGTAVCC")
	)
	(segment
		(start 101.847142 -38.823138)
		(end 101.34727 -38.323266)
		(width 0.381)
		(layer "F.Cu")
		(net "XP1R0V_FPGA_MGTAVCC")
	)
	(segment
		(start 103.847138 -39.823136)
		(end 103.347266 -39.323264)
		(width 0.381)
		(layer "F.Cu")
		(net "XP1R0V_FPGA_MGTAVCC")
	)
	(segment
		(start 101.847142 -42.82313)
		(end 101.34727 -42.323258)
		(width 0.381)
		(layer "F.Cu")
		(net "XP1R0V_FPGA_MGTAVCC")
	)
	(via
		(at 101.34727 -42.323258)
		(size 0.4572)
		(drill 0.2032)
		(layers "F.Cu" "B.Cu")
		(net "XP1R0V_FPGA_MGTAVCC")
	)
	(via
		(at 103.347266 -39.323264)
		(size 0.4572)
		(drill 0.2032)
		(layers "F.Cu" "B.Cu")
		(net "XP1R0V_FPGA_MGTAVCC")
	)
	(via
		(at 93.4466 -39.173912)
		(size 0.508)
		(drill 0.254)
		(layers "F.Cu" "B.Cu")
		(net "XP1R0V_FPGA_MGTAVCC")
	)
	(via
		(at 101.34727 -38.323266)
		(size 0.4572)
		(drill 0.2032)
		(layers "F.Cu" "B.Cu")
		(net "XP1R0V_FPGA_MGTAVCC")
	)
	(via
		(at 94.3356 -39.1922)
		(size 0.508)
		(drill 0.254)
		(layers "F.Cu" "B.Cu")
		(net "XP1R0V_FPGA_MGTAVCC")
	)
	(via
		(at 103.347266 -41.32326)
		(size 0.4572)
		(drill 0.2032)
		(layers "F.Cu" "B.Cu")
		(net "XP1R0V_FPGA_MGTAVCC")
	)
	(via
		(at 96.1136 -39.1922)
		(size 0.508)
		(drill 0.254)
		(layers "F.Cu" "B.Cu")
		(net "XP1R0V_FPGA_MGTAVCC")
	)
	(via
		(at 95.2246 -39.173912)
		(size 0.508)
		(drill 0.254)
		(layers "F.Cu" "B.Cu")
		(net "XP1R0V_FPGA_MGTAVCC")
	)
	(via
		(at 102.347268 -40.323262)
		(size 0.4572)
		(drill 0.2032)
		(layers "F.Cu" "B.Cu")
		(net "XP1R0V_FPGA_MGTAVCC")
	)
	(segment
		(start 101.34727 -42.323258)
		(end 101.847142 -41.823386)
		(width 0.381)
		(layer "B.Cu")
		(net "XP1R0V_FPGA_MGTAVCC")
	)
	(segment
		(start 103.847138 -40.823388)
		(end 103.847138 -40.823134)
		(width 0.381)
		(layer "B.Cu")
		(net "XP1R0V_FPGA_MGTAVCC")
	)
	(segment
		(start 101.847142 -37.823394)
		(end 101.847142 -37.82314)
		(width 0.381)
		(layer "B.Cu")
		(net "XP1R0V_FPGA_MGTAVCC")
	)
	(segment
		(start 103.847138 -39.823136)
		(end 103.347266 -39.323264)
		(width 0.381)
		(layer "B.Cu")
		(net "XP1R0V_FPGA_MGTAVCC")
	)
	(segment
		(start 103.347266 -41.32326)
		(end 103.847138 -40.823388)
		(width 0.381)
		(layer "B.Cu")
		(net "XP1R0V_FPGA_MGTAVCC")
	)
	(segment
		(start 101.847142 -41.823386)
		(end 101.847142 -41.823132)
		(width 0.381)
		(layer "B.Cu")
		(net "XP1R0V_FPGA_MGTAVCC")
	)
	(segment
		(start 101.34727 -38.323266)
		(end 101.847142 -37.823394)
		(width 0.381)
		(layer "B.Cu")
		(net "XP1R0V_FPGA_MGTAVCC")
	)
	(segment
		(start 101.847142 -38.823138)
		(end 101.34727 -38.323266)
		(width 0.381)
		(layer "B.Cu")
		(net "XP1R0V_FPGA_MGTAVCC")
	)
	(segment
		(start 102.84714 -40.823134)
		(end 102.347268 -40.323262)
		(width 0.381)
		(layer "B.Cu")
		(net "XP1R0V_FPGA_MGTAVCC")
	)
	(segment
		(start 143.6116 -60.96)
		(end 143.6116 -62.1538)
		(width 0.381)
		(layer "F.Cu")
		(net "XP1R0V_FPGA")
	)
	(via
		(at 137.73658 -43.1546)
		(size 0.508)
		(drill 0.254)
		(layers "F.Cu" "B.Cu")
		(net "XP1R0V_FPGA")
	)
	(via
		(at 90.678 -39.1668)
		(size 0.508)
		(drill 0.254)
		(layers "F.Cu" "B.Cu")
		(net "XP1R0V_FPGA")
	)
	(via
		(at 91.567 -39.243)
		(size 0.508)
		(drill 0.254)
		(layers "F.Cu" "B.Cu")
		(net "XP1R0V_FPGA")
	)
	(via
		(at 137.73658 -43.7896)
		(size 0.508)
		(drill 0.254)
		(layers "F.Cu" "B.Cu")
		(net "XP1R0V_FPGA")
	)
	(via
		(at 137.10158 -44.4246)
		(size 0.508)
		(drill 0.254)
		(layers "F.Cu" "B.Cu")
		(net "XP1R0V_FPGA")
	)
	(via
		(at 137.10158 -43.7896)
		(size 0.508)
		(drill 0.254)
		(layers "F.Cu" "B.Cu")
		(net "XP1R0V_FPGA")
	)
	(via
		(at 143.6116 -62.1538)
		(size 0.508)
		(drill 0.254)
		(layers "F.Cu" "B.Cu")
		(net "XP1R0V_FPGA")
	)
	(via
		(at 89.784428 -39.155878)
		(size 0.508)
		(drill 0.254)
		(layers "F.Cu" "B.Cu")
		(net "XP1R0V_FPGA")
	)
	(via
		(at 88.92159 -39.1922)
		(size 0.508)
		(drill 0.254)
		(layers "F.Cu" "B.Cu")
		(net "XP1R0V_FPGA")
	)
	(via
		(at 137.10158 -43.1546)
		(size 0.508)
		(drill 0.254)
		(layers "F.Cu" "B.Cu")
		(net "XP1R0V_FPGA")
	)
	(via
		(at 138.05408 -44.44238)
		(size 0.508)
		(drill 0.254)
		(layers "F.Cu" "B.Cu")
		(net "XP1R0V_FPGA")
	)
	(segment
		(start 138.4808 -62.1538)
		(end 143.6116 -62.1538)
		(width 0.381)
		(layer "In7.Cu")
		(net "XP1R0V_FPGA")
	)
	(segment
		(start 135.509 -52.578)
		(end 133.3754 -54.7116)
		(width 0.381)
		(layer "In7.Cu")
		(net "XP1R0V_FPGA")
	)
	(segment
		(start 138.05408 -44.44238)
		(end 138.05408 -45.20692)
		(width 0.381)
		(layer "In7.Cu")
		(net "XP1R0V_FPGA")
	)
	(segment
		(start 133.3754 -58.293)
		(end 136.1694 -61.087)
		(width 0.381)
		(layer "In7.Cu")
		(net "XP1R0V_FPGA")
	)
	(segment
		(start 133.3754 -54.7116)
		(end 133.3754 -58.293)
		(width 0.381)
		(layer "In7.Cu")
		(net "XP1R0V_FPGA")
	)
	(segment
		(start 135.509 -47.752)
		(end 135.509 -52.578)
		(width 0.381)
		(layer "In7.Cu")
		(net "XP1R0V_FPGA")
	)
	(segment
		(start 137.414 -61.087)
		(end 138.4808 -62.1538)
		(width 0.381)
		(layer "In7.Cu")
		(net "XP1R0V_FPGA")
	)
	(segment
		(start 138.05408 -45.20692)
		(end 135.509 -47.752)
		(width 0.381)
		(layer "In7.Cu")
		(net "XP1R0V_FPGA")
	)
	(segment
		(start 136.1694 -61.087)
		(end 137.414 -61.087)
		(width 0.381)
		(layer "In7.Cu")
		(net "XP1R0V_FPGA")
	)
	(segment
		(start 142.355062 -57.011062)
		(end 142.355062 -56.386984)
		(width 0.254)
		(layer "F.Cu")
		(net "XP1R0V_FB_R_TO_AGND")
	)
	(segment
		(start 143.129 -57.785)
		(end 142.355062 -57.011062)
		(width 0.254)
		(layer "F.Cu")
		(net "XP1R0V_FB_R_TO_AGND")
	)
	(segment
		(start 144.653 -59.298078)
		(end 143.9418 -58.586878)
		(width 0.254)
		(layer "F.Cu")
		(net "XP1R0V_FB_R_TO_AGND")
	)
	(segment
		(start 143.9418 -58.586878)
		(end 143.9418 -57.785)
		(width 0.254)
		(layer "F.Cu")
		(net "XP1R0V_FB_R_TO_AGND")
	)
	(segment
		(start 144.653 -59.298078)
		(end 144.921478 -59.0296)
		(width 0.254)
		(layer "F.Cu")
		(net "XP1R0V_FB_R_TO_AGND")
	)
	(segment
		(start 143.9418 -57.785)
		(end 143.129 -57.785)
		(width 0.254)
		(layer "F.Cu")
		(net "XP1R0V_FB_R_TO_AGND")
	)
	(segment
		(start 144.921478 -59.0296)
		(end 146.1516 -59.0296)
		(width 0.254)
		(layer "F.Cu")
		(net "XP1R0V_FB_R_TO_AGND")
	)
	(via
		(at 143.9418 -57.785)
		(size 0.4572)
		(drill 0.2032)
		(layers "F.Cu" "B.Cu")
		(net "XP1R0V_FB_R_TO_AGND")
	)
	(segment
		(start 144.7292 -58.8772)
		(end 144.78 -58.8772)
		(width 0.254)
		(layer "B.Cu")
		(net "XP1R0V_FB_R_TO_AGND")
	)
	(segment
		(start 145.9992 -58.8772)
		(end 144.78 -58.8772)
		(width 0.254)
		(layer "B.Cu")
		(net "XP1R0V_FB_R_TO_AGND")
	)
	(segment
		(start 143.9418 -58.0898)
		(end 144.7292 -58.8772)
		(width 0.254)
		(layer "B.Cu")
		(net "XP1R0V_FB_R_TO_AGND")
	)
	(segment
		(start 143.9418 -57.785)
		(end 143.9418 -58.0898)
		(width 0.254)
		(layer "B.Cu")
		(net "XP1R0V_FB_R_TO_AGND")
	)
	(segment
		(start 146.1516 -59.0296)
		(end 145.9992 -58.8772)
		(width 0.254)
		(layer "B.Cu")
		(net "XP1R0V_FB_R_TO_AGND")
	)
	(segment
		(start 142.113 -57.531)
		(end 141.854936 -57.272936)
		(width 0.254)
		(layer "F.Cu")
		(net "XP1R0V_COMP")
	)
	(segment
		(start 142.621 -58.039)
		(end 142.24 -58.039)
		(width 0.254)
		(layer "F.Cu")
		(net "XP1R0V_COMP")
	)
	(segment
		(start 141.854936 -57.272936)
		(end 141.854936 -56.386984)
		(width 0.254)
		(layer "F.Cu")
		(net "XP1R0V_COMP")
	)
	(segment
		(start 143.256 -59.171078)
		(end 143.256 -58.674)
		(width 0.254)
		(layer "F.Cu")
		(net "XP1R0V_COMP")
	)
	(segment
		(start 143.256 -58.674)
		(end 142.621 -58.039)
		(width 0.254)
		(layer "F.Cu")
		(net "XP1R0V_COMP")
	)
	(segment
		(start 142.113 -57.912)
		(end 142.113 -57.531)
		(width 0.254)
		(layer "F.Cu")
		(net "XP1R0V_COMP")
	)
	(segment
		(start 142.24 -58.039)
		(end 142.113 -57.912)
		(width 0.254)
		(layer "F.Cu")
		(net "XP1R0V_COMP")
	)
	(via
		(at 142.113 -57.912)
		(size 0.4572)
		(drill 0.2032)
		(layers "F.Cu" "B.Cu")
		(net "XP1R0V_COMP")
	)
	(segment
		(start 142.24 -58.039)
		(end 142.24 -59.0296)
		(width 0.254)
		(layer "B.Cu")
		(net "XP1R0V_COMP")
	)
	(segment
		(start 142.113 -57.912)
		(end 142.24 -58.039)
		(width 0.254)
		(layer "B.Cu")
		(net "XP1R0V_COMP")
	)
	(segment
		(start 139.76604 -55.68696)
		(end 139.955016 -55.68696)
		(width 0.3048)
		(layer "F.Cu")
		(net "XP1R0V_BT")
	)
	(segment
		(start 139.2682 -56.1848)
		(end 139.76604 -55.68696)
		(width 0.3048)
		(layer "F.Cu")
		(net "XP1R0V_BT")
	)
	(segment
		(start 139.2682 -56.5404)
		(end 139.2682 -56.1848)
		(width 0.3048)
		(layer "F.Cu")
		(net "XP1R0V_BT")
	)
	(via
		(at 139.2682 -56.5404)
		(size 0.508)
		(drill 0.254)
		(layers "F.Cu" "B.Cu")
		(net "XP1R0V_BT")
	)
	(segment
		(start 139.954 -55.8546)
		(end 139.2682 -56.5404)
		(width 0.381)
		(layer "B.Cu")
		(net "XP1R0V_BT")
	)
	(segment
		(start 139.954 -55.1434)
		(end 139.954 -55.8546)
		(width 0.381)
		(layer "B.Cu")
		(net "XP1R0V_BT")
	)
	(segment
		(start 143.8656 -55.88)
		(end 143.67256 -55.68696)
		(width 0.3048)
		(layer "F.Cu")
		(net "XP1R0V_AGND")
	)
	(segment
		(start 142.24 -60.0964)
		(end 142.860522 -60.0964)
		(width 0.254)
		(layer "F.Cu")
		(net "XP1R0V_AGND")
	)
	(segment
		(start 146.5834 -57.023)
		(end 146.5834 -57.8866)
		(width 0.254)
		(layer "F.Cu")
		(net "XP1R0V_AGND")
	)
	(segment
		(start 142.24 -60.0964)
		(end 142.24 -60.96)
		(width 0.381)
		(layer "F.Cu")
		(net "XP1R0V_AGND")
	)
	(segment
		(start 142.860522 -60.0964)
		(end 143.256 -59.700922)
		(width 0.254)
		(layer "F.Cu")
		(net "XP1R0V_AGND")
	)
	(segment
		(start 144.0053 -55.88)
		(end 143.8656 -55.88)
		(width 0.3048)
		(layer "F.Cu")
		(net "XP1R0V_AGND")
	)
	(segment
		(start 143.67256 -55.68696)
		(end 143.254984 -55.68696)
		(width 0.3048)
		(layer "F.Cu")
		(net "XP1R0V_AGND")
	)
	(via
		(at 144.0053 -55.88)
		(size 0.508)
		(drill 0.254)
		(layers "F.Cu" "B.Cu")
		(net "XP1R0V_AGND")
	)
	(via
		(at 146.5834 -57.8866)
		(size 0.4572)
		(drill 0.2032)
		(layers "F.Cu" "B.Cu")
		(net "XP1R0V_AGND")
	)
	(via
		(at 142.24 -60.96)
		(size 0.508)
		(drill 0.254)
		(layers "F.Cu" "B.Cu")
		(net "XP1R0V_AGND")
	)
	(via
		(at 147.0406 -60.0964)
		(size 0.508)
		(drill 0.254)
		(layers "F.Cu" "B.Cu")
		(net "XP1R0V_AGND")
	)
	(segment
		(start 143.03756 -56.84774)
		(end 143.03756 -58.20156)
		(width 0.254)
		(layer "B.Cu")
		(net "XP1R0V_AGND")
	)
	(segment
		(start 143.383 -58.547)
		(end 143.383 -59.298078)
		(width 0.254)
		(layer "B.Cu")
		(net "XP1R0V_AGND")
	)
	(segment
		(start 143.03756 -58.20156)
		(end 143.383 -58.547)
		(width 0.254)
		(layer "B.Cu")
		(net "XP1R0V_AGND")
	)
	(segment
		(start 145.9992 -60.2488)
		(end 144.78 -60.2488)
		(width 0.381)
		(layer "B.Cu")
		(net "XP1R0V_AGND")
	)
	(segment
		(start 147.0406 -60.0964)
		(end 146.1516 -60.0964)
		(width 0.381)
		(layer "B.Cu")
		(net "XP1R0V_AGND")
	)
	(segment
		(start 144.0053 -55.88)
		(end 143.03756 -56.84774)
		(width 0.254)
		(layer "B.Cu")
		(net "XP1R0V_AGND")
	)
	(segment
		(start 146.1516 -60.0964)
		(end 145.9992 -60.2488)
		(width 0.381)
		(layer "B.Cu")
		(net "XP1R0V_AGND")
	)
	(segment
		(start 141.224 -98.674428)
		(end 141.224 -98.949256)
		(width 0.11938)
		(layer "F.Cu")
		(net "XP12R0V_A_PG")
	)
	(segment
		(start 141.224 -98.949256)
		(end 141.1986 -98.974656)
		(width 0.11938)
		(layer "F.Cu")
		(net "XP12R0V_A_PG")
	)
	(segment
		(start 141.114526 -98.564954)
		(end 141.224 -98.674428)
		(width 0.11938)
		(layer "F.Cu")
		(net "XP12R0V_A_PG")
	)
	(segment
		(start 141.1986 -100.8126)
		(end 142.24 -101.854)
		(width 0.11938)
		(layer "F.Cu")
		(net "XP12R0V_A_PG")
	)
	(segment
		(start 141.1986 -100.584)
		(end 141.1986 -100.8126)
		(width 0.11938)
		(layer "F.Cu")
		(net "XP12R0V_A_PG")
	)
	(segment
		(start 141.114526 -97.397824)
		(end 141.114526 -98.564954)
		(width 0.11938)
		(layer "F.Cu")
		(net "XP12R0V_A_PG")
	)
	(segment
		(start 141.1986 -99.441)
		(end 141.1986 -100.584)
		(width 0.11938)
		(layer "F.Cu")
		(net "XP12R0V_A_PG")
	)
	(segment
		(start 141.1986 -98.974656)
		(end 141.1986 -99.441)
		(width 0.11938)
		(layer "F.Cu")
		(net "XP12R0V_A_PG")
	)
	(via
		(at 141.114526 -98.564954)
		(size 0.4572)
		(drill 0.2032)
		(layers "F.Cu" "B.Cu")
		(net "XP12R0V_A_PG")
	)
	(via
		(at 138.811 -61.087)
		(size 0.508)
		(drill 0.254)
		(layers "F.Cu" "B.Cu")
		(net "VIN_XP1R0V")
	)
	(via
		(at 146.431 -55.8038)
		(size 0.508)
		(drill 0.254)
		(layers "F.Cu" "B.Cu")
		(net "VIN_XP1R0V")
	)
	(via
		(at 145.034 -55.3466)
		(size 0.508)
		(drill 0.254)
		(layers "F.Cu" "B.Cu")
		(net "VIN_XP1R0V")
	)
	(via
		(at 138.6332 -54.991)
		(size 0.508)
		(drill 0.254)
		(layers "F.Cu" "B.Cu")
		(net "VIN_XP1R0V")
	)
	(via
		(at 137.414 -54.9656)
		(size 0.508)
		(drill 0.254)
		(layers "F.Cu" "B.Cu")
		(net "VIN_XP1R0V")
	)
	(segment
		(start 138.811 -60.0964)
		(end 138.811 -61.087)
		(width 0.381)
		(layer "B.Cu")
		(net "VIN_XP1R0V")
	)
	(segment
		(start 138.176 -55.4482)
		(end 138.176 -58.547)
		(width 0.381)
		(layer "In2.Cu")
		(net "VIN_XP1R0V")
	)
	(segment
		(start 138.176 -58.547)
		(end 138.811 -59.182)
		(width 0.381)
		(layer "In2.Cu")
		(net "VIN_XP1R0V")
	)
	(segment
		(start 138.6332 -54.991)
		(end 138.176 -55.4482)
		(width 0.381)
		(layer "In2.Cu")
		(net "VIN_XP1R0V")
	)
	(segment
		(start 138.811 -59.182)
		(end 138.811 -61.087)
		(width 0.381)
		(layer "In2.Cu")
		(net "VIN_XP1R0V")
	)
	(via
		(at 143.3449 -60.564522)
		(size 0.762)
		(drill 0.381)
		(layers "F.Cu" "B.Cu")
		(net "UNNAMED_523_CAPACITOR_I9_1")
	)
	(segment
		(start 143.383 -59.827922)
		(end 143.383 -60.526422)
		(width 0.254)
		(layer "B.Cu")
		(net "UNNAMED_523_CAPACITOR_I9_1")
	)
	(segment
		(start 143.383 -60.526422)
		(end 143.3449 -60.564522)
		(width 0.254)
		(layer "B.Cu")
		(net "UNNAMED_523_CAPACITOR_I9_1")
	)
	(segment
		(start 143.3449 -60.564522)
		(end 142.758922 -60.564522)
		(width 0.254)
		(layer "B.Cu")
		(net "UNNAMED_523_CAPACITOR_I9_1")
	)
	(segment
		(start 142.758922 -60.564522)
		(end 142.2908 -60.0964)
		(width 0.254)
		(layer "B.Cu")
		(net "UNNAMED_523_CAPACITOR_I9_1")
	)
	(segment
		(start 142.2908 -60.0964)
		(end 142.24 -60.0964)
		(width 0.254)
		(layer "B.Cu")
		(net "UNNAMED_523_CAPACITOR_I9_1")
	)
	(segment
		(start 140.854938 -56.386984)
		(end 140.854938 -57.544716)
		(width 0.11938)
		(layer "F.Cu")
		(net "UNNAMED_523_CAPACITOR_I7_1")
	)
	(segment
		(start 141.097 -59.0296)
		(end 141.097 -58.510678)
		(width 0.11938)
		(layer "F.Cu")
		(net "UNNAMED_523_CAPACITOR_I7_1")
	)
	(segment
		(start 141.097 -58.510678)
		(end 140.492988 -57.906666)
		(width 0.11938)
		(layer "F.Cu")
		(net "UNNAMED_523_CAPACITOR_I7_1")
	)
	(segment
		(start 140.854938 -57.544716)
		(end 140.492988 -57.906666)
		(width 0.11938)
		(layer "F.Cu")
		(net "UNNAMED_523_CAPACITOR_I7_1")
	)
	(via
		(at 140.492988 -57.906666)
		(size 0.4572)
		(drill 0.2032)
		(layers "F.Cu" "B.Cu")
		(net "UNNAMED_523_CAPACITOR_I7_1")
	)
	(segment
		(start 141.097 -58.510678)
		(end 140.492988 -57.906666)
		(width 0.11938)
		(layer "B.Cu")
		(net "UNNAMED_523_CAPACITOR_I7_1")
	)
	(segment
		(start 141.097 -59.0296)
		(end 139.954 -59.0296)
		(width 0.11938)
		(layer "B.Cu")
		(net "UNNAMED_523_CAPACITOR_I7_1")
	)
	(segment
		(start 141.097 -59.0296)
		(end 141.097 -58.510678)
		(width 0.11938)
		(layer "B.Cu")
		(net "UNNAMED_523_CAPACITOR_I7_1")
	)
	(segment
		(start 139.954 -59.0296)
		(end 138.811 -59.0296)
		(width 0.11938)
		(layer "B.Cu")
		(net "UNNAMED_523_CAPACITOR_I7_1")
	)
	(segment
		(start 143.2814 -50.546)
		(end 143.0274 -50.292)
		(width 0.381)
		(layer "B.Cu")
		(net "UNNAMED_523_CAPACITOR_I31_2")
	)
	(segment
		(start 144.4498 -50.546)
		(end 143.2814 -50.546)
		(width 0.381)
		(layer "B.Cu")
		(net "UNNAMED_523_CAPACITOR_I31_2")
	)
	(segment
		(start 145.3642 -59.827922)
		(end 145.632678 -60.0964)
		(width 0.254)
		(layer "F.Cu")
		(net "UNNAMED_523_CAPACITOR_I28_1")
	)
	(segment
		(start 144.653 -60.9346)
		(end 144.653 -59.827922)
		(width 0.3048)
		(layer "F.Cu")
		(net "UNNAMED_523_CAPACITOR_I28_1")
	)
	(segment
		(start 144.653 -59.827922)
		(end 145.3642 -59.827922)
		(width 0.254)
		(layer "F.Cu")
		(net "UNNAMED_523_CAPACITOR_I28_1")
	)
	(segment
		(start 144.6784 -60.96)
		(end 144.653 -60.9346)
		(width 0.3048)
		(layer "F.Cu")
		(net "UNNAMED_523_CAPACITOR_I28_1")
	)
	(segment
		(start 145.632678 -60.0964)
		(end 146.1516 -60.0964)
		(width 0.254)
		(layer "F.Cu")
		(net "UNNAMED_523_CAPACITOR_I28_1")
	)
	(via
		(at 138.991594 -53.2892)
		(size 0.762)
		(drill 0.381)
		(layers "F.Cu" "B.Cu")
		(net "UNNAMED_523_CAPACITOR_I24_1")
	)
	(segment
		(start 139.372848 -52.4764)
		(end 139.954 -52.4764)
		(width 0.381)
		(layer "B.Cu")
		(net "UNNAMED_523_CAPACITOR_I24_1")
	)
	(segment
		(start 139.446 -54.0766)
		(end 138.991594 -53.622194)
		(width 0.381)
		(layer "B.Cu")
		(net "UNNAMED_523_CAPACITOR_I24_1")
	)
	(segment
		(start 138.991594 -53.2892)
		(end 138.991594 -52.857654)
		(width 0.381)
		(layer "B.Cu")
		(net "UNNAMED_523_CAPACITOR_I24_1")
	)
	(segment
		(start 138.991594 -52.857654)
		(end 139.372848 -52.4764)
		(width 0.381)
		(layer "B.Cu")
		(net "UNNAMED_523_CAPACITOR_I24_1")
	)
	(segment
		(start 139.954 -54.0766)
		(end 139.446 -54.0766)
		(width 0.381)
		(layer "B.Cu")
		(net "UNNAMED_523_CAPACITOR_I24_1")
	)
	(segment
		(start 138.991594 -53.622194)
		(end 138.991594 -53.2892)
		(width 0.381)
		(layer "B.Cu")
		(net "UNNAMED_523_CAPACITOR_I24_1")
	)
	(segment
		(start 98.2726 -24.638)
		(end 96.7994 -24.638)
		(width 0.11938)
		(layer "F.Cu")
		(net "VDD3V3_OSC_125M")
	)
	(segment
		(start 96.9518 -24.4856)
		(end 96.9518 -23.4696)
		(width 0.11938)
		(layer "F.Cu")
		(net "VDD3V3_OSC_125M")
	)
	(segment
		(start 95.758 -23.2664)
		(end 96.7486 -23.2664)
		(width 0.11938)
		(layer "F.Cu")
		(net "VDD3V3_OSC_125M")
	)
	(segment
		(start 96.9518 -23.4696)
		(end 97.616518 -22.804882)
		(width 0.11938)
		(layer "F.Cu")
		(net "VDD3V3_OSC_125M")
	)
	(segment
		(start 97.616518 -22.804882)
		(end 98.552 -22.804882)
		(width 0.11938)
		(layer "F.Cu")
		(net "VDD3V3_OSC_125M")
	)
	(segment
		(start 96.7994 -24.638)
		(end 96.9518 -24.4856)
		(width 0.11938)
		(layer "F.Cu")
		(net "VDD3V3_OSC_125M")
	)
	(segment
		(start 96.7486 -23.2664)
		(end 96.9518 -23.4696)
		(width 0.11938)
		(layer "F.Cu")
		(net "VDD3V3_OSC_125M")
	)
	(via
		(at 96.9518 -23.4696)
		(size 0.4572)
		(drill 0.2032)
		(layers "F.Cu" "B.Cu")
		(net "VDD3V3_OSC_125M")
	)
	(segment
		(start 96.774 -23.2918)
		(end 96.9518 -23.4696)
		(width 0.11938)
		(layer "B.Cu")
		(net "VDD3V3_OSC_125M")
	)
	(segment
		(start 95.758 -23.2918)
		(end 96.774 -23.2918)
		(width 0.11938)
		(layer "B.Cu")
		(net "VDD3V3_OSC_125M")
	)
	(segment
		(start 107.188 -23.3934)
		(end 107.95 -22.6314)
		(width 0.381)
		(layer "F.Cu")
		(net "VDD3V3_OSC_200M")
	)
	(segment
		(start 108.830364 -22.2758)
		(end 107.95 -22.2758)
		(width 0.381)
		(layer "F.Cu")
		(net "VDD3V3_OSC_200M")
	)
	(segment
		(start 109.5756 -23.021036)
		(end 108.830364 -22.2758)
		(width 0.381)
		(layer "F.Cu")
		(net "VDD3V3_OSC_200M")
	)
	(segment
		(start 107.95 -22.6314)
		(end 107.95 -22.2758)
		(width 0.381)
		(layer "F.Cu")
		(net "VDD3V3_OSC_200M")
	)
	(segment
		(start 106.807 -23.3934)
		(end 107.188 -23.3934)
		(width 0.381)
		(layer "F.Cu")
		(net "VDD3V3_OSC_200M")
	)
	(via
		(at 107.95 -22.2758)
		(size 0.508)
		(drill 0.254)
		(layers "F.Cu" "B.Cu")
		(net "VDD3V3_OSC_200M")
	)
	(segment
		(start 108.585 -23.3426)
		(end 108.5596 -23.3426)
		(width 0.381)
		(layer "B.Cu")
		(net "VDD3V3_OSC_200M")
	)
	(segment
		(start 108.5596 -23.3426)
		(end 107.95 -22.733)
		(width 0.381)
		(layer "B.Cu")
		(net "VDD3V3_OSC_200M")
	)
	(segment
		(start 108.458 -21.1328)
		(end 109.728 -22.4028)
		(width 0.381)
		(layer "B.Cu")
		(net "VDD3V3_OSC_200M")
	)
	(segment
		(start 109.728 -22.4028)
		(end 109.728 -23.3426)
		(width 0.381)
		(layer "B.Cu")
		(net "VDD3V3_OSC_200M")
	)
	(segment
		(start 109.728 -23.3426)
		(end 108.585 -23.3426)
		(width 0.4572)
		(layer "B.Cu")
		(net "VDD3V3_OSC_200M")
	)
	(segment
		(start 107.95 -22.733)
		(end 107.95 -22.2758)
		(width 0.381)
		(layer "B.Cu")
		(net "VDD3V3_OSC_200M")
	)
	(segment
		(start 141.359382 -17.2466)
		(end 139.954 -17.2466)
		(width 0.11938)
		(layer "F.Cu")
		(net "UNNAMED_515_ISL80101IRAJZDFN10_")
	)
	(segment
		(start 138.43 -17.6276)
		(end 138.3284 -17.526)
		(width 0.11938)
		(layer "F.Cu")
		(net "UNNAMED_515_ISL80101IRAJZDFN10_")
	)
	(segment
		(start 139.573 -17.6276)
		(end 138.43 -17.6276)
		(width 0.11938)
		(layer "F.Cu")
		(net "UNNAMED_515_ISL80101IRAJZDFN10_")
	)
	(segment
		(start 139.954 -17.2466)
		(end 139.573 -17.6276)
		(width 0.11938)
		(layer "F.Cu")
		(net "UNNAMED_515_ISL80101IRAJZDFN10_")
	)
	(via
		(at 139.573 -17.6276)
		(size 0.4572)
		(drill 0.2032)
		(layers "F.Cu" "B.Cu")
		(net "UNNAMED_515_ISL80101IRAJZDFN10_")
	)
	(segment
		(start 138.3284 -17.526)
		(end 138.43 -17.6276)
		(width 0.11938)
		(layer "B.Cu")
		(net "UNNAMED_515_ISL80101IRAJZDFN10_")
	)
	(segment
		(start 141.1478 -17.907)
		(end 139.8524 -17.907)
		(width 0.11938)
		(layer "B.Cu")
		(net "UNNAMED_515_ISL80101IRAJZDFN10_")
	)
	(segment
		(start 139.8524 -17.907)
		(end 139.573 -17.6276)
		(width 0.11938)
		(layer "B.Cu")
		(net "UNNAMED_515_ISL80101IRAJZDFN10_")
	)
	(segment
		(start 138.43 -17.6276)
		(end 139.573 -17.6276)
		(width 0.11938)
		(layer "B.Cu")
		(net "UNNAMED_515_ISL80101IRAJZDFN10_")
	)
	(segment
		(start 139.7 -16.129)
		(end 139.446 -16.129)
		(width 0.11938)
		(layer "F.Cu")
		(net "UNNAMED_515_CAPACITOR_I138_1")
	)
	(segment
		(start 141.359382 -16.746474)
		(end 140.317474 -16.746474)
		(width 0.11938)
		(layer "F.Cu")
		(net "UNNAMED_515_CAPACITOR_I138_1")
	)
	(segment
		(start 139.446 -16.129)
		(end 138.694922 -16.129)
		(width 0.11938)
		(layer "F.Cu")
		(net "UNNAMED_515_CAPACITOR_I138_1")
	)
	(segment
		(start 140.317474 -16.746474)
		(end 139.7 -16.129)
		(width 0.11938)
		(layer "F.Cu")
		(net "UNNAMED_515_CAPACITOR_I138_1")
	)
	(via
		(at 139.446 -16.129)
		(size 0.508)
		(drill 0.254)
		(layers "F.Cu" "B.Cu")
		(net "UNNAMED_515_CAPACITOR_I138_1")
	)
	(segment
		(start 140.081 -16.51)
		(end 139.7 -16.129)
		(width 0.11938)
		(layer "B.Cu")
		(net "UNNAMED_515_CAPACITOR_I138_1")
	)
	(segment
		(start 141.097 -16.51)
		(end 140.081 -16.51)
		(width 0.11938)
		(layer "B.Cu")
		(net "UNNAMED_515_CAPACITOR_I138_1")
	)
	(segment
		(start 139.7 -16.129)
		(end 139.446 -16.129)
		(width 0.11938)
		(layer "B.Cu")
		(net "UNNAMED_515_CAPACITOR_I138_1")
	)
	(segment
		(start 139.446 -16.129)
		(end 139.319 -16.256)
		(width 0.11938)
		(layer "B.Cu")
		(net "UNNAMED_515_CAPACITOR_I138_1")
	)
	(segment
		(start 139.319 -16.256)
		(end 138.3284 -16.256)
		(width 0.11938)
		(layer "B.Cu")
		(net "UNNAMED_515_CAPACITOR_I138_1")
	)
	(segment
		(start 145.51533 -16.246348)
		(end 146.293078 -15.4686)
		(width 0.3048)
		(layer "F.Cu")
		(net "UNNAMED_515_CAPACITOR_I132_1")
	)
	(segment
		(start 144.390618 -16.246348)
		(end 145.51533 -16.246348)
		(width 0.3048)
		(layer "F.Cu")
		(net "UNNAMED_515_CAPACITOR_I132_1")
	)
	(segment
		(start 146.140932 -15.316454)
		(end 146.293078 -15.4686)
		(width 0.3048)
		(layer "F.Cu")
		(net "UNNAMED_515_CAPACITOR_I132_1")
	)
	(segment
		(start 145.415 -15.316454)
		(end 146.140932 -15.316454)
		(width 0.3048)
		(layer "F.Cu")
		(net "UNNAMED_515_CAPACITOR_I132_1")
	)
	(via
		(at 145.415 -15.316454)
		(size 0.4572)
		(drill 0.2032)
		(layers "F.Cu" "B.Cu")
		(net "UNNAMED_515_CAPACITOR_I132_1")
	)
	(segment
		(start 145.5674 -20.2184)
		(end 146.685 -20.2184)
		(width 0.254)
		(layer "F.Cu")
		(net "UNNAMED_515_CAPACITOR_I130_1")
	)
	(via
		(at 144.4244 -19.304)
		(size 0.4572)
		(drill 0.2032)
		(layers "F.Cu" "B.Cu")
		(net "UNNAMED_515_CAPACITOR_I130_1")
	)
	(segment
		(start 145.99158 -17.16278)
		(end 145.50898 -17.16278)
		(width 0.11938)
		(layer "F.Cu")
		(net "UNNAMED_515_CAPACITOR_I128_1")
	)
	(segment
		(start 146.685 -17.8562)
		(end 146.6088 -17.78)
		(width 0.11938)
		(layer "F.Cu")
		(net "UNNAMED_515_CAPACITOR_I128_1")
	)
	(segment
		(start 146.685 -19.1516)
		(end 146.685 -17.8562)
		(width 0.11938)
		(layer "F.Cu")
		(net "UNNAMED_515_CAPACITOR_I128_1")
	)
	(segment
		(start 144.390618 -16.746474)
		(end 145.092674 -16.746474)
		(width 0.11938)
		(layer "F.Cu")
		(net "UNNAMED_515_CAPACITOR_I128_1")
	)
	(segment
		(start 145.092674 -16.746474)
		(end 145.50898 -17.16278)
		(width 0.11938)
		(layer "F.Cu")
		(net "UNNAMED_515_CAPACITOR_I128_1")
	)
	(segment
		(start 146.6088 -17.78)
		(end 145.99158 -17.16278)
		(width 0.11938)
		(layer "F.Cu")
		(net "UNNAMED_515_CAPACITOR_I128_1")
	)
	(via
		(at 145.50898 -17.16278)
		(size 0.4572)
		(drill 0.2032)
		(layers "F.Cu" "B.Cu")
		(net "UNNAMED_515_CAPACITOR_I128_1")
	)
	(segment
		(start 146.6088 -17.78)
		(end 146.6088 -19.0754)
		(width 0.11938)
		(layer "B.Cu")
		(net "UNNAMED_515_CAPACITOR_I128_1")
	)
	(segment
		(start 146.6088 -19.0754)
		(end 146.685 -19.1516)
		(width 0.11938)
		(layer "B.Cu")
		(net "UNNAMED_515_CAPACITOR_I128_1")
	)
	(segment
		(start 147.955 -19.1516)
		(end 146.685 -19.1516)
		(width 0.11938)
		(layer "B.Cu")
		(net "UNNAMED_515_CAPACITOR_I128_1")
	)
	(segment
		(start 146.6088 -17.78)
		(end 145.669 -17.78)
		(width 0.11938)
		(layer "B.Cu")
		(net "UNNAMED_515_CAPACITOR_I128_1")
	)
	(segment
		(start 145.669 -17.78)
		(end 145.50898 -17.61998)
		(width 0.11938)
		(layer "B.Cu")
		(net "UNNAMED_515_CAPACITOR_I128_1")
	)
	(segment
		(start 145.50898 -17.61998)
		(end 145.50898 -17.16278)
		(width 0.11938)
		(layer "B.Cu")
		(net "UNNAMED_515_CAPACITOR_I128_1")
	)
	(via
		(at 148.717 -104.013)
		(size 0.762)
		(drill 0.381)
		(layers "F.Cu" "B.Cu")
		(net "UNNAMED_14_RESISTOR_I65_2")
	)
	(segment
		(start 148.717 -104.267)
		(end 148.717 -104.013)
		(width 0.11938)
		(layer "B.Cu")
		(net "UNNAMED_14_RESISTOR_I65_2")
	)
	(segment
		(start 147.5994 -103.505)
		(end 148.463 -103.505)
		(width 0.11938)
		(layer "B.Cu")
		(net "UNNAMED_14_RESISTOR_I65_2")
	)
	(segment
		(start 148.717 -103.759)
		(end 148.717 -104.013)
		(width 0.11938)
		(layer "B.Cu")
		(net "UNNAMED_14_RESISTOR_I65_2")
	)
	(segment
		(start 147.5994 -104.648)
		(end 148.336 -104.648)
		(width 0.11938)
		(layer "B.Cu")
		(net "UNNAMED_14_RESISTOR_I65_2")
	)
	(segment
		(start 148.336 -104.648)
		(end 148.717 -104.267)
		(width 0.11938)
		(layer "B.Cu")
		(net "UNNAMED_14_RESISTOR_I65_2")
	)
	(segment
		(start 148.463 -103.505)
		(end 148.717 -103.759)
		(width 0.11938)
		(layer "B.Cu")
		(net "UNNAMED_14_RESISTOR_I65_2")
	)
	(via
		(at 142.679674 -103.759)
		(size 0.762)
		(drill 0.381)
		(layers "F.Cu" "B.Cu")
		(net "UNNAMED_14_RESISTOR_I58_2")
	)
	(segment
		(start 142.113 -104.521)
		(end 141.5034 -104.521)
		(width 0.11938)
		(layer "B.Cu")
		(net "UNNAMED_14_RESISTOR_I58_2")
	)
	(segment
		(start 142.560294 -103.378)
		(end 142.679674 -103.49738)
		(width 0.11938)
		(layer "B.Cu")
		(net "UNNAMED_14_RESISTOR_I58_2")
	)
	(segment
		(start 142.679674 -103.954326)
		(end 142.113 -104.521)
		(width 0.11938)
		(layer "B.Cu")
		(net "UNNAMED_14_RESISTOR_I58_2")
	)
	(segment
		(start 141.5034 -103.378)
		(end 142.560294 -103.378)
		(width 0.11938)
		(layer "B.Cu")
		(net "UNNAMED_14_RESISTOR_I58_2")
	)
	(segment
		(start 142.679674 -103.759)
		(end 142.679674 -103.954326)
		(width 0.11938)
		(layer "B.Cu")
		(net "UNNAMED_14_RESISTOR_I58_2")
	)
	(segment
		(start 142.679674 -103.49738)
		(end 142.679674 -103.759)
		(width 0.11938)
		(layer "B.Cu")
		(net "UNNAMED_14_RESISTOR_I58_2")
	)
	(segment
		(start 138.050016 -105.099866)
		(end 136.793732 -105.099866)
		(width 0.11938)
		(layer "F.Cu")
		(net "UNNAMED_14_OPTICAL_I140_A")
	)
	(via
		(at 136.793732 -105.099866)
		(size 0.508)
		(drill 0.254)
		(layers "F.Cu" "B.Cu")
		(net "UNNAMED_14_OPTICAL_I140_A")
	)
	(segment
		(start 136.793732 -105.099866)
		(end 137.143998 -104.7496)
		(width 0.11938)
		(layer "B.Cu")
		(net "UNNAMED_14_OPTICAL_I140_A")
	)
	(segment
		(start 137.143998 -104.7496)
		(end 138.049 -104.7496)
		(width 0.11938)
		(layer "B.Cu")
		(net "UNNAMED_14_OPTICAL_I140_A")
	)
	(segment
		(start 140.024866 -105.099866)
		(end 141.05001 -105.099866)
		(width 0.11938)
		(layer "F.Cu")
		(net "UNNAMED_14_OPTICAL_I141_A")
	)
	(segment
		(start 139.319 -104.394)
		(end 140.024866 -105.099866)
		(width 0.11938)
		(layer "F.Cu")
		(net "UNNAMED_14_OPTICAL_I141_A")
	)
	(via
		(at 139.319 -104.394)
		(size 0.508)
		(drill 0.254)
		(layers "F.Cu" "B.Cu")
		(net "UNNAMED_14_OPTICAL_I141_A")
	)
	(segment
		(start 139.446 -104.521)
		(end 140.4366 -104.521)
		(width 0.11938)
		(layer "B.Cu")
		(net "UNNAMED_14_OPTICAL_I141_A")
	)
	(segment
		(start 139.319 -104.394)
		(end 139.446 -104.521)
		(width 0.11938)
		(layer "B.Cu")
		(net "UNNAMED_14_OPTICAL_I141_A")
	)
	(segment
		(start 145.485866 -105.099866)
		(end 147.049998 -105.099866)
		(width 0.11938)
		(layer "F.Cu")
		(net "UNNAMED_14_OPTICAL_I143_A")
	)
	(segment
		(start 145.415 -105.029)
		(end 145.485866 -105.099866)
		(width 0.11938)
		(layer "F.Cu")
		(net "UNNAMED_14_OPTICAL_I143_A")
	)
	(via
		(at 145.415 -105.029)
		(size 0.508)
		(drill 0.254)
		(layers "F.Cu" "B.Cu")
		(net "UNNAMED_14_OPTICAL_I143_A")
	)
	(segment
		(start 145.415 -105.029)
		(end 145.796 -104.648)
		(width 0.11938)
		(layer "B.Cu")
		(net "UNNAMED_14_OPTICAL_I143_A")
	)
	(segment
		(start 145.796 -104.648)
		(end 146.5326 -104.648)
		(width 0.11938)
		(layer "B.Cu")
		(net "UNNAMED_14_OPTICAL_I143_A")
	)
	(segment
		(start 144.050004 -105.099866)
		(end 142.79372 -105.099866)
		(width 0.11938)
		(layer "F.Cu")
		(net "UNNAMED_14_OPTICAL_I142_A")
	)
	(via
		(at 142.79372 -105.099866)
		(size 0.508)
		(drill 0.254)
		(layers "F.Cu" "B.Cu")
		(net "UNNAMED_14_OPTICAL_I142_A")
	)
	(segment
		(start 143.093186 -104.8004)
		(end 144.145 -104.8004)
		(width 0.11938)
		(layer "B.Cu")
		(net "UNNAMED_14_OPTICAL_I142_A")
	)
	(segment
		(start 142.79372 -105.099866)
		(end 143.093186 -104.8004)
		(width 0.11938)
		(layer "B.Cu")
		(net "UNNAMED_14_OPTICAL_I142_A")
	)
	(segment
		(start 134.1882 -106.922062)
		(end 135.2042 -107.938062)
		(width 0.11938)
		(layer "F.Cu")
		(net "UNNAMED_14_OPTICAL_I292_A")
	)
	(segment
		(start 135.2042 -107.938062)
		(end 135.2042 -108.1278)
		(width 0.11938)
		(layer "F.Cu")
		(net "UNNAMED_14_OPTICAL_I292_A")
	)
	(via
		(at 135.2042 -108.1278)
		(size 0.4572)
		(drill 0.2032)
		(layers "F.Cu" "B.Cu")
		(net "UNNAMED_14_OPTICAL_I292_A")
	)
	(segment
		(start 135.2042 -106.705654)
		(end 135.2042 -108.1278)
		(width 0.11938)
		(layer "B.Cu")
		(net "UNNAMED_14_OPTICAL_I292_A")
	)
	(segment
		(start 95.7326 -84.709)
		(end 97.282 -84.709)
		(width 0.11938)
		(layer "F.Cu")
		(net "UNNAMED_127_MT25QL128ABA1ESES_3")
	)
	(via
		(at 97.282 -84.709)
		(size 0.4572)
		(drill 0.2032)
		(layers "F.Cu" "B.Cu")
		(net "UNNAMED_127_MT25QL128ABA1ESES_3")
	)
	(segment
		(start 97.282 -84.709)
		(end 97.282 -85.344)
		(width 0.11938)
		(layer "B.Cu")
		(net "UNNAMED_127_MT25QL128ABA1ESES_3")
	)
	(segment
		(start 97.028 -85.598)
		(end 96.1644 -85.598)
		(width 0.11938)
		(layer "B.Cu")
		(net "UNNAMED_127_MT25QL128ABA1ESES_3")
	)
	(segment
		(start 96.1644 -85.598)
		(end 96.1644 -86.741)
		(width 0.11938)
		(layer "B.Cu")
		(net "UNNAMED_127_MT25QL128ABA1ESES_3")
	)
	(segment
		(start 97.282 -85.344)
		(end 97.028 -85.598)
		(width 0.11938)
		(layer "B.Cu")
		(net "UNNAMED_127_MT25QL128ABA1ESES_3")
	)
	(segment
		(start 88.4174 -83.439)
		(end 86.741 -83.439)
		(width 0.11938)
		(layer "F.Cu")
		(net "UNNAMED_127_MT25QL128ABA1ESES_2")
	)
	(via
		(at 86.741 -83.439)
		(size 0.4572)
		(drill 0.2032)
		(layers "F.Cu" "B.Cu")
		(net "UNNAMED_127_MT25QL128ABA1ESES_2")
	)
	(segment
		(start 86.868 -83.312)
		(end 87.9856 -83.312)
		(width 0.11938)
		(layer "B.Cu")
		(net "UNNAMED_127_MT25QL128ABA1ESES_2")
	)
	(segment
		(start 87.9856 -82.169)
		(end 87.9856 -83.312)
		(width 0.11938)
		(layer "B.Cu")
		(net "UNNAMED_127_MT25QL128ABA1ESES_2")
	)
	(segment
		(start 86.741 -83.439)
		(end 86.868 -83.312)
		(width 0.11938)
		(layer "B.Cu")
		(net "UNNAMED_127_MT25QL128ABA1ESES_2")
	)
	(segment
		(start 95.7326 -83.439)
		(end 97.282 -83.439)
		(width 0.11938)
		(layer "F.Cu")
		(net "UNNAMED_127_MT25QL128ABA1ESES_1")
	)
	(via
		(at 97.282 -83.439)
		(size 0.4572)
		(drill 0.2032)
		(layers "F.Cu" "B.Cu")
		(net "UNNAMED_127_MT25QL128ABA1ESES_1")
	)
	(segment
		(start 97.282 -83.439)
		(end 97.155 -83.312)
		(width 0.11938)
		(layer "B.Cu")
		(net "UNNAMED_127_MT25QL128ABA1ESES_1")
	)
	(segment
		(start 96.1644 -83.312)
		(end 96.1644 -84.455)
		(width 0.11938)
		(layer "B.Cu")
		(net "UNNAMED_127_MT25QL128ABA1ESES_1")
	)
	(segment
		(start 97.155 -83.312)
		(end 96.1644 -83.312)
		(width 0.11938)
		(layer "B.Cu")
		(net "UNNAMED_127_MT25QL128ABA1ESES_1")
	)
	(segment
		(start 88.4174 -85.979)
		(end 86.741 -85.979)
		(width 0.11938)
		(layer "F.Cu")
		(net "UNNAMED_127_MT25QL128ABA1ESESOP")
	)
	(via
		(at 86.741 -85.979)
		(size 0.4572)
		(drill 0.2032)
		(layers "F.Cu" "B.Cu")
		(net "UNNAMED_127_MT25QL128ABA1ESESOP")
	)
	(segment
		(start 87.9856 -86.741)
		(end 87.9856 -85.598)
		(width 0.11938)
		(layer "B.Cu")
		(net "UNNAMED_127_MT25QL128ABA1ESESOP")
	)
	(segment
		(start 86.741 -85.979)
		(end 87.122 -85.598)
		(width 0.11938)
		(layer "B.Cu")
		(net "UNNAMED_127_MT25QL128ABA1ESESOP")
	)
	(segment
		(start 87.122 -85.598)
		(end 87.9856 -85.598)
		(width 0.11938)
		(layer "B.Cu")
		(net "UNNAMED_127_MT25QL128ABA1ESESOP")
	)
	(segment
		(start 119.847106 -50.823114)
		(end 120.019572 -50.99558)
		(width 0.11938)
		(layer "F.Cu")
		(net "UART_MAC_TX_FPGA_RX")
	)
	(segment
		(start 123.068842 -49.53)
		(end 123.93422 -49.53)
		(width 0.11938)
		(layer "F.Cu")
		(net "UART_MAC_TX_FPGA_RX")
	)
	(segment
		(start 124.0536 -49.64938)
		(end 124.0536 -50.165)
		(width 0.11938)
		(layer "F.Cu")
		(net "UART_MAC_TX_FPGA_RX")
	)
	(segment
		(start 122.903234 -50.353214)
		(end 122.903234 -49.695608)
		(width 0.11938)
		(layer "F.Cu")
		(net "UART_MAC_TX_FPGA_RX")
	)
	(segment
		(start 122.260868 -50.99558)
		(end 122.903234 -50.353214)
		(width 0.11938)
		(layer "F.Cu")
		(net "UART_MAC_TX_FPGA_RX")
	)
	(segment
		(start 123.93422 -49.53)
		(end 124.0536 -49.64938)
		(width 0.11938)
		(layer "F.Cu")
		(net "UART_MAC_TX_FPGA_RX")
	)
	(segment
		(start 120.019572 -50.99558)
		(end 122.260868 -50.99558)
		(width 0.11938)
		(layer "F.Cu")
		(net "UART_MAC_TX_FPGA_RX")
	)
	(segment
		(start 122.903234 -49.695608)
		(end 123.068842 -49.53)
		(width 0.11938)
		(layer "F.Cu")
		(net "UART_MAC_TX_FPGA_RX")
	)
	(via
		(at 122.903234 -50.353214)
		(size 0.508)
		(drill 0.254)
		(layers "F.Cu" "B.Cu")
		(net "UART_MAC_TX_FPGA_RX")
	)
	(segment
		(start 124.0536 -50.165)
		(end 123.091448 -50.165)
		(width 0.11938)
		(layer "B.Cu")
		(net "UART_MAC_TX_FPGA_RX")
	)
	(segment
		(start 123.091448 -50.165)
		(end 122.903234 -50.353214)
		(width 0.11938)
		(layer "B.Cu")
		(net "UART_MAC_TX_FPGA_RX")
	)
	(segment
		(start 121.993152 -51.762152)
		(end 122.12066 -51.762152)
		(width 0.11938)
		(layer "F.Cu")
		(net "UART_MAC_RX_FPGA_TX")
	)
	(segment
		(start 121.993152 -51.762152)
		(end 121.642632 -51.411632)
		(width 0.11938)
		(layer "F.Cu")
		(net "UART_MAC_RX_FPGA_TX")
	)
	(segment
		(start 123.952 -51.435)
		(end 124.0536 -51.435)
		(width 0.11938)
		(layer "F.Cu")
		(net "UART_MAC_RX_FPGA_TX")
	)
	(segment
		(start 121.642632 -51.411632)
		(end 119.435626 -51.411632)
		(width 0.11938)
		(layer "F.Cu")
		(net "UART_MAC_RX_FPGA_TX")
	)
	(segment
		(start 122.955812 -50.927)
		(end 123.444 -50.927)
		(width 0.11938)
		(layer "F.Cu")
		(net "UART_MAC_RX_FPGA_TX")
	)
	(segment
		(start 119.435626 -51.411632)
		(end 118.847108 -50.823114)
		(width 0.11938)
		(layer "F.Cu")
		(net "UART_MAC_RX_FPGA_TX")
	)
	(segment
		(start 123.444 -50.927)
		(end 123.952 -51.435)
		(width 0.11938)
		(layer "F.Cu")
		(net "UART_MAC_RX_FPGA_TX")
	)
	(segment
		(start 122.12066 -51.762152)
		(end 122.955812 -50.927)
		(width 0.11938)
		(layer "F.Cu")
		(net "UART_MAC_RX_FPGA_TX")
	)
	(via
		(at 121.993152 -51.762152)
		(size 0.508)
		(drill 0.254)
		(layers "F.Cu" "B.Cu")
		(net "UART_MAC_RX_FPGA_TX")
	)
	(segment
		(start 110.847124 -47.82312)
		(end 111.346996 -48.322992)
		(width 0.11938)
		(layer "F.Cu")
		(net "UART_GPS_TX_FPGA_RX")
	)
	(via
		(at 126.238 -86.614)
		(size 0.508)
		(drill 0.254)
		(layers "F.Cu" "B.Cu")
		(net "UART_GPS_TX_FPGA_RX")
	)
	(via
		(at 111.346996 -48.322992)
		(size 0.4572)
		(drill 0.2032)
		(layers "F.Cu" "B.Cu")
		(net "UART_GPS_TX_FPGA_RX")
	)
	(segment
		(start 127.7874 -87.2744)
		(end 127.7874 -87.757)
		(width 0.11938)
		(layer "B.Cu")
		(net "UART_GPS_TX_FPGA_RX")
	)
	(segment
		(start 127.127 -86.614)
		(end 127.7874 -87.2744)
		(width 0.11938)
		(layer "B.Cu")
		(net "UART_GPS_TX_FPGA_RX")
	)
	(segment
		(start 127.7874 -88.4936)
		(end 127.7874 -87.757)
		(width 0.11938)
		(layer "B.Cu")
		(net "UART_GPS_TX_FPGA_RX")
	)
	(segment
		(start 127.2794 -89.0016)
		(end 127.7874 -88.4936)
		(width 0.11938)
		(layer "B.Cu")
		(net "UART_GPS_TX_FPGA_RX")
	)
	(segment
		(start 126.619 -89.0016)
		(end 127.2794 -89.0016)
		(width 0.11938)
		(layer "B.Cu")
		(net "UART_GPS_TX_FPGA_RX")
	)
	(segment
		(start 126.238 -86.614)
		(end 127.127 -86.614)
		(width 0.11938)
		(layer "B.Cu")
		(net "UART_GPS_TX_FPGA_RX")
	)
	(segment
		(start 111.887 -48.862996)
		(end 111.346996 -48.322992)
		(width 0.127)
		(layer "In2.Cu")
		(net "UART_GPS_TX_FPGA_RX")
	)
	(segment
		(start 111.887 -52.49672)
		(end 111.887 -48.862996)
		(width 0.127)
		(layer "In2.Cu")
		(net "UART_GPS_TX_FPGA_RX")
	)
	(segment
		(start 123.698 -86.614)
		(end 122.809 -85.725)
		(width 0.127)
		(layer "In2.Cu")
		(net "UART_GPS_TX_FPGA_RX")
	)
	(segment
		(start 118.364 -84.074)
		(end 118.364 -81.026)
		(width 0.127)
		(layer "In2.Cu")
		(net "UART_GPS_TX_FPGA_RX")
	)
	(segment
		(start 114.681 -75.438)
		(end 114.681 -69.214746)
		(width 0.127)
		(layer "In2.Cu")
		(net "UART_GPS_TX_FPGA_RX")
	)
	(segment
		(start 114.4905 -62.247018)
		(end 115.316 -61.421518)
		(width 0.127)
		(layer "In2.Cu")
		(net "UART_GPS_TX_FPGA_RX")
	)
	(segment
		(start 112.52454 -52.832)
		(end 112.22228 -52.832)
		(width 0.127)
		(layer "In2.Cu")
		(net "UART_GPS_TX_FPGA_RX")
	)
	(segment
		(start 116.586 -79.248)
		(end 116.586 -77.343)
		(width 0.127)
		(layer "In2.Cu")
		(net "UART_GPS_TX_FPGA_RX")
	)
	(segment
		(start 115.316 -61.421518)
		(end 115.316 -57.023254)
		(width 0.127)
		(layer "In2.Cu")
		(net "UART_GPS_TX_FPGA_RX")
	)
	(segment
		(start 120.015 -85.725)
		(end 118.364 -84.074)
		(width 0.127)
		(layer "In2.Cu")
		(net "UART_GPS_TX_FPGA_RX")
	)
	(segment
		(start 112.89538 -53.20284)
		(end 112.52454 -52.832)
		(width 0.127)
		(layer "In2.Cu")
		(net "UART_GPS_TX_FPGA_RX")
	)
	(segment
		(start 122.809 -85.725)
		(end 120.015 -85.725)
		(width 0.127)
		(layer "In2.Cu")
		(net "UART_GPS_TX_FPGA_RX")
	)
	(segment
		(start 118.364 -81.026)
		(end 116.586 -79.248)
		(width 0.127)
		(layer "In2.Cu")
		(net "UART_GPS_TX_FPGA_RX")
	)
	(segment
		(start 114.4905 -69.024246)
		(end 114.4905 -62.247018)
		(width 0.127)
		(layer "In2.Cu")
		(net "UART_GPS_TX_FPGA_RX")
	)
	(segment
		(start 114.681 -69.214746)
		(end 114.4905 -69.024246)
		(width 0.127)
		(layer "In2.Cu")
		(net "UART_GPS_TX_FPGA_RX")
	)
	(segment
		(start 126.238 -86.614)
		(end 123.698 -86.614)
		(width 0.127)
		(layer "In2.Cu")
		(net "UART_GPS_TX_FPGA_RX")
	)
	(segment
		(start 112.22228 -52.832)
		(end 111.887 -52.49672)
		(width 0.127)
		(layer "In2.Cu")
		(net "UART_GPS_TX_FPGA_RX")
	)
	(segment
		(start 116.586 -77.343)
		(end 114.681 -75.438)
		(width 0.127)
		(layer "In2.Cu")
		(net "UART_GPS_TX_FPGA_RX")
	)
	(segment
		(start 115.316 -57.023254)
		(end 112.89538 -54.602634)
		(width 0.127)
		(layer "In2.Cu")
		(net "UART_GPS_TX_FPGA_RX")
	)
	(segment
		(start 112.89538 -54.602634)
		(end 112.89538 -53.20284)
		(width 0.127)
		(layer "In2.Cu")
		(net "UART_GPS_TX_FPGA_RX")
	)
	(segment
		(start 111.847122 -52.82311)
		(end 112.346994 -53.322982)
		(width 0.11938)
		(layer "F.Cu")
		(net "UART_GPS_RX_FPGA_TX")
	)
	(via
		(at 122.174 -86.614)
		(size 0.508)
		(drill 0.254)
		(layers "F.Cu" "B.Cu")
		(net "UART_GPS_RX_FPGA_TX")
	)
	(via
		(at 112.346994 -53.322982)
		(size 0.4572)
		(drill 0.2032)
		(layers "F.Cu" "B.Cu")
		(net "UART_GPS_RX_FPGA_TX")
	)
	(segment
		(start 125.349 -88.351106)
		(end 125.349 -89.0016)
		(width 0.11938)
		(layer "B.Cu")
		(net "UART_GPS_RX_FPGA_TX")
	)
	(segment
		(start 123.611894 -86.614)
		(end 125.349 -88.351106)
		(width 0.11938)
		(layer "B.Cu")
		(net "UART_GPS_RX_FPGA_TX")
	)
	(segment
		(start 122.174 -86.614)
		(end 123.611894 -86.614)
		(width 0.11938)
		(layer "B.Cu")
		(net "UART_GPS_RX_FPGA_TX")
	)
	(segment
		(start 113.3475 -68.7705)
		(end 114.173 -69.596)
		(width 0.127)
		(layer "In2.Cu")
		(net "UART_GPS_RX_FPGA_TX")
	)
	(segment
		(start 113.2205 -65.490344)
		(end 111.379 -65.490344)
		(width 0.127)
		(layer "In2.Cu")
		(net "UART_GPS_RX_FPGA_TX")
	)
	(segment
		(start 114.681 -60.96)
		(end 113.3475 -62.2935)
		(width 0.127)
		(layer "In2.Cu")
		(net "UART_GPS_RX_FPGA_TX")
	)
	(segment
		(start 111.0996 -64.220344)
		(end 110.9726 -64.347344)
		(width 0.127)
		(layer "In2.Cu")
		(net "UART_GPS_RX_FPGA_TX")
	)
	(segment
		(start 116.078 -78.993746)
		(end 116.078 -79.458566)
		(width 0.127)
		(layer "In2.Cu")
		(net "UART_GPS_RX_FPGA_TX")
	)
	(segment
		(start 112.346994 -54.815994)
		(end 114.681 -57.15)
		(width 0.127)
		(layer "In2.Cu")
		(net "UART_GPS_RX_FPGA_TX")
	)
	(segment
		(start 111.2012 -65.947544)
		(end 111.379 -66.125344)
		(width 0.127)
		(layer "In2.Cu")
		(net "UART_GPS_RX_FPGA_TX")
	)
	(segment
		(start 115.1255 -77.614018)
		(end 115.1255 -78.041246)
		(width 0.127)
		(layer "In2.Cu")
		(net "UART_GPS_RX_FPGA_TX")
	)
	(segment
		(start 110.9726 -64.728344)
		(end 111.0996 -64.855344)
		(width 0.127)
		(layer "In2.Cu")
		(net "UART_GPS_RX_FPGA_TX")
	)
	(segment
		(start 115.1255 -78.041246)
		(end 116.078 -78.993746)
		(width 0.127)
		(layer "In2.Cu")
		(net "UART_GPS_RX_FPGA_TX")
	)
	(segment
		(start 113.3475 -65.363344)
		(end 113.2205 -65.490344)
		(width 0.127)
		(layer "In2.Cu")
		(net "UART_GPS_RX_FPGA_TX")
	)
	(segment
		(start 111.2012 -65.668144)
		(end 111.2012 -65.947544)
		(width 0.127)
		(layer "In2.Cu")
		(net "UART_GPS_RX_FPGA_TX")
	)
	(segment
		(start 113.3475 -62.2935)
		(end 113.3475 -64.093344)
		(width 0.127)
		(layer "In2.Cu")
		(net "UART_GPS_RX_FPGA_TX")
	)
	(segment
		(start 112.346994 -53.322982)
		(end 112.346994 -54.815994)
		(width 0.127)
		(layer "In2.Cu")
		(net "UART_GPS_RX_FPGA_TX")
	)
	(segment
		(start 117.856 -81.236566)
		(end 117.856 -84.284566)
		(width 0.127)
		(layer "In2.Cu")
		(net "UART_GPS_RX_FPGA_TX")
	)
	(segment
		(start 113.3475 -64.982344)
		(end 113.3475 -65.363344)
		(width 0.127)
		(layer "In2.Cu")
		(net "UART_GPS_RX_FPGA_TX")
	)
	(segment
		(start 116.078 -79.458566)
		(end 117.856 -81.236566)
		(width 0.127)
		(layer "In2.Cu")
		(net "UART_GPS_RX_FPGA_TX")
	)
	(segment
		(start 113.2205 -66.125344)
		(end 113.3475 -66.252344)
		(width 0.127)
		(layer "In2.Cu")
		(net "UART_GPS_RX_FPGA_TX")
	)
	(segment
		(start 120.185434 -86.614)
		(end 122.174 -86.614)
		(width 0.127)
		(layer "In2.Cu")
		(net "UART_GPS_RX_FPGA_TX")
	)
	(segment
		(start 111.379 -65.490344)
		(end 111.2012 -65.668144)
		(width 0.127)
		(layer "In2.Cu")
		(net "UART_GPS_RX_FPGA_TX")
	)
	(segment
		(start 111.0996 -64.855344)
		(end 113.2205 -64.855344)
		(width 0.127)
		(layer "In2.Cu")
		(net "UART_GPS_RX_FPGA_TX")
	)
	(segment
		(start 114.681 -57.15)
		(end 114.681 -60.96)
		(width 0.127)
		(layer "In2.Cu")
		(net "UART_GPS_RX_FPGA_TX")
	)
	(segment
		(start 113.3475 -64.093344)
		(end 113.2205 -64.220344)
		(width 0.127)
		(layer "In2.Cu")
		(net "UART_GPS_RX_FPGA_TX")
	)
	(segment
		(start 117.856 -84.284566)
		(end 120.185434 -86.614)
		(width 0.127)
		(layer "In2.Cu")
		(net "UART_GPS_RX_FPGA_TX")
	)
	(segment
		(start 113.2205 -64.855344)
		(end 113.3475 -64.982344)
		(width 0.127)
		(layer "In2.Cu")
		(net "UART_GPS_RX_FPGA_TX")
	)
	(segment
		(start 113.2205 -64.220344)
		(end 111.0996 -64.220344)
		(width 0.127)
		(layer "In2.Cu")
		(net "UART_GPS_RX_FPGA_TX")
	)
	(segment
		(start 114.173 -69.596)
		(end 114.173 -76.661518)
		(width 0.127)
		(layer "In2.Cu")
		(net "UART_GPS_RX_FPGA_TX")
	)
	(segment
		(start 111.379 -66.125344)
		(end 113.2205 -66.125344)
		(width 0.127)
		(layer "In2.Cu")
		(net "UART_GPS_RX_FPGA_TX")
	)
	(segment
		(start 110.9726 -64.347344)
		(end 110.9726 -64.728344)
		(width 0.127)
		(layer "In2.Cu")
		(net "UART_GPS_RX_FPGA_TX")
	)
	(segment
		(start 114.173 -76.661518)
		(end 115.1255 -77.614018)
		(width 0.127)
		(layer "In2.Cu")
		(net "UART_GPS_RX_FPGA_TX")
	)
	(segment
		(start 113.3475 -66.252344)
		(end 113.3475 -68.7705)
		(width 0.127)
		(layer "In2.Cu")
		(net "UART_GPS_RX_FPGA_TX")
	)
	(segment
		(start 89.017602 -104.6734)
		(end 89.574878 -104.6734)
		(width 0.11938)
		(layer "F.Cu")
		(net "R_XP3R3V_PG")
	)
	(segment
		(start 86.816184 -103.279702)
		(end 87.623904 -103.279702)
		(width 0.11938)
		(layer "F.Cu")
		(net "R_XP3R3V_PG")
	)
	(segment
		(start 88.611202 -104.267)
		(end 89.017602 -104.6734)
		(width 0.11938)
		(layer "F.Cu")
		(net "R_XP3R3V_PG")
	)
	(segment
		(start 87.623904 -103.279702)
		(end 88.611202 -104.267)
		(width 0.11938)
		(layer "F.Cu")
		(net "R_XP3R3V_PG")
	)
	(via
		(at 88.611202 -104.267)
		(size 0.508)
		(drill 0.254)
		(layers "F.Cu" "B.Cu")
		(net "R_XP3R3V_PG")
	)
	(segment
		(start 90.2208 -106.1212)
		(end 90.2208 -106.6038)
		(width 0.11938)
		(layer "B.Cu")
		(net "R_XP3R3V_PG")
	)
	(segment
		(start 90.297 -106.045)
		(end 90.2208 -106.1212)
		(width 0.11938)
		(layer "B.Cu")
		(net "R_XP3R3V_PG")
	)
	(segment
		(start 89.8906 -104.902)
		(end 90.297 -105.3084)
		(width 0.11938)
		(layer "B.Cu")
		(net "R_XP3R3V_PG")
	)
	(segment
		(start 88.611202 -104.267)
		(end 89.2556 -104.267)
		(width 0.11938)
		(layer "B.Cu")
		(net "R_XP3R3V_PG")
	)
	(segment
		(start 90.297 -105.3084)
		(end 90.297 -106.045)
		(width 0.11938)
		(layer "B.Cu")
		(net "R_XP3R3V_PG")
	)
	(segment
		(start 89.2556 -104.267)
		(end 89.8906 -104.902)
		(width 0.11938)
		(layer "B.Cu")
		(net "R_XP3R3V_PG")
	)
	(segment
		(start 74.5998 -82.7786)
		(end 75.2602 -82.7786)
		(width 0.11938)
		(layer "F.Cu")
		(net "R_PCA9546_I2C_SDA")
	)
	(segment
		(start 75.2602 -82.7786)
		(end 75.8698 -82.169)
		(width 0.11938)
		(layer "F.Cu")
		(net "R_PCA9546_I2C_SDA")
	)
	(segment
		(start 75.8698 -82.169)
		(end 76.276708 -82.575908)
		(width 0.11938)
		(layer "F.Cu")
		(net "R_PCA9546_I2C_SDA")
	)
	(segment
		(start 76.276708 -82.575908)
		(end 77.2795 -82.575908)
		(width 0.11938)
		(layer "F.Cu")
		(net "R_PCA9546_I2C_SDA")
	)
	(via
		(at 19.2913 -41.7068)
		(size 0.4572)
		(drill 0.2032)
		(layers "F.Cu" "B.Cu")
		(net "R_PCA9546_I2C_SDA")
	)
	(via
		(at 75.8698 -82.169)
		(size 0.4572)
		(drill 0.2032)
		(layers "F.Cu" "B.Cu")
		(net "R_PCA9546_I2C_SDA")
	)
	(segment
		(start 19.7104 -40.4876)
		(end 19.2913 -40.9067)
		(width 0.11938)
		(layer "B.Cu")
		(net "R_PCA9546_I2C_SDA")
	)
	(segment
		(start 19.2913 -41.6687)
		(end 19.2913 -41.7068)
		(width 0.11938)
		(layer "B.Cu")
		(net "R_PCA9546_I2C_SDA")
	)
	(segment
		(start 20.5232 -42.7736)
		(end 20.5232 -41.6306)
		(width 0.11938)
		(layer "B.Cu")
		(net "R_PCA9546_I2C_SDA")
	)
	(segment
		(start 18.2372 -40.6146)
		(end 19.2913 -41.6687)
		(width 0.11938)
		(layer "B.Cu")
		(net "R_PCA9546_I2C_SDA")
	)
	(segment
		(start 20.5232 -41.6306)
		(end 20.5232 -40.4876)
		(width 0.11938)
		(layer "B.Cu")
		(net "R_PCA9546_I2C_SDA")
	)
	(segment
		(start 20.5232 -40.4876)
		(end 19.7104 -40.4876)
		(width 0.11938)
		(layer "B.Cu")
		(net "R_PCA9546_I2C_SDA")
	)
	(segment
		(start 19.2913 -40.9067)
		(end 19.2913 -41.6687)
		(width 0.11938)
		(layer "B.Cu")
		(net "R_PCA9546_I2C_SDA")
	)
	(segment
		(start 70.95617 -81.34858)
		(end 71.08317 -81.22158)
		(width 0.127)
		(layer "In7.Cu")
		(net "R_PCA9546_I2C_SDA")
	)
	(segment
		(start 75.595734 -81.894934)
		(end 75.8698 -82.169)
		(width 0.127)
		(layer "In7.Cu")
		(net "R_PCA9546_I2C_SDA")
	)
	(segment
		(start 68.412614 -83.82)
		(end 70.33768 -81.894934)
		(width 0.127)
		(layer "In7.Cu")
		(net "R_PCA9546_I2C_SDA")
	)
	(segment
		(start 22.987 -45.339)
		(end 22.2885 -46.0375)
		(width 0.127)
		(layer "In7.Cu")
		(net "R_PCA9546_I2C_SDA")
	)
	(segment
		(start 25.0444 -58.547)
		(end 29.845 -63.3476)
		(width 0.127)
		(layer "In7.Cu")
		(net "R_PCA9546_I2C_SDA")
	)
	(segment
		(start 22.352 -44.069)
		(end 22.987 -44.704)
		(width 0.127)
		(layer "In7.Cu")
		(net "R_PCA9546_I2C_SDA")
	)
	(segment
		(start 73.49617 -81.767934)
		(end 73.49617 -81.20634)
		(width 0.127)
		(layer "In7.Cu")
		(net "R_PCA9546_I2C_SDA")
	)
	(segment
		(start 73.49617 -81.20634)
		(end 73.62317 -81.07934)
		(width 0.127)
		(layer "In7.Cu")
		(net "R_PCA9546_I2C_SDA")
	)
	(segment
		(start 71.59117 -81.34858)
		(end 71.59117 -81.767934)
		(width 0.127)
		(layer "In7.Cu")
		(net "R_PCA9546_I2C_SDA")
	)
	(segment
		(start 74.00417 -81.07934)
		(end 74.13117 -81.20634)
		(width 0.127)
		(layer "In7.Cu")
		(net "R_PCA9546_I2C_SDA")
	)
	(segment
		(start 71.71817 -81.894934)
		(end 72.09917 -81.894934)
		(width 0.127)
		(layer "In7.Cu")
		(net "R_PCA9546_I2C_SDA")
	)
	(segment
		(start 22.352 -43.223434)
		(end 22.352 -44.069)
		(width 0.127)
		(layer "In7.Cu")
		(net "R_PCA9546_I2C_SDA")
	)
	(segment
		(start 74.13117 -81.20634)
		(end 74.13117 -81.767934)
		(width 0.127)
		(layer "In7.Cu")
		(net "R_PCA9546_I2C_SDA")
	)
	(segment
		(start 73.36917 -81.894934)
		(end 73.49617 -81.767934)
		(width 0.127)
		(layer "In7.Cu")
		(net "R_PCA9546_I2C_SDA")
	)
	(segment
		(start 72.22617 -81.20634)
		(end 72.35317 -81.07934)
		(width 0.127)
		(layer "In7.Cu")
		(net "R_PCA9546_I2C_SDA")
	)
	(segment
		(start 23.7363 -58.42)
		(end 23.8633 -58.547)
		(width 0.127)
		(layer "In7.Cu")
		(net "R_PCA9546_I2C_SDA")
	)
	(segment
		(start 22.2885 -50.736246)
		(end 22.86 -51.307746)
		(width 0.127)
		(layer "In7.Cu")
		(net "R_PCA9546_I2C_SDA")
	)
	(segment
		(start 23.8633 -58.547)
		(end 25.0444 -58.547)
		(width 0.127)
		(layer "In7.Cu")
		(net "R_PCA9546_I2C_SDA")
	)
	(segment
		(start 22.2885 -46.0375)
		(end 22.2885 -50.736246)
		(width 0.127)
		(layer "In7.Cu")
		(net "R_PCA9546_I2C_SDA")
	)
	(segment
		(start 70.82917 -81.894934)
		(end 70.95617 -81.767934)
		(width 0.127)
		(layer "In7.Cu")
		(net "R_PCA9546_I2C_SDA")
	)
	(segment
		(start 72.98817 -81.894934)
		(end 73.36917 -81.894934)
		(width 0.127)
		(layer "In7.Cu")
		(net "R_PCA9546_I2C_SDA")
	)
	(segment
		(start 72.09917 -81.894934)
		(end 72.22617 -81.767934)
		(width 0.127)
		(layer "In7.Cu")
		(net "R_PCA9546_I2C_SDA")
	)
	(segment
		(start 22.86 -56.223408)
		(end 23.7363 -57.099708)
		(width 0.127)
		(layer "In7.Cu")
		(net "R_PCA9546_I2C_SDA")
	)
	(segment
		(start 71.08317 -81.22158)
		(end 71.46417 -81.22158)
		(width 0.127)
		(layer "In7.Cu")
		(net "R_PCA9546_I2C_SDA")
	)
	(segment
		(start 70.95617 -81.767934)
		(end 70.95617 -81.34858)
		(width 0.127)
		(layer "In7.Cu")
		(net "R_PCA9546_I2C_SDA")
	)
	(segment
		(start 74.13117 -81.767934)
		(end 74.25817 -81.894934)
		(width 0.127)
		(layer "In7.Cu")
		(net "R_PCA9546_I2C_SDA")
	)
	(segment
		(start 72.35317 -81.07934)
		(end 72.73417 -81.07934)
		(width 0.127)
		(layer "In7.Cu")
		(net "R_PCA9546_I2C_SDA")
	)
	(segment
		(start 22.86 -51.307746)
		(end 22.86 -56.223408)
		(width 0.127)
		(layer "In7.Cu")
		(net "R_PCA9546_I2C_SDA")
	)
	(segment
		(start 72.22617 -81.767934)
		(end 72.22617 -81.20634)
		(width 0.127)
		(layer "In7.Cu")
		(net "R_PCA9546_I2C_SDA")
	)
	(segment
		(start 21.038566 -41.91)
		(end 22.352 -43.223434)
		(width 0.127)
		(layer "In7.Cu")
		(net "R_PCA9546_I2C_SDA")
	)
	(segment
		(start 72.86117 -81.20634)
		(end 72.86117 -81.767934)
		(width 0.127)
		(layer "In7.Cu")
		(net "R_PCA9546_I2C_SDA")
	)
	(segment
		(start 74.25817 -81.894934)
		(end 75.595734 -81.894934)
		(width 0.127)
		(layer "In7.Cu")
		(net "R_PCA9546_I2C_SDA")
	)
	(segment
		(start 22.987 -44.704)
		(end 22.987 -45.339)
		(width 0.127)
		(layer "In7.Cu")
		(net "R_PCA9546_I2C_SDA")
	)
	(segment
		(start 62.778386 -83.82)
		(end 68.412614 -83.82)
		(width 0.127)
		(layer "In7.Cu")
		(net "R_PCA9546_I2C_SDA")
	)
	(segment
		(start 58.674 -79.715614)
		(end 62.778386 -83.82)
		(width 0.127)
		(layer "In7.Cu")
		(net "R_PCA9546_I2C_SDA")
	)
	(segment
		(start 73.62317 -81.07934)
		(end 74.00417 -81.07934)
		(width 0.127)
		(layer "In7.Cu")
		(net "R_PCA9546_I2C_SDA")
	)
	(segment
		(start 23.7363 -57.099708)
		(end 23.7363 -58.42)
		(width 0.127)
		(layer "In7.Cu")
		(net "R_PCA9546_I2C_SDA")
	)
	(segment
		(start 72.86117 -81.767934)
		(end 72.98817 -81.894934)
		(width 0.127)
		(layer "In7.Cu")
		(net "R_PCA9546_I2C_SDA")
	)
	(segment
		(start 19.2913 -41.7068)
		(end 19.4945 -41.91)
		(width 0.127)
		(layer "In7.Cu")
		(net "R_PCA9546_I2C_SDA")
	)
	(segment
		(start 19.4945 -41.91)
		(end 21.038566 -41.91)
		(width 0.127)
		(layer "In7.Cu")
		(net "R_PCA9546_I2C_SDA")
	)
	(segment
		(start 71.59117 -81.767934)
		(end 71.71817 -81.894934)
		(width 0.127)
		(layer "In7.Cu")
		(net "R_PCA9546_I2C_SDA")
	)
	(segment
		(start 71.46417 -81.22158)
		(end 71.59117 -81.34858)
		(width 0.127)
		(layer "In7.Cu")
		(net "R_PCA9546_I2C_SDA")
	)
	(segment
		(start 72.73417 -81.07934)
		(end 72.86117 -81.20634)
		(width 0.127)
		(layer "In7.Cu")
		(net "R_PCA9546_I2C_SDA")
	)
	(segment
		(start 58.674 -70.317868)
		(end 58.674 -79.715614)
		(width 0.127)
		(layer "In7.Cu")
		(net "R_PCA9546_I2C_SDA")
	)
	(segment
		(start 70.33768 -81.894934)
		(end 70.82917 -81.894934)
		(width 0.127)
		(layer "In7.Cu")
		(net "R_PCA9546_I2C_SDA")
	)
	(segment
		(start 29.845 -63.3476)
		(end 51.703732 -63.3476)
		(width 0.127)
		(layer "In7.Cu")
		(net "R_PCA9546_I2C_SDA")
	)
	(segment
		(start 51.703732 -63.3476)
		(end 58.674 -70.317868)
		(width 0.127)
		(layer "In7.Cu")
		(net "R_PCA9546_I2C_SDA")
	)
	(segment
		(start 75.8698 -83.058)
		(end 75.7682 -83.058)
		(width 0.11938)
		(layer "F.Cu")
		(net "R_PCA9546_I2C_SCL")
	)
	(segment
		(start 75.8698 -83.058)
		(end 76.037694 -83.225894)
		(width 0.11938)
		(layer "F.Cu")
		(net "R_PCA9546_I2C_SCL")
	)
	(segment
		(start 76.037694 -83.225894)
		(end 77.2795 -83.225894)
		(width 0.11938)
		(layer "F.Cu")
		(net "R_PCA9546_I2C_SCL")
	)
	(segment
		(start 75.7682 -83.058)
		(end 75.0062 -83.82)
		(width 0.11938)
		(layer "F.Cu")
		(net "R_PCA9546_I2C_SCL")
	)
	(segment
		(start 75.0062 -84.2518)
		(end 74.6252 -84.6328)
		(width 0.11938)
		(layer "F.Cu")
		(net "R_PCA9546_I2C_SCL")
	)
	(segment
		(start 75.0062 -83.82)
		(end 75.0062 -84.2518)
		(width 0.11938)
		(layer "F.Cu")
		(net "R_PCA9546_I2C_SCL")
	)
	(via
		(at 75.8698 -83.058)
		(size 0.4572)
		(drill 0.2032)
		(layers "F.Cu" "B.Cu")
		(net "R_PCA9546_I2C_SCL")
	)
	(via
		(at 19.3294 -39.2176)
		(size 0.4572)
		(drill 0.2032)
		(layers "F.Cu" "B.Cu")
		(net "R_PCA9546_I2C_SCL")
	)
	(segment
		(start 20.5232 -39.3446)
		(end 19.44878 -39.3446)
		(width 0.11938)
		(layer "B.Cu")
		(net "R_PCA9546_I2C_SCL")
	)
	(segment
		(start 18.1864 -37.973)
		(end 18.1864 -39.1922)
		(width 0.11938)
		(layer "B.Cu")
		(net "R_PCA9546_I2C_SCL")
	)
	(segment
		(start 18.1864 -39.1922)
		(end 18.2118 -39.2176)
		(width 0.11938)
		(layer "B.Cu")
		(net "R_PCA9546_I2C_SCL")
	)
	(segment
		(start 19.3294 -39.2176)
		(end 18.2118 -39.2176)
		(width 0.11938)
		(layer "B.Cu")
		(net "R_PCA9546_I2C_SCL")
	)
	(segment
		(start 19.3294 -39.22522)
		(end 19.3294 -39.2176)
		(width 0.11938)
		(layer "B.Cu")
		(net "R_PCA9546_I2C_SCL")
	)
	(segment
		(start 20.5232 -38.2016)
		(end 20.5232 -39.3446)
		(width 0.11938)
		(layer "B.Cu")
		(net "R_PCA9546_I2C_SCL")
	)
	(segment
		(start 19.44878 -39.3446)
		(end 19.3294 -39.22522)
		(width 0.11938)
		(layer "B.Cu")
		(net "R_PCA9546_I2C_SCL")
	)
	(segment
		(start 20.4216 -38.1)
		(end 20.5232 -38.2016)
		(width 0.11938)
		(layer "B.Cu")
		(net "R_PCA9546_I2C_SCL")
	)
	(segment
		(start 51.493166 -63.8556)
		(end 58.166 -70.528434)
		(width 0.127)
		(layer "In7.Cu")
		(net "R_PCA9546_I2C_SCL")
	)
	(segment
		(start 20.828 -42.418)
		(end 21.7805 -43.3705)
		(width 0.127)
		(layer "In7.Cu")
		(net "R_PCA9546_I2C_SCL")
	)
	(segment
		(start 21.209 -52.197)
		(end 22.352 -53.34)
		(width 0.127)
		(layer "In7.Cu")
		(net "R_PCA9546_I2C_SCL")
	)
	(segment
		(start 58.166 -70.528434)
		(end 58.166 -79.92618)
		(width 0.127)
		(layer "In7.Cu")
		(net "R_PCA9546_I2C_SCL")
	)
	(segment
		(start 23.2283 -58.630566)
		(end 23.652734 -59.055)
		(width 0.127)
		(layer "In7.Cu")
		(net "R_PCA9546_I2C_SCL")
	)
	(segment
		(start 62.56782 -84.328)
		(end 68.62318 -84.328)
		(width 0.127)
		(layer "In7.Cu")
		(net "R_PCA9546_I2C_SCL")
	)
	(segment
		(start 70.37959 -82.57159)
		(end 75.38339 -82.57159)
		(width 0.127)
		(layer "In7.Cu")
		(net "R_PCA9546_I2C_SCL")
	)
	(segment
		(start 19.3294 -39.2176)
		(end 19.2786 -39.2176)
		(width 0.127)
		(layer "In7.Cu")
		(net "R_PCA9546_I2C_SCL")
	)
	(segment
		(start 18.4912 -40.005)
		(end 18.4912 -41.7322)
		(width 0.127)
		(layer "In7.Cu")
		(net "R_PCA9546_I2C_SCL")
	)
	(segment
		(start 22.352 -53.34)
		(end 22.352 -56.433974)
		(width 0.127)
		(layer "In7.Cu")
		(net "R_PCA9546_I2C_SCL")
	)
	(segment
		(start 19.2786 -39.2176)
		(end 18.4912 -40.005)
		(width 0.127)
		(layer "In7.Cu")
		(net "R_PCA9546_I2C_SCL")
	)
	(segment
		(start 19.177 -42.418)
		(end 20.828 -42.418)
		(width 0.127)
		(layer "In7.Cu")
		(net "R_PCA9546_I2C_SCL")
	)
	(segment
		(start 23.2283 -57.310274)
		(end 23.2283 -58.630566)
		(width 0.127)
		(layer "In7.Cu")
		(net "R_PCA9546_I2C_SCL")
	)
	(segment
		(start 58.166 -79.92618)
		(end 62.56782 -84.328)
		(width 0.127)
		(layer "In7.Cu")
		(net "R_PCA9546_I2C_SCL")
	)
	(segment
		(start 21.7805 -43.3705)
		(end 21.7805 -50.3555)
		(width 0.127)
		(layer "In7.Cu")
		(net "R_PCA9546_I2C_SCL")
	)
	(segment
		(start 24.765 -59.055)
		(end 29.5656 -63.8556)
		(width 0.127)
		(layer "In7.Cu")
		(net "R_PCA9546_I2C_SCL")
	)
	(segment
		(start 18.4912 -41.7322)
		(end 19.177 -42.418)
		(width 0.127)
		(layer "In7.Cu")
		(net "R_PCA9546_I2C_SCL")
	)
	(segment
		(start 21.209 -50.927)
		(end 21.209 -52.197)
		(width 0.127)
		(layer "In7.Cu")
		(net "R_PCA9546_I2C_SCL")
	)
	(segment
		(start 68.62318 -84.328)
		(end 70.37959 -82.57159)
		(width 0.127)
		(layer "In7.Cu")
		(net "R_PCA9546_I2C_SCL")
	)
	(segment
		(start 21.7805 -50.3555)
		(end 21.209 -50.927)
		(width 0.127)
		(layer "In7.Cu")
		(net "R_PCA9546_I2C_SCL")
	)
	(segment
		(start 23.652734 -59.055)
		(end 24.765 -59.055)
		(width 0.127)
		(layer "In7.Cu")
		(net "R_PCA9546_I2C_SCL")
	)
	(segment
		(start 29.5656 -63.8556)
		(end 51.493166 -63.8556)
		(width 0.127)
		(layer "In7.Cu")
		(net "R_PCA9546_I2C_SCL")
	)
	(segment
		(start 75.38339 -82.57159)
		(end 75.8698 -83.058)
		(width 0.127)
		(layer "In7.Cu")
		(net "R_PCA9546_I2C_SCL")
	)
	(segment
		(start 22.352 -56.433974)
		(end 23.2283 -57.310274)
		(width 0.127)
		(layer "In7.Cu")
		(net "R_PCA9546_I2C_SCL")
	)
	(segment
		(start 114.847116 -45.823124)
		(end 115.346988 -46.322996)
		(width 0.11938)
		(layer "F.Cu")
		(net "R_FPGA_TDO")
	)
	(via
		(at 121.728484 -45.329856)
		(size 0.508)
		(drill 0.254)
		(layers "F.Cu" "B.Cu")
		(net "R_FPGA_TDO")
	)
	(via
		(at 115.346988 -46.322996)
		(size 0.4572)
		(drill 0.2032)
		(layers "F.Cu" "B.Cu")
		(net "R_FPGA_TDO")
	)
	(segment
		(start 123.409456 -45.329856)
		(end 124.0536 -45.974)
		(width 0.11938)
		(layer "B.Cu")
		(net "R_FPGA_TDO")
	)
	(segment
		(start 121.728484 -45.329856)
		(end 123.409456 -45.329856)
		(width 0.11938)
		(layer "B.Cu")
		(net "R_FPGA_TDO")
	)
	(segment
		(start 117.31498 -44.704)
		(end 116.87302 -45.14596)
		(width 0.127)
		(layer "In7.Cu")
		(net "R_FPGA_TDO")
	)
	(segment
		(start 120.946672 -45.329856)
		(end 120.320816 -44.704)
		(width 0.127)
		(layer "In7.Cu")
		(net "R_FPGA_TDO")
	)
	(segment
		(start 116.54536 -45.81906)
		(end 115.850924 -45.81906)
		(width 0.127)
		(layer "In7.Cu")
		(net "R_FPGA_TDO")
	)
	(segment
		(start 120.320816 -44.704)
		(end 117.31498 -44.704)
		(width 0.127)
		(layer "In7.Cu")
		(net "R_FPGA_TDO")
	)
	(segment
		(start 116.87302 -45.14596)
		(end 116.87302 -45.4914)
		(width 0.127)
		(layer "In7.Cu")
		(net "R_FPGA_TDO")
	)
	(segment
		(start 116.87302 -45.4914)
		(end 116.54536 -45.81906)
		(width 0.127)
		(layer "In7.Cu")
		(net "R_FPGA_TDO")
	)
	(segment
		(start 115.850924 -45.81906)
		(end 115.346988 -46.322996)
		(width 0.127)
		(layer "In7.Cu")
		(net "R_FPGA_TDO")
	)
	(segment
		(start 121.728484 -45.329856)
		(end 120.946672 -45.329856)
		(width 0.127)
		(layer "In7.Cu")
		(net "R_FPGA_TDO")
	)
	(segment
		(start 114.847116 -54.823106)
		(end 115.346988 -55.322978)
		(width 0.11938)
		(layer "F.Cu")
		(net "PUDC")
	)
	(via
		(at 115.346988 -55.322978)
		(size 0.4572)
		(drill 0.2032)
		(layers "F.Cu" "B.Cu")
		(net "PUDC")
	)
	(segment
		(start 115.346988 -55.322978)
		(end 115.346988 -56.972708)
		(width 0.11938)
		(layer "B.Cu")
		(net "PUDC")
	)
	(segment
		(start 115.346988 -60.584588)
		(end 116.205 -61.4426)
		(width 0.11938)
		(layer "B.Cu")
		(net "PUDC")
	)
	(segment
		(start 117.348 -61.4426)
		(end 116.205 -61.4426)
		(width 0.11938)
		(layer "B.Cu")
		(net "PUDC")
	)
	(segment
		(start 115.346988 -58.3438)
		(end 115.346988 -60.584588)
		(width 0.11938)
		(layer "B.Cu")
		(net "PUDC")
	)
	(segment
		(start 115.2144 -58.211212)
		(end 115.346988 -58.3438)
		(width 0.11938)
		(layer "B.Cu")
		(net "PUDC")
	)
	(segment
		(start 115.2144 -57.105296)
		(end 115.2144 -58.211212)
		(width 0.11938)
		(layer "B.Cu")
		(net "PUDC")
	)
	(segment
		(start 115.346988 -56.972708)
		(end 115.2144 -57.105296)
		(width 0.11938)
		(layer "B.Cu")
		(net "PUDC")
	)
	(segment
		(start 39.9542 -18.90014)
		(end 39.9542 -18.542)
		(width 0.11938)
		(layer "F.Cu")
		(net "PCIE_SMDAT")
	)
	(segment
		(start 40.54602 -16.256)
		(end 42.21988 -16.256)
		(width 0.11938)
		(layer "F.Cu")
		(net "PCIE_SMDAT")
	)
	(segment
		(start 37.38118 -17.91462)
		(end 37.50056 -17.79524)
		(width 0.11938)
		(layer "F.Cu")
		(net "PCIE_SMDAT")
	)
	(segment
		(start 40.1574 -17.79524)
		(end 40.42664 -17.526)
		(width 0.11938)
		(layer "F.Cu")
		(net "PCIE_SMDAT")
	)
	(segment
		(start 39.755826 -19.098514)
		(end 39.9542 -18.90014)
		(width 0.11938)
		(layer "F.Cu")
		(net "PCIE_SMDAT")
	)
	(segment
		(start 39.9542 -18.542)
		(end 39.83482 -18.42262)
		(width 0.11938)
		(layer "F.Cu")
		(net "PCIE_SMDAT")
	)
	(segment
		(start 37.38118 -18.30324)
		(end 37.38118 -17.91462)
		(width 0.11938)
		(layer "F.Cu")
		(net "PCIE_SMDAT")
	)
	(segment
		(start 39.83482 -18.42262)
		(end 37.50056 -18.42262)
		(width 0.11938)
		(layer "F.Cu")
		(net "PCIE_SMDAT")
	)
	(segment
		(start 38.4048 -19.098514)
		(end 39.755826 -19.098514)
		(width 0.11938)
		(layer "F.Cu")
		(net "PCIE_SMDAT")
	)
	(segment
		(start 37.50056 -18.42262)
		(end 37.38118 -18.30324)
		(width 0.11938)
		(layer "F.Cu")
		(net "PCIE_SMDAT")
	)
	(segment
		(start 40.42664 -17.526)
		(end 40.42664 -16.37538)
		(width 0.11938)
		(layer "F.Cu")
		(net "PCIE_SMDAT")
	)
	(segment
		(start 40.42664 -16.37538)
		(end 40.54602 -16.256)
		(width 0.11938)
		(layer "F.Cu")
		(net "PCIE_SMDAT")
	)
	(segment
		(start 37.50056 -17.79524)
		(end 40.1574 -17.79524)
		(width 0.11938)
		(layer "F.Cu")
		(net "PCIE_SMDAT")
	)
	(via
		(at 38.4048 -19.098514)
		(size 0.508)
		(drill 0.254)
		(layers "F.Cu" "B.Cu")
		(net "PCIE_SMDAT")
	)
	(via
		(at 24.257 -36.957)
		(size 0.508)
		(drill 0.254)
		(layers "F.Cu" "B.Cu")
		(net "PCIE_SMDAT")
	)
	(segment
		(start 23.368 -38.227)
		(end 23.368 -37.846)
		(width 0.11938)
		(layer "B.Cu")
		(net "PCIE_SMDAT")
	)
	(segment
		(start 23.368 -37.846)
		(end 24.257 -36.957)
		(width 0.11938)
		(layer "B.Cu")
		(net "PCIE_SMDAT")
	)
	(segment
		(start 23.1394 -38.4556)
		(end 23.368 -38.227)
		(width 0.11938)
		(layer "B.Cu")
		(net "PCIE_SMDAT")
	)
	(segment
		(start 22.455886 -40.4876)
		(end 23.1394 -39.804086)
		(width 0.11938)
		(layer "B.Cu")
		(net "PCIE_SMDAT")
	)
	(segment
		(start 36.88969 -17.321276)
		(end 36.88969 -17.583404)
		(width 0.11938)
		(layer "B.Cu")
		(net "PCIE_SMDAT")
	)
	(segment
		(start 36.88969 -17.583404)
		(end 38.4048 -19.098514)
		(width 0.11938)
		(layer "B.Cu")
		(net "PCIE_SMDAT")
	)
	(segment
		(start 23.1394 -39.804086)
		(end 23.1394 -38.4556)
		(width 0.11938)
		(layer "B.Cu")
		(net "PCIE_SMDAT")
	)
	(segment
		(start 36.281614 -16.7132)
		(end 36.88969 -17.321276)
		(width 0.11938)
		(layer "B.Cu")
		(net "PCIE_SMDAT")
	)
	(segment
		(start 34.3027 -16.7132)
		(end 36.281614 -16.7132)
		(width 0.11938)
		(layer "B.Cu")
		(net "PCIE_SMDAT")
	)
	(segment
		(start 21.59 -40.4876)
		(end 22.455886 -40.4876)
		(width 0.11938)
		(layer "B.Cu")
		(net "PCIE_SMDAT")
	)
	(segment
		(start 27.813 -34.289746)
		(end 25.145746 -36.957)
		(width 0.127)
		(layer "In7.Cu")
		(net "PCIE_SMDAT")
	)
	(segment
		(start 32.9311 -21.844)
		(end 27.813 -26.9621)
		(width 0.127)
		(layer "In7.Cu")
		(net "PCIE_SMDAT")
	)
	(segment
		(start 36.1569 -21.844)
		(end 32.9311 -21.844)
		(width 0.127)
		(layer "In7.Cu")
		(net "PCIE_SMDAT")
	)
	(segment
		(start 25.145746 -36.957)
		(end 24.257 -36.957)
		(width 0.127)
		(layer "In7.Cu")
		(net "PCIE_SMDAT")
	)
	(segment
		(start 27.813 -26.9621)
		(end 27.813 -34.289746)
		(width 0.127)
		(layer "In7.Cu")
		(net "PCIE_SMDAT")
	)
	(segment
		(start 38.4048 -19.5961)
		(end 36.1569 -21.844)
		(width 0.127)
		(layer "In7.Cu")
		(net "PCIE_SMDAT")
	)
	(segment
		(start 38.4048 -19.098514)
		(end 38.4048 -19.5961)
		(width 0.127)
		(layer "In7.Cu")
		(net "PCIE_SMDAT")
	)
	(segment
		(start 45.95114 -16.10106)
		(end 46.10608 -16.256)
		(width 0.11938)
		(layer "F.Cu")
		(net "PCIE_SMCLK")
	)
	(segment
		(start 45.01896 -17.03324)
		(end 45.95114 -16.10106)
		(width 0.11938)
		(layer "F.Cu")
		(net "PCIE_SMCLK")
	)
	(segment
		(start 43.24096 -19.7612)
		(end 45.01896 -17.9832)
		(width 0.11938)
		(layer "F.Cu")
		(net "PCIE_SMCLK")
	)
	(segment
		(start 37.0586 -19.1008)
		(end 37.719 -19.7612)
		(width 0.11938)
		(layer "F.Cu")
		(net "PCIE_SMCLK")
	)
	(segment
		(start 37.719 -19.7612)
		(end 43.24096 -19.7612)
		(width 0.11938)
		(layer "F.Cu")
		(net "PCIE_SMCLK")
	)
	(segment
		(start 46.10608 -16.256)
		(end 47.83328 -16.256)
		(width 0.11938)
		(layer "F.Cu")
		(net "PCIE_SMCLK")
	)
	(segment
		(start 45.01896 -17.9832)
		(end 45.01896 -17.03324)
		(width 0.11938)
		(layer "F.Cu")
		(net "PCIE_SMCLK")
	)
	(via
		(at 22.987 -36.703)
		(size 0.508)
		(drill 0.254)
		(layers "F.Cu" "B.Cu")
		(net "PCIE_SMCLK")
	)
	(via
		(at 37.0586 -19.1008)
		(size 0.4572)
		(drill 0.2032)
		(layers "F.Cu" "B.Cu")
		(net "PCIE_SMCLK")
	)
	(via
		(at 45.95114 -16.10106)
		(size 0.4572)
		(drill 0.2032)
		(layers "F.Cu" "B.Cu")
		(net "PCIE_SMCLK")
	)
	(segment
		(start 34.30778 -17.4752)
		(end 34.30778 -17.9832)
		(width 0.11938)
		(layer "B.Cu")
		(net "PCIE_SMCLK")
	)
	(segment
		(start 36.54044 -18.79854)
		(end 36.40328 -18.9357)
		(width 0.11938)
		(layer "B.Cu")
		(net "PCIE_SMCLK")
	)
	(segment
		(start 22.733 -36.957)
		(end 22.01799 -36.957)
		(width 0.11938)
		(layer "B.Cu")
		(net "PCIE_SMCLK")
	)
	(segment
		(start 22.987 -36.703)
		(end 22.733 -36.957)
		(width 0.11938)
		(layer "B.Cu")
		(net "PCIE_SMCLK")
	)
	(segment
		(start 34.42716 -17.35582)
		(end 34.30778 -17.4752)
		(width 0.11938)
		(layer "B.Cu")
		(net "PCIE_SMCLK")
	)
	(segment
		(start 37.16528 -18.6563)
		(end 37.0459 -18.53692)
		(width 0.11938)
		(layer "B.Cu")
		(net "PCIE_SMCLK")
	)
	(segment
		(start 35.84702 -18.9357)
		(end 35.72256 -18.81124)
		(width 0.11938)
		(layer "B.Cu")
		(net "PCIE_SMCLK")
	)
	(segment
		(start 22.01799 -36.957)
		(end 21.4884 -37.48659)
		(width 0.11938)
		(layer "B.Cu")
		(net "PCIE_SMCLK")
	)
	(segment
		(start 36.40328 -18.9357)
		(end 35.84702 -18.9357)
		(width 0.11938)
		(layer "B.Cu")
		(net "PCIE_SMCLK")
	)
	(segment
		(start 37.16528 -18.99412)
		(end 37.16528 -18.6563)
		(width 0.11938)
		(layer "B.Cu")
		(net "PCIE_SMCLK")
	)
	(segment
		(start 37.0586 -19.1008)
		(end 37.16528 -18.99412)
		(width 0.11938)
		(layer "B.Cu")
		(net "PCIE_SMCLK")
	)
	(segment
		(start 36.65982 -18.53692)
		(end 36.54044 -18.6563)
		(width 0.11938)
		(layer "B.Cu")
		(net "PCIE_SMCLK")
	)
	(segment
		(start 21.4884 -37.48659)
		(end 21.4884 -38.1)
		(width 0.11938)
		(layer "B.Cu")
		(net "PCIE_SMCLK")
	)
	(segment
		(start 35.21456 -17.9832)
		(end 35.21456 -17.65554)
		(width 0.11938)
		(layer "B.Cu")
		(net "PCIE_SMCLK")
	)
	(segment
		(start 36.54044 -18.6563)
		(end 36.54044 -18.79854)
		(width 0.11938)
		(layer "B.Cu")
		(net "PCIE_SMCLK")
	)
	(segment
		(start 35.72256 -18.4912)
		(end 35.21456 -17.9832)
		(width 0.11938)
		(layer "B.Cu")
		(net "PCIE_SMCLK")
	)
	(segment
		(start 34.91484 -17.35582)
		(end 34.42716 -17.35582)
		(width 0.11938)
		(layer "B.Cu")
		(net "PCIE_SMCLK")
	)
	(segment
		(start 37.0459 -18.53692)
		(end 36.65982 -18.53692)
		(width 0.11938)
		(layer "B.Cu")
		(net "PCIE_SMCLK")
	)
	(segment
		(start 35.21456 -17.65554)
		(end 34.91484 -17.35582)
		(width 0.11938)
		(layer "B.Cu")
		(net "PCIE_SMCLK")
	)
	(segment
		(start 35.72256 -18.81124)
		(end 35.72256 -18.4912)
		(width 0.11938)
		(layer "B.Cu")
		(net "PCIE_SMCLK")
	)
	(segment
		(start 35.5092 -21.336)
		(end 31.8008 -21.336)
		(width 0.127)
		(layer "In7.Cu")
		(net "PCIE_SMCLK")
	)
	(segment
		(start 37.0586 -19.1008)
		(end 37.0586 -19.7866)
		(width 0.127)
		(layer "In7.Cu")
		(net "PCIE_SMCLK")
	)
	(segment
		(start 25.019254 -36.195)
		(end 23.495 -36.195)
		(width 0.127)
		(layer "In7.Cu")
		(net "PCIE_SMCLK")
	)
	(segment
		(start 31.8008 -21.336)
		(end 27.178 -25.9588)
		(width 0.127)
		(layer "In7.Cu")
		(net "PCIE_SMCLK")
	)
	(segment
		(start 23.495 -36.195)
		(end 22.987 -36.703)
		(width 0.127)
		(layer "In7.Cu")
		(net "PCIE_SMCLK")
	)
	(segment
		(start 37.0586 -19.7866)
		(end 35.5092 -21.336)
		(width 0.127)
		(layer "In7.Cu")
		(net "PCIE_SMCLK")
	)
	(segment
		(start 27.178 -34.036254)
		(end 25.019254 -36.195)
		(width 0.127)
		(layer "In7.Cu")
		(net "PCIE_SMCLK")
	)
	(segment
		(start 27.178 -25.9588)
		(end 27.178 -34.036254)
		(width 0.127)
		(layer "In7.Cu")
		(net "PCIE_SMCLK")
	)
	(segment
		(start 103.847138 -42.82313)
		(end 103.347266 -42.323258)
		(width 0.09906)
		(layer "F.Cu")
		(net "PCIE_REFCLKP")
	)
	(via
		(at 103.347266 -42.323258)
		(size 0.4572)
		(drill 0.2032)
		(layers "F.Cu" "B.Cu")
		(net "PCIE_REFCLKP")
	)
	(segment
		(start 60.682632 -18.32356)
		(end 60.44184 -18.32356)
		(width 0.09906)
		(layer "B.Cu")
		(net "PCIE_REFCLKP")
	)
	(segment
		(start 61.089032 -18.5674)
		(end 60.960254 -18.438622)
		(width 0.09906)
		(layer "B.Cu")
		(net "PCIE_REFCLKP")
	)
	(segment
		(start 59.9948 -17.87652)
		(end 59.9948 -16.89608)
		(width 0.09906)
		(layer "B.Cu")
		(net "PCIE_REFCLKP")
	)
	(segment
		(start 103.847138 -42.82313)
		(end 103.347266 -42.323258)
		(width 0.09906)
		(layer "B.Cu")
		(net "PCIE_REFCLKP")
	)
	(segment
		(start 59.9948 -16.89608)
		(end 59.995562 -16.586708)
		(width 0.09906)
		(layer "B.Cu")
		(net "PCIE_REFCLKP")
	)
	(segment
		(start 59.85129 -16.235934)
		(end 59.51474 -15.89786)
		(width 0.09906)
		(layer "B.Cu")
		(net "PCIE_REFCLKP")
	)
	(arc
		(start 60.960254 -18.438622)
		(mid 60.832894 -18.35346)
		(end 60.682632 -18.32356)
		(width 0.09906)
		(layer "B.Cu")
		(net "PCIE_REFCLKP")
	)
	(arc
		(start 59.995562 -16.586708)
		(mid 59.958324 -16.396965)
		(end 59.85129 -16.235934)
		(width 0.09906)
		(layer "B.Cu")
		(net "PCIE_REFCLKP")
	)
	(arc
		(start 60.44184 -18.32356)
		(mid 60.125735 -18.192625)
		(end 59.9948 -17.87652)
		(width 0.09906)
		(layer "B.Cu")
		(net "PCIE_REFCLKP")
	)
	(segment
		(start 97.7646 -41.664128)
		(end 97.742502 -41.664128)
		(width 0.0889)
		(layer "In7.Cu")
		(net "PCIE_REFCLKP")
	)
	(segment
		(start 60.2742 -28.28671)
		(end 60.2742 -21.832062)
		(width 0.11684)
		(layer "In7.Cu")
		(net "PCIE_REFCLKP")
	)
	(segment
		(start 70.406768 -38.529768)
		(end 60.352432 -28.475432)
		(width 0.11684)
		(layer "In7.Cu")
		(net "PCIE_REFCLKP")
	)
	(segment
		(start 60.47105 -18.31975)
		(end 60.677806 -18.31975)
		(width 0.11684)
		(layer "In7.Cu")
		(net "PCIE_REFCLKP")
	)
	(segment
		(start 60.956952 -18.43532)
		(end 61.089032 -18.5674)
		(width 0.11684)
		(layer "In7.Cu")
		(net "PCIE_REFCLKP")
	)
	(segment
		(start 102.99319 -42.284904)
		(end 102.980998 -42.272712)
		(width 0.0889)
		(layer "In7.Cu")
		(net "PCIE_REFCLKP")
	)
	(segment
		(start 102.561644 -41.727628)
		(end 97.8281 -41.727628)
		(width 0.0889)
		(layer "In7.Cu")
		(net "PCIE_REFCLKP")
	)
	(segment
		(start 60.47486 -21.631402)
		(end 60.47486 -21.407882)
		(width 0.11684)
		(layer "In7.Cu")
		(net "PCIE_REFCLKP")
	)
	(segment
		(start 103.347266 -42.323258)
		(end 103.085646 -42.323258)
		(width 0.0889)
		(layer "In7.Cu")
		(net "PCIE_REFCLKP")
	)
	(segment
		(start 83.14563 -40.86225)
		(end 81.028286 -38.744906)
		(width 0.11684)
		(layer "In7.Cu")
		(net "PCIE_REFCLKP")
	)
	(segment
		(start 80.697832 -38.608)
		(end 70.59549 -38.608)
		(width 0.11684)
		(layer "In7.Cu")
		(net "PCIE_REFCLKP")
	)
	(segment
		(start 60.2742 -21.207222)
		(end 60.2742 -18.5166)
		(width 0.11684)
		(layer "In7.Cu")
		(net "PCIE_REFCLKP")
	)
	(segment
		(start 97.742502 -41.664128)
		(end 85.081618 -41.664128)
		(width 0.11684)
		(layer "In7.Cu")
		(net "PCIE_REFCLKP")
	)
	(segment
		(start 97.8281 -41.727628)
		(end 97.7646 -41.664128)
		(width 0.0889)
		(layer "In7.Cu")
		(net "PCIE_REFCLKP")
	)
	(segment
		(start 102.942644 -42.180256)
		(end 102.942644 -42.108628)
		(width 0.0889)
		(layer "In7.Cu")
		(net "PCIE_REFCLKP")
	)
	(arc
		(start 60.352432 -28.475432)
		(mid 60.294523 -28.38886)
		(end 60.2742 -28.28671)
		(width 0.11684)
		(layer "In7.Cu")
		(net "PCIE_REFCLKP")
	)
	(arc
		(start 85.081618 -41.664128)
		(mid 84.033882 -41.45572)
		(end 83.14563 -40.86225)
		(width 0.11684)
		(layer "In7.Cu")
		(net "PCIE_REFCLKP")
	)
	(arc
		(start 70.59549 -38.608)
		(mid 70.493345 -38.587664)
		(end 70.406768 -38.529768)
		(width 0.11684)
		(layer "In7.Cu")
		(net "PCIE_REFCLKP")
	)
	(arc
		(start 102.980998 -42.272712)
		(mid 102.952601 -42.230307)
		(end 102.942644 -42.180256)
		(width 0.0889)
		(layer "In7.Cu")
		(net "PCIE_REFCLKP")
	)
	(arc
		(start 60.2742 -21.832062)
		(mid 60.297262 -21.776384)
		(end 60.35294 -21.753322)
		(width 0.11684)
		(layer "In7.Cu")
		(net "PCIE_REFCLKP")
	)
	(arc
		(start 81.028286 -38.744906)
		(mid 80.876699 -38.643552)
		(end 80.697832 -38.608)
		(width 0.11684)
		(layer "In7.Cu")
		(net "PCIE_REFCLKP")
	)
	(arc
		(start 60.47486 -21.407882)
		(mid 60.43915 -21.321672)
		(end 60.35294 -21.285962)
		(width 0.11684)
		(layer "In7.Cu")
		(net "PCIE_REFCLKP")
	)
	(arc
		(start 60.677806 -18.31975)
		(mid 60.828872 -18.349781)
		(end 60.956952 -18.43532)
		(width 0.11684)
		(layer "In7.Cu")
		(net "PCIE_REFCLKP")
	)
	(arc
		(start 60.35294 -21.285962)
		(mid 60.297262 -21.2629)
		(end 60.2742 -21.207222)
		(width 0.11684)
		(layer "In7.Cu")
		(net "PCIE_REFCLKP")
	)
	(arc
		(start 60.2742 -18.5166)
		(mid 60.331856 -18.377406)
		(end 60.47105 -18.31975)
		(width 0.11684)
		(layer "In7.Cu")
		(net "PCIE_REFCLKP")
	)
	(arc
		(start 102.942644 -42.108628)
		(mid 102.831052 -41.83922)
		(end 102.561644 -41.727628)
		(width 0.0889)
		(layer "In7.Cu")
		(net "PCIE_REFCLKP")
	)
	(arc
		(start 103.085646 -42.323258)
		(mid 103.035601 -42.313286)
		(end 102.99319 -42.284904)
		(width 0.0889)
		(layer "In7.Cu")
		(net "PCIE_REFCLKP")
	)
	(arc
		(start 60.35294 -21.753322)
		(mid 60.43915 -21.717612)
		(end 60.47486 -21.631402)
		(width 0.11684)
		(layer "In7.Cu")
		(net "PCIE_REFCLKP")
	)
	(segment
		(start 102.84714 -42.82313)
		(end 102.347268 -42.323258)
		(width 0.09906)
		(layer "F.Cu")
		(net "PCIE_REFCLKN")
	)
	(via
		(at 102.347268 -42.323258)
		(size 0.4572)
		(drill 0.2032)
		(layers "F.Cu" "B.Cu")
		(net "PCIE_REFCLKN")
	)
	(segment
		(start 60.950094 -17.893538)
		(end 61.089032 -17.7546)
		(width 0.09906)
		(layer "B.Cu")
		(net "PCIE_REFCLKN")
	)
	(segment
		(start 60.2996 -16.896588)
		(end 60.2996 -17.87652)
		(width 0.09906)
		(layer "B.Cu")
		(net "PCIE_REFCLKN")
	)
	(segment
		(start 60.784994 -15.9004)
		(end 60.446412 -16.237458)
		(width 0.09906)
		(layer "B.Cu")
		(net "PCIE_REFCLKN")
	)
	(segment
		(start 60.300616 -16.586962)
		(end 60.2996 -16.896588)
		(width 0.09906)
		(layer "B.Cu")
		(net "PCIE_REFCLKN")
	)
	(segment
		(start 102.347268 -42.323258)
		(end 102.846886 -42.822876)
		(width 0.09906)
		(layer "B.Cu")
		(net "PCIE_REFCLKN")
	)
	(segment
		(start 60.44184 -18.01876)
		(end 60.647834 -18.01876)
		(width 0.09906)
		(layer "B.Cu")
		(net "PCIE_REFCLKN")
	)
	(segment
		(start 102.846886 -42.822876)
		(end 102.846886 -42.82313)
		(width 0.09906)
		(layer "B.Cu")
		(net "PCIE_REFCLKN")
	)
	(arc
		(start 60.446412 -16.237458)
		(mid 60.338799 -16.397723)
		(end 60.300616 -16.586962)
		(width 0.09906)
		(layer "B.Cu")
		(net "PCIE_REFCLKN")
	)
	(arc
		(start 60.647834 -18.01876)
		(mid 60.811424 -17.98622)
		(end 60.950094 -17.893538)
		(width 0.09906)
		(layer "B.Cu")
		(net "PCIE_REFCLKN")
	)
	(arc
		(start 60.2996 -17.87652)
		(mid 60.341261 -17.977099)
		(end 60.44184 -18.01876)
		(width 0.09906)
		(layer "B.Cu")
		(net "PCIE_REFCLKN")
	)
	(segment
		(start 102.347268 -42.323258)
		(end 102.609142 -42.323258)
		(width 0.0889)
		(layer "In7.Cu")
		(net "PCIE_REFCLKN")
	)
	(segment
		(start 59.9567 -28.28671)
		(end 59.9567 -18.5166)
		(width 0.11684)
		(layer "In7.Cu")
		(net "PCIE_REFCLKN")
	)
	(segment
		(start 102.752144 -42.180256)
		(end 102.752144 -42.108628)
		(width 0.0889)
		(layer "In7.Cu")
		(net "PCIE_REFCLKN")
	)
	(segment
		(start 97.742502 -41.981628)
		(end 85.081618 -41.981628)
		(width 0.11684)
		(layer "In7.Cu")
		(net "PCIE_REFCLKN")
	)
	(segment
		(start 60.47105 -18.00225)
		(end 60.677806 -18.00225)
		(width 0.11684)
		(layer "In7.Cu")
		(net "PCIE_REFCLKN")
	)
	(segment
		(start 102.701598 -42.284904)
		(end 102.71379 -42.272712)
		(width 0.0889)
		(layer "In7.Cu")
		(net "PCIE_REFCLKN")
	)
	(segment
		(start 80.698086 -38.9255)
		(end 70.59549 -38.9255)
		(width 0.11684)
		(layer "In7.Cu")
		(net "PCIE_REFCLKN")
	)
	(segment
		(start 70.182232 -38.754304)
		(end 60.127896 -28.699968)
		(width 0.11684)
		(layer "In7.Cu")
		(net "PCIE_REFCLKN")
	)
	(segment
		(start 97.8281 -41.918128)
		(end 97.7646 -41.981628)
		(width 0.0889)
		(layer "In7.Cu")
		(net "PCIE_REFCLKN")
	)
	(segment
		(start 102.561644 -41.918128)
		(end 97.8281 -41.918128)
		(width 0.0889)
		(layer "In7.Cu")
		(net "PCIE_REFCLKN")
	)
	(segment
		(start 97.7646 -41.981628)
		(end 97.742502 -41.981628)
		(width 0.0889)
		(layer "In7.Cu")
		(net "PCIE_REFCLKN")
	)
	(segment
		(start 60.956952 -17.88668)
		(end 61.089032 -17.7546)
		(width 0.11684)
		(layer "In7.Cu")
		(net "PCIE_REFCLKN")
	)
	(segment
		(start 82.921094 -41.086786)
		(end 80.803496 -38.969188)
		(width 0.11684)
		(layer "In7.Cu")
		(net "PCIE_REFCLKN")
	)
	(arc
		(start 60.677806 -18.00225)
		(mid 60.828872 -17.972219)
		(end 60.956952 -17.88668)
		(width 0.11684)
		(layer "In7.Cu")
		(net "PCIE_REFCLKN")
	)
	(arc
		(start 102.609142 -42.323258)
		(mid 102.659187 -42.313286)
		(end 102.701598 -42.284904)
		(width 0.0889)
		(layer "In7.Cu")
		(net "PCIE_REFCLKN")
	)
	(arc
		(start 102.71379 -42.272712)
		(mid 102.742187 -42.230307)
		(end 102.752144 -42.180256)
		(width 0.0889)
		(layer "In7.Cu")
		(net "PCIE_REFCLKN")
	)
	(arc
		(start 59.9567 -18.5166)
		(mid 60.10735 -18.1529)
		(end 60.47105 -18.00225)
		(width 0.11684)
		(layer "In7.Cu")
		(net "PCIE_REFCLKN")
	)
	(arc
		(start 70.59549 -38.9255)
		(mid 70.371829 -38.881011)
		(end 70.182232 -38.754304)
		(width 0.11684)
		(layer "In7.Cu")
		(net "PCIE_REFCLKN")
	)
	(arc
		(start 102.752144 -42.108628)
		(mid 102.696348 -41.973924)
		(end 102.561644 -41.918128)
		(width 0.0889)
		(layer "In7.Cu")
		(net "PCIE_REFCLKN")
	)
	(arc
		(start 60.127896 -28.699968)
		(mid 60.001206 -28.510364)
		(end 59.9567 -28.28671)
		(width 0.11684)
		(layer "In7.Cu")
		(net "PCIE_REFCLKN")
	)
	(arc
		(start 80.803496 -38.969188)
		(mid 80.755148 -38.936819)
		(end 80.698086 -38.9255)
		(width 0.11684)
		(layer "In7.Cu")
		(net "PCIE_REFCLKN")
	)
	(arc
		(start 85.081618 -41.981628)
		(mid 83.912366 -41.749067)
		(end 82.921094 -41.086786)
		(width 0.11684)
		(layer "In7.Cu")
		(net "PCIE_REFCLKN")
	)
	(segment
		(start 111.752888 -24.249888)
		(end 112.2172 -24.7142)
		(width 0.09906)
		(layer "F.Cu")
		(net "OSC_200M_CLKP")
	)
	(segment
		(start 112.080548 -23.174452)
		(end 111.747046 -23.507954)
		(width 0.09906)
		(layer "F.Cu")
		(net "OSC_200M_CLKP")
	)
	(segment
		(start 111.6965 -25.35809)
		(end 111.6965 -25.563068)
		(width 0.09906)
		(layer "F.Cu")
		(net "OSC_200M_CLKP")
	)
	(segment
		(start 111.841788 -25.913588)
		(end 112.1156 -26.1874)
		(width 0.09906)
		(layer "F.Cu")
		(net "OSC_200M_CLKP")
	)
	(segment
		(start 111.64062 -23.764748)
		(end 111.64062 -23.97887)
		(width 0.09906)
		(layer "F.Cu")
		(net "OSC_200M_CLKP")
	)
	(segment
		(start 112.1156 -23.021036)
		(end 112.1156 -23.090124)
		(width 0.09906)
		(layer "F.Cu")
		(net "OSC_200M_CLKP")
	)
	(segment
		(start 112.2172 -24.7142)
		(end 111.783622 -25.147778)
		(width 0.09906)
		(layer "F.Cu")
		(net "OSC_200M_CLKP")
	)
	(arc
		(start 111.6965 -25.563068)
		(mid 111.734256 -25.752791)
		(end 111.841788 -25.913588)
		(width 0.09906)
		(layer "F.Cu")
		(net "OSC_200M_CLKP")
	)
	(arc
		(start 111.783622 -25.147778)
		(mid 111.719148 -25.24427)
		(end 111.6965 -25.35809)
		(width 0.09906)
		(layer "F.Cu")
		(net "OSC_200M_CLKP")
	)
	(arc
		(start 112.1156 -23.090124)
		(mid 112.10643 -23.135755)
		(end 112.080548 -23.174452)
		(width 0.09906)
		(layer "F.Cu")
		(net "OSC_200M_CLKP")
	)
	(arc
		(start 111.64062 -23.97887)
		(mid 111.669796 -24.125547)
		(end 111.752888 -24.249888)
		(width 0.09906)
		(layer "F.Cu")
		(net "OSC_200M_CLKP")
	)
	(arc
		(start 111.747046 -23.507954)
		(mid 111.668322 -23.625772)
		(end 111.64062 -23.764748)
		(width 0.09906)
		(layer "F.Cu")
		(net "OSC_200M_CLKP")
	)
	(segment
		(start 111.3917 -25.465532)
		(end 111.3917 -25.563068)
		(width 0.09906)
		(layer "F.Cu")
		(net "OSC_200M_CLKN")
	)
	(segment
		(start 111.33582 -23.764494)
		(end 111.33582 -24.160734)
		(width 0.09906)
		(layer "F.Cu")
		(net "OSC_200M_CLKN")
	)
	(segment
		(start 110.8456 -24.7142)
		(end 111.246412 -25.115012)
		(width 0.09906)
		(layer "F.Cu")
		(net "OSC_200M_CLKN")
	)
	(segment
		(start 111.246412 -25.913588)
		(end 110.9726 -26.1874)
		(width 0.09906)
		(layer "F.Cu")
		(net "OSC_200M_CLKN")
	)
	(segment
		(start 110.907576 -23.277576)
		(end 111.233712 -23.603712)
		(width 0.09906)
		(layer "F.Cu")
		(net "OSC_200M_CLKN")
	)
	(segment
		(start 110.8456 -23.021036)
		(end 110.8456 -23.128224)
		(width 0.09906)
		(layer "F.Cu")
		(net "OSC_200M_CLKN")
	)
	(segment
		(start 111.291116 -24.268684)
		(end 110.8456 -24.7142)
		(width 0.09906)
		(layer "F.Cu")
		(net "OSC_200M_CLKN")
	)
	(arc
		(start 111.3917 -25.563068)
		(mid 111.353944 -25.752791)
		(end 111.246412 -25.913588)
		(width 0.09906)
		(layer "F.Cu")
		(net "OSC_200M_CLKN")
	)
	(arc
		(start 110.8456 -23.128224)
		(mid 110.861769 -23.209042)
		(end 110.907576 -23.277576)
		(width 0.09906)
		(layer "F.Cu")
		(net "OSC_200M_CLKN")
	)
	(arc
		(start 111.33582 -24.160734)
		(mid 111.3242 -24.219152)
		(end 111.291116 -24.268684)
		(width 0.09906)
		(layer "F.Cu")
		(net "OSC_200M_CLKN")
	)
	(arc
		(start 111.246412 -25.115012)
		(mid 111.353922 -25.275818)
		(end 111.3917 -25.465532)
		(width 0.09906)
		(layer "F.Cu")
		(net "OSC_200M_CLKN")
	)
	(arc
		(start 111.33582 -23.752302)
		(mid 111.335792 -23.758398)
		(end 111.33582 -23.764494)
		(width 0.09906)
		(layer "F.Cu")
		(net "OSC_200M_CLKN")
	)
	(arc
		(start 111.233712 -23.603712)
		(mid 111.291583 -23.673323)
		(end 111.33582 -23.752302)
		(width 0.09906)
		(layer "F.Cu")
		(net "OSC_200M_CLKN")
	)
	(segment
		(start 102.761288 -25.900888)
		(end 102.997 -26.1366)
		(width 0.09906)
		(layer "F.Cu")
		(net "OSC_125M_CLKP")
	)
	(segment
		(start 103.0986 -24.638)
		(end 102.761288 -24.975312)
		(width 0.09906)
		(layer "F.Cu")
		(net "OSC_125M_CLKP")
	)
	(segment
		(start 102.616 -25.325832)
		(end 102.616 -25.550368)
		(width 0.09906)
		(layer "F.Cu")
		(net "OSC_125M_CLKP")
	)
	(segment
		(start 103.632 -22.804882)
		(end 102.743 -22.804882)
		(width 0.09906)
		(layer "F.Cu")
		(net "OSC_125M_CLKP")
	)
	(segment
		(start 102.528116 -23.019766)
		(end 102.528116 -23.862284)
		(width 0.09906)
		(layer "F.Cu")
		(net "OSC_125M_CLKP")
	)
	(segment
		(start 102.673404 -24.212804)
		(end 103.0986 -24.638)
		(width 0.09906)
		(layer "F.Cu")
		(net "OSC_125M_CLKP")
	)
	(arc
		(start 102.616 -25.550368)
		(mid 102.653756 -25.740091)
		(end 102.761288 -25.900888)
		(width 0.09906)
		(layer "F.Cu")
		(net "OSC_125M_CLKP")
	)
	(arc
		(start 102.761288 -24.975312)
		(mid 102.653778 -25.136118)
		(end 102.616 -25.325832)
		(width 0.09906)
		(layer "F.Cu")
		(net "OSC_125M_CLKP")
	)
	(arc
		(start 102.743 -22.804882)
		(mid 102.591054 -22.86782)
		(end 102.528116 -23.019766)
		(width 0.09906)
		(layer "F.Cu")
		(net "OSC_125M_CLKP")
	)
	(arc
		(start 102.528116 -23.862284)
		(mid 102.565872 -24.052007)
		(end 102.673404 -24.212804)
		(width 0.09906)
		(layer "F.Cu")
		(net "OSC_125M_CLKP")
	)
	(segment
		(start 101.092 -22.804882)
		(end 102.108 -22.804882)
		(width 0.09906)
		(layer "F.Cu")
		(net "OSC_125M_CLKN")
	)
	(segment
		(start 102.078028 -24.312372)
		(end 101.7524 -24.638)
		(width 0.09906)
		(layer "F.Cu")
		(net "OSC_125M_CLKN")
	)
	(segment
		(start 102.064312 -25.926288)
		(end 101.854 -26.1366)
		(width 0.09906)
		(layer "F.Cu")
		(net "OSC_125M_CLKN")
	)
	(segment
		(start 101.7524 -24.638)
		(end 102.064312 -24.949912)
		(width 0.09906)
		(layer "F.Cu")
		(net "OSC_125M_CLKN")
	)
	(segment
		(start 102.2096 -25.300432)
		(end 102.2096 -25.575768)
		(width 0.09906)
		(layer "F.Cu")
		(net "OSC_125M_CLKN")
	)
	(segment
		(start 102.223316 -22.920198)
		(end 102.223316 -23.961852)
		(width 0.09906)
		(layer "F.Cu")
		(net "OSC_125M_CLKN")
	)
	(arc
		(start 102.064312 -24.949912)
		(mid 102.171822 -25.110718)
		(end 102.2096 -25.300432)
		(width 0.09906)
		(layer "F.Cu")
		(net "OSC_125M_CLKN")
	)
	(arc
		(start 102.223316 -23.961852)
		(mid 102.18556 -24.151575)
		(end 102.078028 -24.312372)
		(width 0.09906)
		(layer "F.Cu")
		(net "OSC_125M_CLKN")
	)
	(arc
		(start 102.2096 -25.575768)
		(mid 102.171844 -25.765491)
		(end 102.064312 -25.926288)
		(width 0.09906)
		(layer "F.Cu")
		(net "OSC_125M_CLKN")
	)
	(arc
		(start 102.108 -22.804882)
		(mid 102.189541 -22.838657)
		(end 102.223316 -22.920198)
		(width 0.09906)
		(layer "F.Cu")
		(net "OSC_125M_CLKN")
	)
	(segment
		(start 111.73841 -29.378656)
		(end 111.9759 -29.616146)
		(width 0.09906)
		(layer "F.Cu")
		(net "MHZ200CLKP_CLKIN")
	)
	(segment
		(start 112.1791 -28.5242)
		(end 111.761016 -28.942284)
		(width 0.09906)
		(layer "F.Cu")
		(net "MHZ200CLKP_CLKIN")
	)
	(segment
		(start 111.69904 -27.738832)
		(end 111.69904 -27.976322)
		(width 0.09906)
		(layer "F.Cu")
		(net "MHZ200CLKP_CLKIN")
	)
	(segment
		(start 111.7092 -29.067506)
		(end 111.7092 -29.308298)
		(width 0.09906)
		(layer "F.Cu")
		(net "MHZ200CLKP_CLKIN")
	)
	(segment
		(start 111.747046 -28.092146)
		(end 112.1791 -28.5242)
		(width 0.09906)
		(layer "F.Cu")
		(net "MHZ200CLKP_CLKIN")
	)
	(segment
		(start 111.79429 -27.57551)
		(end 111.7473 -27.622754)
		(width 0.09906)
		(layer "F.Cu")
		(net "MHZ200CLKP_CLKIN")
	)
	(segment
		(start 112.84712 -36.823142)
		(end 113.346992 -36.32327)
		(width 0.09906)
		(layer "F.Cu")
		(net "MHZ200CLKP_CLKIN")
	)
	(segment
		(start 112.1156 -27.2542)
		(end 111.79429 -27.57551)
		(width 0.09906)
		(layer "F.Cu")
		(net "MHZ200CLKP_CLKIN")
	)
	(via
		(at 113.346992 -36.32327)
		(size 0.4572)
		(drill 0.2032)
		(layers "F.Cu" "B.Cu")
		(net "MHZ200CLKP_CLKIN")
	)
	(via
		(at 111.9759 -29.616146)
		(size 0.4572)
		(drill 0.2032)
		(layers "F.Cu" "B.Cu")
		(net "MHZ200CLKP_CLKIN")
	)
	(arc
		(start 111.761016 -28.942284)
		(mid 111.722681 -28.999751)
		(end 111.7092 -29.067506)
		(width 0.09906)
		(layer "F.Cu")
		(net "MHZ200CLKP_CLKIN")
	)
	(arc
		(start 111.7473 -27.622754)
		(mid 111.711632 -27.675996)
		(end 111.69904 -27.738832)
		(width 0.09906)
		(layer "F.Cu")
		(net "MHZ200CLKP_CLKIN")
	)
	(arc
		(start 111.7092 -29.308298)
		(mid 111.716794 -29.346387)
		(end 111.73841 -29.378656)
		(width 0.09906)
		(layer "F.Cu")
		(net "MHZ200CLKP_CLKIN")
	)
	(arc
		(start 111.69904 -27.976322)
		(mid 111.711511 -28.039017)
		(end 111.747046 -28.092146)
		(width 0.09906)
		(layer "F.Cu")
		(net "MHZ200CLKP_CLKIN")
	)
	(segment
		(start 113.846864 -36.823142)
		(end 113.346992 -36.32327)
		(width 0.09906)
		(layer "B.Cu")
		(net "MHZ200CLKP_CLKIN")
	)
	(segment
		(start 111.7092 -29.308298)
		(end 111.7092 -28.953968)
		(width 0.09906)
		(layer "B.Cu")
		(net "MHZ200CLKP_CLKIN")
	)
	(segment
		(start 111.743744 -28.870656)
		(end 112.141 -28.4734)
		(width 0.09906)
		(layer "B.Cu")
		(net "MHZ200CLKP_CLKIN")
	)
	(segment
		(start 111.9759 -29.616146)
		(end 111.73841 -29.378656)
		(width 0.09906)
		(layer "B.Cu")
		(net "MHZ200CLKP_CLKIN")
	)
	(segment
		(start 113.847118 -36.823142)
		(end 113.846864 -36.823142)
		(width 0.09906)
		(layer "B.Cu")
		(net "MHZ200CLKP_CLKIN")
	)
	(arc
		(start 111.73841 -29.378656)
		(mid 111.716787 -29.34639)
		(end 111.7092 -29.308298)
		(width 0.09906)
		(layer "B.Cu")
		(net "MHZ200CLKP_CLKIN")
	)
	(arc
		(start 111.7092 -28.953968)
		(mid 111.718171 -28.908866)
		(end 111.743744 -28.870656)
		(width 0.09906)
		(layer "B.Cu")
		(net "MHZ200CLKP_CLKIN")
	)
	(segment
		(start 112.02924 -36.7284)
		(end 113.660428 -36.7284)
		(width 0.0889)
		(layer "In7.Cu")
		(net "MHZ200CLKP_CLKIN")
	)
	(segment
		(start 111.7092 -31.003494)
		(end 111.7092 -31.272734)
		(width 0.11684)
		(layer "In7.Cu")
		(net "MHZ200CLKP_CLKIN")
	)
	(segment
		(start 112.26292 -34.79292)
		(end 112.065308 -34.990786)
		(width 0.0889)
		(layer "In7.Cu")
		(net "MHZ200CLKP_CLKIN")
	)
	(segment
		(start 112.80648 -33.256474)
		(end 112.80648 -33.439354)
		(width 0.11684)
		(layer "In7.Cu")
		(net "MHZ200CLKP_CLKIN")
	)
	(segment
		(start 111.7092 -30.099)
		(end 111.7092 -30.332934)
		(width 0.11684)
		(layer "In7.Cu")
		(net "MHZ200CLKP_CLKIN")
	)
	(segment
		(start 111.9124 -30.536134)
		(end 111.9124 -30.800294)
		(width 0.11684)
		(layer "In7.Cu")
		(net "MHZ200CLKP_CLKIN")
	)
	(segment
		(start 111.9759 -29.616146)
		(end 111.862108 -29.730192)
		(width 0.11684)
		(layer "In7.Cu")
		(net "MHZ200CLKP_CLKIN")
	)
	(segment
		(start 112.522 -33.723834)
		(end 112.522 -34.115502)
		(width 0.11684)
		(layer "In7.Cu")
		(net "MHZ200CLKP_CLKIN")
	)
	(segment
		(start 112.522 -34.1376)
		(end 112.4585 -34.2011)
		(width 0.0889)
		(layer "In7.Cu")
		(net "MHZ200CLKP_CLKIN")
	)
	(segment
		(start 112.330992 -34.725356)
		(end 112.263174 -34.793174)
		(width 0.0889)
		(layer "In7.Cu")
		(net "MHZ200CLKP_CLKIN")
	)
	(segment
		(start 112.263174 -34.793174)
		(end 112.26292 -34.79292)
		(width 0.0889)
		(layer "In7.Cu")
		(net "MHZ200CLKP_CLKIN")
	)
	(segment
		(start 111.794798 -31.47949)
		(end 112.276128 -31.961074)
		(width 0.11684)
		(layer "In7.Cu")
		(net "MHZ200CLKP_CLKIN")
	)
	(segment
		(start 113.662968 -36.32327)
		(end 113.346992 -36.32327)
		(width 0.0889)
		(layer "In7.Cu")
		(net "MHZ200CLKP_CLKIN")
	)
	(segment
		(start 112.4585 -34.2011)
		(end 112.4585 -34.417254)
		(width 0.0889)
		(layer "In7.Cu")
		(net "MHZ200CLKP_CLKIN")
	)
	(segment
		(start 113.751868 -36.63696)
		(end 113.751868 -36.41217)
		(width 0.0889)
		(layer "In7.Cu")
		(net "MHZ200CLKP_CLKIN")
	)
	(segment
		(start 112.522 -32.555434)
		(end 112.522 -32.971994)
		(width 0.11684)
		(layer "In7.Cu")
		(net "MHZ200CLKP_CLKIN")
	)
	(segment
		(start 112.522 -34.115502)
		(end 112.522 -34.1376)
		(width 0.0889)
		(layer "In7.Cu")
		(net "MHZ200CLKP_CLKIN")
	)
	(segment
		(start 111.9378 -35.298634)
		(end 111.9378 -36.63696)
		(width 0.0889)
		(layer "In7.Cu")
		(net "MHZ200CLKP_CLKIN")
	)
	(arc
		(start 112.66424 -33.581594)
		(mid 112.563661 -33.623255)
		(end 112.522 -33.723834)
		(width 0.11684)
		(layer "In7.Cu")
		(net "MHZ200CLKP_CLKIN")
	)
	(arc
		(start 112.276128 -31.961074)
		(mid 112.458146 -32.233812)
		(end 112.522 -32.555434)
		(width 0.11684)
		(layer "In7.Cu")
		(net "MHZ200CLKP_CLKIN")
	)
	(arc
		(start 112.80648 -33.439354)
		(mid 112.764819 -33.539933)
		(end 112.66424 -33.581594)
		(width 0.11684)
		(layer "In7.Cu")
		(net "MHZ200CLKP_CLKIN")
	)
	(arc
		(start 111.8108 -30.901894)
		(mid 111.738958 -30.931652)
		(end 111.7092 -31.003494)
		(width 0.11684)
		(layer "In7.Cu")
		(net "MHZ200CLKP_CLKIN")
	)
	(arc
		(start 112.4585 -34.417254)
		(mid 112.425356 -34.583969)
		(end 112.330992 -34.725356)
		(width 0.0889)
		(layer "In7.Cu")
		(net "MHZ200CLKP_CLKIN")
	)
	(arc
		(start 111.8108 -30.434534)
		(mid 111.882642 -30.464292)
		(end 111.9124 -30.536134)
		(width 0.11684)
		(layer "In7.Cu")
		(net "MHZ200CLKP_CLKIN")
	)
	(arc
		(start 111.862108 -29.730192)
		(mid 111.748938 -29.899374)
		(end 111.7092 -30.099)
		(width 0.11684)
		(layer "In7.Cu")
		(net "MHZ200CLKP_CLKIN")
	)
	(arc
		(start 112.065308 -34.990786)
		(mid 111.970933 -35.132028)
		(end 111.9378 -35.298634)
		(width 0.0889)
		(layer "In7.Cu")
		(net "MHZ200CLKP_CLKIN")
	)
	(arc
		(start 112.66424 -33.114234)
		(mid 112.764819 -33.155895)
		(end 112.80648 -33.256474)
		(width 0.11684)
		(layer "In7.Cu")
		(net "MHZ200CLKP_CLKIN")
	)
	(arc
		(start 112.522 -32.971994)
		(mid 112.563661 -33.072573)
		(end 112.66424 -33.114234)
		(width 0.11684)
		(layer "In7.Cu")
		(net "MHZ200CLKP_CLKIN")
	)
	(arc
		(start 113.751868 -36.41217)
		(mid 113.72583 -36.349308)
		(end 113.662968 -36.32327)
		(width 0.0889)
		(layer "In7.Cu")
		(net "MHZ200CLKP_CLKIN")
	)
	(arc
		(start 113.660428 -36.7284)
		(mid 113.725086 -36.701618)
		(end 113.751868 -36.63696)
		(width 0.0889)
		(layer "In7.Cu")
		(net "MHZ200CLKP_CLKIN")
	)
	(arc
		(start 111.7092 -30.332934)
		(mid 111.738958 -30.404776)
		(end 111.8108 -30.434534)
		(width 0.11684)
		(layer "In7.Cu")
		(net "MHZ200CLKP_CLKIN")
	)
	(arc
		(start 111.7092 -31.272734)
		(mid 111.731439 -31.384627)
		(end 111.794798 -31.47949)
		(width 0.11684)
		(layer "In7.Cu")
		(net "MHZ200CLKP_CLKIN")
	)
	(arc
		(start 111.9378 -36.63696)
		(mid 111.964582 -36.701618)
		(end 112.02924 -36.7284)
		(width 0.0889)
		(layer "In7.Cu")
		(net "MHZ200CLKP_CLKIN")
	)
	(arc
		(start 111.9124 -30.800294)
		(mid 111.882642 -30.872136)
		(end 111.8108 -30.901894)
		(width 0.11684)
		(layer "In7.Cu")
		(net "MHZ200CLKP_CLKIN")
	)
	(segment
		(start 110.9091 -28.5242)
		(end 111.37519 -28.99029)
		(width 0.09906)
		(layer "F.Cu")
		(net "MHZ200CLKN_CLKIN")
	)
	(segment
		(start 111.28375 -27.56535)
		(end 110.9726 -27.2542)
		(width 0.09906)
		(layer "F.Cu")
		(net "MHZ200CLKN_CLKIN")
	)
	(segment
		(start 113.847118 -36.823142)
		(end 114.34699 -36.32327)
		(width 0.09906)
		(layer "F.Cu")
		(net "MHZ200CLKN_CLKIN")
	)
	(segment
		(start 111.39424 -27.976322)
		(end 111.39424 -27.738832)
		(width 0.09906)
		(layer "F.Cu")
		(net "MHZ200CLKN_CLKIN")
	)
	(segment
		(start 111.4044 -29.060648)
		(end 111.4044 -29.30144)
		(width 0.09906)
		(layer "F.Cu")
		(net "MHZ200CLKN_CLKIN")
	)
	(segment
		(start 111.352584 -29.426662)
		(end 111.1631 -29.616146)
		(width 0.09906)
		(layer "F.Cu")
		(net "MHZ200CLKN_CLKIN")
	)
	(segment
		(start 111.34979 -27.631136)
		(end 111.28375 -27.56535)
		(width 0.09906)
		(layer "F.Cu")
		(net "MHZ200CLKN_CLKIN")
	)
	(segment
		(start 110.9091 -28.5242)
		(end 111.34979 -28.083256)
		(width 0.09906)
		(layer "F.Cu")
		(net "MHZ200CLKN_CLKIN")
	)
	(via
		(at 114.34699 -36.32327)
		(size 0.4572)
		(drill 0.2032)
		(layers "F.Cu" "B.Cu")
		(net "MHZ200CLKN_CLKIN")
	)
	(via
		(at 111.1631 -29.616146)
		(size 0.4572)
		(drill 0.2032)
		(layers "F.Cu" "B.Cu")
		(net "MHZ200CLKN_CLKIN")
	)
	(arc
		(start 111.37519 -28.99029)
		(mid 111.396813 -29.022556)
		(end 111.4044 -29.060648)
		(width 0.09906)
		(layer "F.Cu")
		(net "MHZ200CLKN_CLKIN")
	)
	(arc
		(start 111.34979 -28.083256)
		(mid 111.382655 -28.034209)
		(end 111.39424 -27.976322)
		(width 0.09906)
		(layer "F.Cu")
		(net "MHZ200CLKN_CLKIN")
	)
	(arc
		(start 111.39424 -27.738832)
		(mid 111.382742 -27.680555)
		(end 111.34979 -27.631136)
		(width 0.09906)
		(layer "F.Cu")
		(net "MHZ200CLKN_CLKIN")
	)
	(arc
		(start 111.4044 -29.30144)
		(mid 111.390939 -29.369204)
		(end 111.352584 -29.426662)
		(width 0.09906)
		(layer "F.Cu")
		(net "MHZ200CLKN_CLKIN")
	)
	(segment
		(start 111.1631 -29.616146)
		(end 111.338614 -29.440632)
		(width 0.09906)
		(layer "B.Cu")
		(net "MHZ200CLKN_CLKIN")
	)
	(segment
		(start 114.84737 -36.823142)
		(end 114.846862 -36.823142)
		(width 0.09906)
		(layer "B.Cu")
		(net "MHZ200CLKN_CLKIN")
	)
	(segment
		(start 111.37519 -28.85059)
		(end 110.998 -28.4734)
		(width 0.09906)
		(layer "B.Cu")
		(net "MHZ200CLKN_CLKIN")
	)
	(segment
		(start 114.846862 -36.823142)
		(end 114.34699 -36.32327)
		(width 0.09906)
		(layer "B.Cu")
		(net "MHZ200CLKN_CLKIN")
	)
	(segment
		(start 111.4044 -29.281882)
		(end 111.4044 -28.920948)
		(width 0.09906)
		(layer "B.Cu")
		(net "MHZ200CLKN_CLKIN")
	)
	(arc
		(start 111.4044 -28.920948)
		(mid 111.396806 -28.882859)
		(end 111.37519 -28.85059)
		(width 0.09906)
		(layer "B.Cu")
		(net "MHZ200CLKN_CLKIN")
	)
	(arc
		(start 111.338614 -29.440632)
		(mid 111.387281 -29.367797)
		(end 111.4044 -29.281882)
		(width 0.09906)
		(layer "B.Cu")
		(net "MHZ200CLKN_CLKIN")
	)
	(segment
		(start 113.942368 -36.63696)
		(end 113.942368 -36.41217)
		(width 0.0889)
		(layer "In7.Cu")
		(net "MHZ200CLKN_CLKIN")
	)
	(segment
		(start 111.7473 -35.298634)
		(end 111.7473 -36.63696)
		(width 0.0889)
		(layer "In7.Cu")
		(net "MHZ200CLKN_CLKIN")
	)
	(segment
		(start 111.930434 -34.855912)
		(end 111.930688 -34.855912)
		(width 0.0889)
		(layer "In7.Cu")
		(net "MHZ200CLKN_CLKIN")
	)
	(segment
		(start 112.196118 -34.590482)
		(end 111.930434 -34.855912)
		(width 0.0889)
		(layer "In7.Cu")
		(net "MHZ200CLKN_CLKIN")
	)
	(segment
		(start 111.570262 -31.704026)
		(end 112.051338 -32.18561)
		(width 0.11684)
		(layer "In7.Cu")
		(net "MHZ200CLKN_CLKIN")
	)
	(segment
		(start 112.2045 -34.115502)
		(end 112.2045 -34.1376)
		(width 0.0889)
		(layer "In7.Cu")
		(net "MHZ200CLKN_CLKIN")
	)
	(segment
		(start 112.2045 -34.1376)
		(end 112.268 -34.2011)
		(width 0.0889)
		(layer "In7.Cu")
		(net "MHZ200CLKN_CLKIN")
	)
	(segment
		(start 112.268 -34.2011)
		(end 112.268 -34.417)
		(width 0.0889)
		(layer "In7.Cu")
		(net "MHZ200CLKN_CLKIN")
	)
	(segment
		(start 111.3917 -30.168088)
		(end 111.3917 -31.272734)
		(width 0.11684)
		(layer "In7.Cu")
		(net "MHZ200CLKN_CLKIN")
	)
	(segment
		(start 112.02924 -36.9189)
		(end 113.660428 -36.9189)
		(width 0.0889)
		(layer "In7.Cu")
		(net "MHZ200CLKN_CLKIN")
	)
	(segment
		(start 112.2045 -32.555434)
		(end 112.2045 -34.115502)
		(width 0.11684)
		(layer "In7.Cu")
		(net "MHZ200CLKN_CLKIN")
	)
	(segment
		(start 114.031268 -36.32327)
		(end 114.34699 -36.32327)
		(width 0.0889)
		(layer "In7.Cu")
		(net "MHZ200CLKN_CLKIN")
	)
	(arc
		(start 111.1631 -29.616146)
		(mid 111.332305 -29.869379)
		(end 111.3917 -30.168088)
		(width 0.11684)
		(layer "In7.Cu")
		(net "MHZ200CLKN_CLKIN")
	)
	(arc
		(start 111.7473 -36.63696)
		(mid 111.829878 -36.836322)
		(end 112.02924 -36.9189)
		(width 0.0889)
		(layer "In7.Cu")
		(net "MHZ200CLKN_CLKIN")
	)
	(arc
		(start 111.3917 -31.272734)
		(mid 111.438107 -31.506129)
		(end 111.570262 -31.704026)
		(width 0.11684)
		(layer "In7.Cu")
		(net "MHZ200CLKN_CLKIN")
	)
	(arc
		(start 111.930688 -34.855912)
		(mid 111.794912 -35.05902)
		(end 111.7473 -35.298634)
		(width 0.0889)
		(layer "In7.Cu")
		(net "MHZ200CLKN_CLKIN")
	)
	(arc
		(start 112.051338 -32.18561)
		(mid 112.164712 -32.355287)
		(end 112.2045 -32.555434)
		(width 0.11684)
		(layer "In7.Cu")
		(net "MHZ200CLKN_CLKIN")
	)
	(arc
		(start 112.268 -34.417)
		(mid 112.249323 -34.510897)
		(end 112.196118 -34.590482)
		(width 0.0889)
		(layer "In7.Cu")
		(net "MHZ200CLKN_CLKIN")
	)
	(arc
		(start 113.660428 -36.9189)
		(mid 113.85979 -36.836322)
		(end 113.942368 -36.63696)
		(width 0.0889)
		(layer "In7.Cu")
		(net "MHZ200CLKN_CLKIN")
	)
	(arc
		(start 113.942368 -36.41217)
		(mid 113.968406 -36.349308)
		(end 114.031268 -36.32327)
		(width 0.0889)
		(layer "In7.Cu")
		(net "MHZ200CLKN_CLKIN")
	)
	(segment
		(start 103.847138 -38.823138)
		(end 103.347266 -38.323266)
		(width 0.09906)
		(layer "F.Cu")
		(net "MHZ125CLKP_CLKIN")
	)
	(segment
		(start 102.706424 -27.493976)
		(end 102.997 -27.2034)
		(width 0.09906)
		(layer "F.Cu")
		(net "MHZ125CLKP_CLKIN")
	)
	(segment
		(start 102.5652 -28.845256)
		(end 102.5652 -27.834844)
		(width 0.09906)
		(layer "F.Cu")
		(net "MHZ125CLKP_CLKIN")
	)
	(via
		(at 102.8319 -29.489146)
		(size 0.4572)
		(drill 0.2032)
		(layers "F.Cu" "B.Cu")
		(net "MHZ125CLKP_CLKIN")
	)
	(via
		(at 103.347266 -38.323266)
		(size 0.4572)
		(drill 0.2032)
		(layers "F.Cu" "B.Cu")
		(net "MHZ125CLKP_CLKIN")
	)
	(arc
		(start 102.5652 -27.834844)
		(mid 102.601897 -27.650355)
		(end 102.706424 -27.493976)
		(width 0.09906)
		(layer "F.Cu")
		(net "MHZ125CLKP_CLKIN")
	)
	(arc
		(start 102.8319 -29.489146)
		(mid 102.634507 -29.193727)
		(end 102.5652 -28.845256)
		(width 0.09906)
		(layer "F.Cu")
		(net "MHZ125CLKP_CLKIN")
	)
	(segment
		(start 103.847138 -37.82314)
		(end 103.847138 -37.823394)
		(width 0.09906)
		(layer "B.Cu")
		(net "MHZ125CLKP_CLKIN")
	)
	(segment
		(start 103.847138 -37.823394)
		(end 103.347266 -38.323266)
		(width 0.09906)
		(layer "B.Cu")
		(net "MHZ125CLKP_CLKIN")
	)
	(segment
		(start 102.6287 -34.29)
		(end 102.6287 -29.824426)
		(width 0.11684)
		(layer "In7.Cu")
		(net "MHZ125CLKP_CLKIN")
	)
	(segment
		(start 103.347266 -38.323266)
		(end 103.136192 -38.323266)
		(width 0.0889)
		(layer "In7.Cu")
		(net "MHZ125CLKP_CLKIN")
	)
	(segment
		(start 102.812342 -34.867342)
		(end 102.639622 -34.694622)
		(width 0.0889)
		(layer "In7.Cu")
		(net "MHZ125CLKP_CLKIN")
	)
	(segment
		(start 102.6287 -34.312098)
		(end 102.6287 -34.29)
		(width 0.0889)
		(layer "In7.Cu")
		(net "MHZ125CLKP_CLKIN")
	)
	(segment
		(start 102.5652 -34.51479)
		(end 102.5652 -34.375598)
		(width 0.0889)
		(layer "In7.Cu")
		(net "MHZ125CLKP_CLKIN")
	)
	(segment
		(start 102.5652 -34.375598)
		(end 102.6287 -34.312098)
		(width 0.0889)
		(layer "In7.Cu")
		(net "MHZ125CLKP_CLKIN")
	)
	(segment
		(start 102.942644 -38.129718)
		(end 102.942644 -35.182048)
		(width 0.0889)
		(layer "In7.Cu")
		(net "MHZ125CLKP_CLKIN")
	)
	(segment
		(start 102.722172 -29.598874)
		(end 102.8319 -29.489146)
		(width 0.11684)
		(layer "In7.Cu")
		(net "MHZ125CLKP_CLKIN")
	)
	(arc
		(start 102.639622 -34.694622)
		(mid 102.584546 -34.6121)
		(end 102.5652 -34.51479)
		(width 0.0889)
		(layer "In7.Cu")
		(net "MHZ125CLKP_CLKIN")
	)
	(arc
		(start 102.942644 -35.182048)
		(mid 102.90877 -35.011751)
		(end 102.812342 -34.867342)
		(width 0.0889)
		(layer "In7.Cu")
		(net "MHZ125CLKP_CLKIN")
	)
	(arc
		(start 102.6287 -29.824426)
		(mid 102.652999 -29.702355)
		(end 102.722172 -29.598874)
		(width 0.11684)
		(layer "In7.Cu")
		(net "MHZ125CLKP_CLKIN")
	)
	(arc
		(start 103.136192 -38.323266)
		(mid 102.999333 -38.266577)
		(end 102.942644 -38.129718)
		(width 0.0889)
		(layer "In7.Cu")
		(net "MHZ125CLKP_CLKIN")
	)
	(segment
		(start 102.84714 -38.823138)
		(end 102.347268 -38.323266)
		(width 0.09906)
		(layer "F.Cu")
		(net "MHZ125CLKN_CLKIN")
	)
	(segment
		(start 102.115112 -27.464512)
		(end 101.854 -27.2034)
		(width 0.09906)
		(layer "F.Cu")
		(net "MHZ125CLKN_CLKIN")
	)
	(segment
		(start 102.2604 -28.90647)
		(end 102.2604 -27.815032)
		(width 0.09906)
		(layer "F.Cu")
		(net "MHZ125CLKN_CLKIN")
	)
	(via
		(at 102.0191 -29.489146)
		(size 0.4572)
		(drill 0.2032)
		(layers "F.Cu" "B.Cu")
		(net "MHZ125CLKN_CLKIN")
	)
	(via
		(at 102.347268 -38.323266)
		(size 0.4572)
		(drill 0.2032)
		(layers "F.Cu" "B.Cu")
		(net "MHZ125CLKN_CLKIN")
	)
	(arc
		(start 102.2604 -27.815032)
		(mid 102.222644 -27.625309)
		(end 102.115112 -27.464512)
		(width 0.09906)
		(layer "F.Cu")
		(net "MHZ125CLKN_CLKIN")
	)
	(arc
		(start 102.0191 -29.489146)
		(mid 102.197727 -29.221812)
		(end 102.2604 -28.90647)
		(width 0.09906)
		(layer "F.Cu")
		(net "MHZ125CLKN_CLKIN")
	)
	(segment
		(start 102.846886 -37.82314)
		(end 102.846886 -37.823648)
		(width 0.09906)
		(layer "B.Cu")
		(net "MHZ125CLKN_CLKIN")
	)
	(segment
		(start 102.846886 -37.823648)
		(end 102.347268 -38.323266)
		(width 0.09906)
		(layer "B.Cu")
		(net "MHZ125CLKN_CLKIN")
	)
	(segment
		(start 102.3747 -34.375598)
		(end 102.3112 -34.312098)
		(width 0.0889)
		(layer "In7.Cu")
		(net "MHZ125CLKN_CLKIN")
	)
	(segment
		(start 102.3747 -34.51479)
		(end 102.3747 -34.375598)
		(width 0.0889)
		(layer "In7.Cu")
		(net "MHZ125CLKN_CLKIN")
	)
	(segment
		(start 102.3112 -34.312098)
		(end 102.3112 -34.29)
		(width 0.0889)
		(layer "In7.Cu")
		(net "MHZ125CLKN_CLKIN")
	)
	(segment
		(start 102.677722 -35.002216)
		(end 102.505002 -34.829496)
		(width 0.0889)
		(layer "In7.Cu")
		(net "MHZ125CLKN_CLKIN")
	)
	(segment
		(start 102.180898 -29.650944)
		(end 102.0191 -29.489146)
		(width 0.11684)
		(layer "In7.Cu")
		(net "MHZ125CLKN_CLKIN")
	)
	(segment
		(start 102.752144 -38.129718)
		(end 102.752144 -35.182048)
		(width 0.0889)
		(layer "In7.Cu")
		(net "MHZ125CLKN_CLKIN")
	)
	(segment
		(start 102.347268 -38.323266)
		(end 102.558596 -38.323266)
		(width 0.0889)
		(layer "In7.Cu")
		(net "MHZ125CLKN_CLKIN")
	)
	(segment
		(start 102.3112 -34.29)
		(end 102.3112 -29.965396)
		(width 0.11684)
		(layer "In7.Cu")
		(net "MHZ125CLKN_CLKIN")
	)
	(arc
		(start 102.3112 -29.965396)
		(mid 102.27733 -29.79521)
		(end 102.180898 -29.650944)
		(width 0.11684)
		(layer "In7.Cu")
		(net "MHZ125CLKN_CLKIN")
	)
	(arc
		(start 102.505002 -34.829496)
		(mid 102.408525 -34.685108)
		(end 102.3747 -34.51479)
		(width 0.0889)
		(layer "In7.Cu")
		(net "MHZ125CLKN_CLKIN")
	)
	(arc
		(start 102.752144 -35.182048)
		(mid 102.732805 -35.084735)
		(end 102.677722 -35.002216)
		(width 0.0889)
		(layer "In7.Cu")
		(net "MHZ125CLKN_CLKIN")
	)
	(arc
		(start 102.558596 -38.323266)
		(mid 102.695455 -38.266577)
		(end 102.752144 -38.129718)
		(width 0.0889)
		(layer "In7.Cu")
		(net "MHZ125CLKN_CLKIN")
	)
	(segment
		(start 124.0536 -53.721)
		(end 122.682 -53.721)
		(width 0.11938)
		(layer "F.Cu")
		(net "FPGA_PROGRAM_N")
	)
	(segment
		(start 122.682 -53.721)
		(end 122.428 -53.975)
		(width 0.11938)
		(layer "F.Cu")
		(net "FPGA_PROGRAM_N")
	)
	(segment
		(start 110.847124 -44.823126)
		(end 111.346996 -45.322998)
		(width 0.11938)
		(layer "F.Cu")
		(net "FPGA_PROGRAM_N")
	)
	(segment
		(start 124.0536 -53.721)
		(end 124.0536 -52.578)
		(width 0.11938)
		(layer "F.Cu")
		(net "FPGA_PROGRAM_N")
	)
	(via
		(at 111.346996 -45.322998)
		(size 0.4572)
		(drill 0.2032)
		(layers "F.Cu" "B.Cu")
		(net "FPGA_PROGRAM_N")
	)
	(segment
		(start 118.617746 -50.8)
		(end 118.15318 -50.8)
		(width 0.127)
		(layer "In7.Cu")
		(net "FPGA_PROGRAM_N")
	)
	(segment
		(start 116.84 -49.121314)
		(end 116.613686 -48.895)
		(width 0.127)
		(layer "In7.Cu")
		(net "FPGA_PROGRAM_N")
	)
	(segment
		(start 118.15318 -50.8)
		(end 117.856 -50.50282)
		(width 0.127)
		(layer "In7.Cu")
		(net "FPGA_PROGRAM_N")
	)
	(segment
		(start 115.824 -48.061118)
		(end 115.641882 -47.879)
		(width 0.127)
		(layer "In7.Cu")
		(net "FPGA_PROGRAM_N")
	)
	(segment
		(start 116.078 -48.895)
		(end 115.824 -48.641)
		(width 0.127)
		(layer "In7.Cu")
		(net "FPGA_PROGRAM_N")
	)
	(segment
		(start 117.729 -49.784)
		(end 117.094 -49.784)
		(width 0.127)
		(layer "In7.Cu")
		(net "FPGA_PROGRAM_N")
	)
	(segment
		(start 110.927896 -45.917104)
		(end 111.346996 -45.498004)
		(width 0.127)
		(layer "In7.Cu")
		(net "FPGA_PROGRAM_N")
	)
	(segment
		(start 120.142 -51.308)
		(end 119.125746 -51.308)
		(width 0.127)
		(layer "In7.Cu")
		(net "FPGA_PROGRAM_N")
	)
	(segment
		(start 117.094 -49.784)
		(end 116.84 -49.53)
		(width 0.127)
		(layer "In7.Cu")
		(net "FPGA_PROGRAM_N")
	)
	(segment
		(start 117.856 -49.911)
		(end 117.729 -49.784)
		(width 0.127)
		(layer "In7.Cu")
		(net "FPGA_PROGRAM_N")
	)
	(segment
		(start 111.054896 -47.879)
		(end 110.927896 -47.752)
		(width 0.127)
		(layer "In7.Cu")
		(net "FPGA_PROGRAM_N")
	)
	(segment
		(start 119.125746 -51.308)
		(end 118.617746 -50.8)
		(width 0.127)
		(layer "In7.Cu")
		(net "FPGA_PROGRAM_N")
	)
	(segment
		(start 116.84 -49.53)
		(end 116.84 -49.121314)
		(width 0.127)
		(layer "In7.Cu")
		(net "FPGA_PROGRAM_N")
	)
	(segment
		(start 111.346996 -45.498004)
		(end 111.346996 -45.322998)
		(width 0.127)
		(layer "In7.Cu")
		(net "FPGA_PROGRAM_N")
	)
	(segment
		(start 110.927896 -47.752)
		(end 110.927896 -45.917104)
		(width 0.127)
		(layer "In7.Cu")
		(net "FPGA_PROGRAM_N")
	)
	(segment
		(start 117.856 -50.50282)
		(end 117.856 -49.911)
		(width 0.127)
		(layer "In7.Cu")
		(net "FPGA_PROGRAM_N")
	)
	(segment
		(start 121.3485 -52.8955)
		(end 121.3485 -52.5145)
		(width 0.127)
		(layer "In7.Cu")
		(net "FPGA_PROGRAM_N")
	)
	(segment
		(start 115.824 -48.641)
		(end 115.824 -48.061118)
		(width 0.127)
		(layer "In7.Cu")
		(net "FPGA_PROGRAM_N")
	)
	(segment
		(start 116.613686 -48.895)
		(end 116.078 -48.895)
		(width 0.127)
		(layer "In7.Cu")
		(net "FPGA_PROGRAM_N")
	)
	(segment
		(start 122.428 -53.975)
		(end 121.3485 -52.8955)
		(width 0.127)
		(layer "In7.Cu")
		(net "FPGA_PROGRAM_N")
	)
	(segment
		(start 121.3485 -52.5145)
		(end 120.142 -51.308)
		(width 0.127)
		(layer "In7.Cu")
		(net "FPGA_PROGRAM_N")
	)
	(segment
		(start 115.641882 -47.879)
		(end 111.054896 -47.879)
		(width 0.127)
		(layer "In7.Cu")
		(net "FPGA_PROGRAM_N")
	)
	(segment
		(start 89.92997 -26.750518)
		(end 90.084656 -26.595832)
		(width 0.09906)
		(layer "F.Cu")
		(net "FPGA_OUT_MAC_PPS_IN1P")
	)
	(segment
		(start 85.5218 -52.1716)
		(end 85.5218 -34.622232)
		(width 0.09906)
		(layer "F.Cu")
		(net "FPGA_OUT_MAC_PPS_IN1P")
	)
	(segment
		(start 85.81136 -33.923732)
		(end 89.66327 -30.072076)
		(width 0.09906)
		(layer "F.Cu")
		(net "FPGA_OUT_MAC_PPS_IN1P")
	)
	(segment
		(start 82.217006 -53.086)
		(end 82.197194 -53.086)
		(width 0.09906)
		(layer "F.Cu")
		(net "FPGA_OUT_MAC_PPS_IN1P")
	)
	(segment
		(start 82.7786 -53.4924)
		(end 82.482182 -53.195982)
		(width 0.09906)
		(layer "F.Cu")
		(net "FPGA_OUT_MAC_PPS_IN1P")
	)
	(segment
		(start 82.7786 -53.4924)
		(end 82.872072 -53.398674)
		(width 0.09906)
		(layer "F.Cu")
		(net "FPGA_OUT_MAC_PPS_IN1P")
	)
	(segment
		(start 90.084656 -26.595832)
		(end 90.084656 -26.595578)
		(width 0.09906)
		(layer "F.Cu")
		(net "FPGA_OUT_MAC_PPS_IN1P")
	)
	(segment
		(start 81.932018 -53.195982)
		(end 81.534 -53.594)
		(width 0.09906)
		(layer "F.Cu")
		(net "FPGA_OUT_MAC_PPS_IN1P")
	)
	(segment
		(start 83.566 -53.1114)
		(end 84.582 -53.1114)
		(width 0.09906)
		(layer "F.Cu")
		(net "FPGA_OUT_MAC_PPS_IN1P")
	)
	(segment
		(start 89.789 -29.767276)
		(end 89.789 -27.090878)
		(width 0.09906)
		(layer "F.Cu")
		(net "FPGA_OUT_MAC_PPS_IN1P")
	)
	(segment
		(start 118.847108 -37.82314)
		(end 119.34698 -37.323268)
		(width 0.09906)
		(layer "F.Cu")
		(net "FPGA_OUT_MAC_PPS_IN1P")
	)
	(arc
		(start 85.5218 -34.622232)
		(mid 85.59711 -34.244186)
		(end 85.81136 -33.923732)
		(width 0.09906)
		(layer "F.Cu")
		(net "FPGA_OUT_MAC_PPS_IN1P")
	)
	(arc
		(start 89.789 -27.090878)
		(mid 89.825639 -26.906681)
		(end 89.92997 -26.750518)
		(width 0.09906)
		(layer "F.Cu")
		(net "FPGA_OUT_MAC_PPS_IN1P")
	)
	(arc
		(start 84.582 -53.1114)
		(mid 85.246539 -52.836139)
		(end 85.5218 -52.1716)
		(width 0.09906)
		(layer "F.Cu")
		(net "FPGA_OUT_MAC_PPS_IN1P")
	)
	(arc
		(start 89.66327 -30.072076)
		(mid 89.756437 -29.932174)
		(end 89.789 -29.767276)
		(width 0.09906)
		(layer "F.Cu")
		(net "FPGA_OUT_MAC_PPS_IN1P")
	)
	(arc
		(start 82.197194 -53.086)
		(mid 82.053681 -53.11464)
		(end 81.932018 -53.195982)
		(width 0.09906)
		(layer "F.Cu")
		(net "FPGA_OUT_MAC_PPS_IN1P")
	)
	(arc
		(start 82.872072 -53.398674)
		(mid 83.190464 -53.186024)
		(end 83.566 -53.1114)
		(width 0.09906)
		(layer "F.Cu")
		(net "FPGA_OUT_MAC_PPS_IN1P")
	)
	(arc
		(start 82.482182 -53.195982)
		(mid 82.360533 -53.114606)
		(end 82.217006 -53.086)
		(width 0.09906)
		(layer "F.Cu")
		(net "FPGA_OUT_MAC_PPS_IN1P")
	)
	(segment
		(start 120.11914 -36.7411)
		(end 121.021094 -36.7411)
		(width 0.0889)
		(layer "In7.Cu")
		(net "FPGA_OUT_MAC_PPS_IN1P")
	)
	(segment
		(start 119.93372 -27.35072)
		(end 119.72925 -27.14625)
		(width 0.11684)
		(layer "In7.Cu")
		(net "FPGA_OUT_MAC_PPS_IN1P")
	)
	(segment
		(start 121.021094 -36.7411)
		(end 121.084594 -36.6776)
		(width 0.0889)
		(layer "In7.Cu")
		(net "FPGA_OUT_MAC_PPS_IN1P")
	)
	(segment
		(start 90.084656 -26.595324)
		(end 90.084656 -26.595578)
		(width 0.11684)
		(layer "In7.Cu")
		(net "FPGA_OUT_MAC_PPS_IN1P")
	)
	(segment
		(start 122.710448 -30.340554)
		(end 122.53722 -30.167326)
		(width 0.11684)
		(layer "In7.Cu")
		(net "FPGA_OUT_MAC_PPS_IN1P")
	)
	(segment
		(start 119.34698 -37.323268)
		(end 119.662702 -37.323268)
		(width 0.0889)
		(layer "In7.Cu")
		(net "FPGA_OUT_MAC_PPS_IN1P")
	)
	(segment
		(start 123.152154 -35.275774)
		(end 123.343162 -35.084766)
		(width 0.11684)
		(layer "In7.Cu")
		(net "FPGA_OUT_MAC_PPS_IN1P")
	)
	(segment
		(start 122.715782 -35.500818)
		(end 122.940826 -35.275774)
		(width 0.11684)
		(layer "In7.Cu")
		(net "FPGA_OUT_MAC_PPS_IN1P")
	)
	(segment
		(start 122.489214 -29.906214)
		(end 120.381268 -27.798268)
		(width 0.11684)
		(layer "In7.Cu")
		(net "FPGA_OUT_MAC_PPS_IN1P")
	)
	(segment
		(start 121.084594 -36.6776)
		(end 121.106692 -36.6776)
		(width 0.0889)
		(layer "In7.Cu")
		(net "FPGA_OUT_MAC_PPS_IN1P")
	)
	(segment
		(start 113.919 -24.7396)
		(end 93.580204 -24.7396)
		(width 0.11684)
		(layer "In7.Cu")
		(net "FPGA_OUT_MAC_PPS_IN1P")
	)
	(segment
		(start 89.837006 -25.658572)
		(end 89.837006 -26.183844)
		(width 0.11684)
		(layer "In7.Cu")
		(net "FPGA_OUT_MAC_PPS_IN1P")
	)
	(segment
		(start 119.751602 -37.234368)
		(end 119.751602 -37.108638)
		(width 0.0889)
		(layer "In7.Cu")
		(net "FPGA_OUT_MAC_PPS_IN1P")
	)
	(segment
		(start 89.95283 -26.463498)
		(end 90.084656 -26.595324)
		(width 0.11684)
		(layer "In7.Cu")
		(net "FPGA_OUT_MAC_PPS_IN1P")
	)
	(segment
		(start 93.427804 -24.892)
		(end 93.112844 -24.892)
		(width 0.11684)
		(layer "In7.Cu")
		(net "FPGA_OUT_MAC_PPS_IN1P")
	)
	(segment
		(start 123.143772 -30.560772)
		(end 122.97156 -30.38856)
		(width 0.11684)
		(layer "In7.Cu")
		(net "FPGA_OUT_MAC_PPS_IN1P")
	)
	(segment
		(start 121.106692 -36.6776)
		(end 121.69775 -36.6776)
		(width 0.11684)
		(layer "In7.Cu")
		(net "FPGA_OUT_MAC_PPS_IN1P")
	)
	(segment
		(start 120.147588 -27.798268)
		(end 119.93372 -27.5844)
		(width 0.11684)
		(layer "In7.Cu")
		(net "FPGA_OUT_MAC_PPS_IN1P")
	)
	(segment
		(start 92.960444 -24.7396)
		(end 91.263216 -24.7396)
		(width 0.11684)
		(layer "In7.Cu")
		(net "FPGA_OUT_MAC_PPS_IN1P")
	)
	(segment
		(start 90.307414 -25.135586)
		(end 89.874344 -25.568656)
		(width 0.11684)
		(layer "In7.Cu")
		(net "FPGA_OUT_MAC_PPS_IN1P")
	)
	(segment
		(start 121.787666 -36.640262)
		(end 122.715782 -35.712146)
		(width 0.11684)
		(layer "In7.Cu")
		(net "FPGA_OUT_MAC_PPS_IN1P")
	)
	(segment
		(start 123.3805 -34.99485)
		(end 123.3805 -31.132018)
		(width 0.11684)
		(layer "In7.Cu")
		(net "FPGA_OUT_MAC_PPS_IN1P")
	)
	(arc
		(start 122.715782 -35.712146)
		(mid 122.737666 -35.659314)
		(end 122.715782 -35.606482)
		(width 0.11684)
		(layer "In7.Cu")
		(net "FPGA_OUT_MAC_PPS_IN1P")
	)
	(arc
		(start 119.751602 -37.108638)
		(mid 119.859251 -36.848749)
		(end 120.11914 -36.7411)
		(width 0.0889)
		(layer "In7.Cu")
		(net "FPGA_OUT_MAC_PPS_IN1P")
	)
	(arc
		(start 119.662702 -37.323268)
		(mid 119.725564 -37.29723)
		(end 119.751602 -37.234368)
		(width 0.0889)
		(layer "In7.Cu")
		(net "FPGA_OUT_MAC_PPS_IN1P")
	)
	(arc
		(start 122.97156 -30.38856)
		(mid 122.910005 -30.35627)
		(end 122.841004 -30.364684)
		(width 0.11684)
		(layer "In7.Cu")
		(net "FPGA_OUT_MAC_PPS_IN1P")
	)
	(arc
		(start 122.51309 -30.03677)
		(mid 122.521513 -29.967767)
		(end 122.489214 -29.906214)
		(width 0.11684)
		(layer "In7.Cu")
		(net "FPGA_OUT_MAC_PPS_IN1P")
	)
	(arc
		(start 122.53722 -30.167326)
		(mid 122.5048 -30.105803)
		(end 122.51309 -30.03677)
		(width 0.11684)
		(layer "In7.Cu")
		(net "FPGA_OUT_MAC_PPS_IN1P")
	)
	(arc
		(start 91.263216 -24.7396)
		(mid 90.745898 -24.842461)
		(end 90.307414 -25.135586)
		(width 0.11684)
		(layer "In7.Cu")
		(net "FPGA_OUT_MAC_PPS_IN1P")
	)
	(arc
		(start 123.3805 -31.132018)
		(mid 123.318982 -30.822834)
		(end 123.143772 -30.560772)
		(width 0.11684)
		(layer "In7.Cu")
		(net "FPGA_OUT_MAC_PPS_IN1P")
	)
	(arc
		(start 120.381268 -27.798268)
		(mid 120.322848 -27.77407)
		(end 120.264428 -27.798268)
		(width 0.11684)
		(layer "In7.Cu")
		(net "FPGA_OUT_MAC_PPS_IN1P")
	)
	(arc
		(start 89.874344 -25.568656)
		(mid 89.846725 -25.609896)
		(end 89.837006 -25.658572)
		(width 0.11684)
		(layer "In7.Cu")
		(net "FPGA_OUT_MAC_PPS_IN1P")
	)
	(arc
		(start 119.93372 -27.5844)
		(mid 119.909522 -27.52598)
		(end 119.93372 -27.46756)
		(width 0.11684)
		(layer "In7.Cu")
		(net "FPGA_OUT_MAC_PPS_IN1P")
	)
	(arc
		(start 123.343162 -35.084766)
		(mid 123.370781 -35.043526)
		(end 123.3805 -34.99485)
		(width 0.11684)
		(layer "In7.Cu")
		(net "FPGA_OUT_MAC_PPS_IN1P")
	)
	(arc
		(start 122.715782 -35.606482)
		(mid 122.693898 -35.55365)
		(end 122.715782 -35.500818)
		(width 0.11684)
		(layer "In7.Cu")
		(net "FPGA_OUT_MAC_PPS_IN1P")
	)
	(arc
		(start 119.93372 -27.46756)
		(mid 119.957918 -27.40914)
		(end 119.93372 -27.35072)
		(width 0.11684)
		(layer "In7.Cu")
		(net "FPGA_OUT_MAC_PPS_IN1P")
	)
	(arc
		(start 93.504004 -24.8158)
		(mid 93.481686 -24.869682)
		(end 93.427804 -24.892)
		(width 0.11684)
		(layer "In7.Cu")
		(net "FPGA_OUT_MAC_PPS_IN1P")
	)
	(arc
		(start 119.72925 -27.14625)
		(mid 117.063485 -25.365043)
		(end 113.919 -24.7396)
		(width 0.11684)
		(layer "In7.Cu")
		(net "FPGA_OUT_MAC_PPS_IN1P")
	)
	(arc
		(start 123.04649 -35.275774)
		(mid 123.099322 -35.297658)
		(end 123.152154 -35.275774)
		(width 0.11684)
		(layer "In7.Cu")
		(net "FPGA_OUT_MAC_PPS_IN1P")
	)
	(arc
		(start 93.112844 -24.892)
		(mid 93.058962 -24.869682)
		(end 93.036644 -24.8158)
		(width 0.11684)
		(layer "In7.Cu")
		(net "FPGA_OUT_MAC_PPS_IN1P")
	)
	(arc
		(start 122.940826 -35.275774)
		(mid 122.993658 -35.25389)
		(end 123.04649 -35.275774)
		(width 0.11684)
		(layer "In7.Cu")
		(net "FPGA_OUT_MAC_PPS_IN1P")
	)
	(arc
		(start 120.264428 -27.798268)
		(mid 120.206008 -27.822466)
		(end 120.147588 -27.798268)
		(width 0.11684)
		(layer "In7.Cu")
		(net "FPGA_OUT_MAC_PPS_IN1P")
	)
	(arc
		(start 93.036644 -24.8158)
		(mid 93.014326 -24.761918)
		(end 92.960444 -24.7396)
		(width 0.11684)
		(layer "In7.Cu")
		(net "FPGA_OUT_MAC_PPS_IN1P")
	)
	(arc
		(start 93.580204 -24.7396)
		(mid 93.526322 -24.761918)
		(end 93.504004 -24.8158)
		(width 0.11684)
		(layer "In7.Cu")
		(net "FPGA_OUT_MAC_PPS_IN1P")
	)
	(arc
		(start 89.837006 -26.183844)
		(mid 89.86711 -26.335187)
		(end 89.95283 -26.463498)
		(width 0.11684)
		(layer "In7.Cu")
		(net "FPGA_OUT_MAC_PPS_IN1P")
	)
	(arc
		(start 122.841004 -30.364684)
		(mid 122.771979 -30.372931)
		(end 122.710448 -30.340554)
		(width 0.11684)
		(layer "In7.Cu")
		(net "FPGA_OUT_MAC_PPS_IN1P")
	)
	(arc
		(start 121.69775 -36.6776)
		(mid 121.746434 -36.667898)
		(end 121.787666 -36.640262)
		(width 0.11684)
		(layer "In7.Cu")
		(net "FPGA_OUT_MAC_PPS_IN1P")
	)
	(segment
		(start 82.7786 -52.4256)
		(end 82.872072 -52.519326)
		(width 0.09906)
		(layer "F.Cu")
		(net "FPGA_OUT_MAC_PPS_IN1N")
	)
	(segment
		(start 89.384886 -26.708608)
		(end 89.271856 -26.595578)
		(width 0.09906)
		(layer "F.Cu")
		(net "FPGA_OUT_MAC_PPS_IN1N")
	)
	(segment
		(start 89.4842 -29.767276)
		(end 89.4842 -26.948384)
		(width 0.09906)
		(layer "F.Cu")
		(net "FPGA_OUT_MAC_PPS_IN1N")
	)
	(segment
		(start 82.217768 -52.7812)
		(end 82.196432 -52.7812)
		(width 0.09906)
		(layer "F.Cu")
		(net "FPGA_OUT_MAC_PPS_IN1N")
	)
	(segment
		(start 85.217 -52.1716)
		(end 85.217 -34.622232)
		(width 0.09906)
		(layer "F.Cu")
		(net "FPGA_OUT_MAC_PPS_IN1N")
	)
	(segment
		(start 85.595714 -33.708086)
		(end 89.44737 -29.85643)
		(width 0.09906)
		(layer "F.Cu")
		(net "FPGA_OUT_MAC_PPS_IN1N")
	)
	(segment
		(start 81.845912 -52.635912)
		(end 81.534 -52.324)
		(width 0.09906)
		(layer "F.Cu")
		(net "FPGA_OUT_MAC_PPS_IN1N")
	)
	(segment
		(start 82.7786 -52.4256)
		(end 82.568288 -52.635912)
		(width 0.09906)
		(layer "F.Cu")
		(net "FPGA_OUT_MAC_PPS_IN1N")
	)
	(segment
		(start 119.847106 -37.82314)
		(end 120.346978 -37.323268)
		(width 0.09906)
		(layer "F.Cu")
		(net "FPGA_OUT_MAC_PPS_IN1N")
	)
	(segment
		(start 83.566 -52.8066)
		(end 84.582 -52.8066)
		(width 0.09906)
		(layer "F.Cu")
		(net "FPGA_OUT_MAC_PPS_IN1N")
	)
	(arc
		(start 89.4842 -26.948384)
		(mid 89.458388 -26.81862)
		(end 89.384886 -26.708608)
		(width 0.09906)
		(layer "F.Cu")
		(net "FPGA_OUT_MAC_PPS_IN1N")
	)
	(arc
		(start 82.196432 -52.7812)
		(mid 82.006709 -52.743444)
		(end 81.845912 -52.635912)
		(width 0.09906)
		(layer "F.Cu")
		(net "FPGA_OUT_MAC_PPS_IN1N")
	)
	(arc
		(start 84.582 -52.8066)
		(mid 85.031013 -52.620613)
		(end 85.217 -52.1716)
		(width 0.09906)
		(layer "F.Cu")
		(net "FPGA_OUT_MAC_PPS_IN1N")
	)
	(arc
		(start 89.44737 -29.85643)
		(mid 89.474648 -29.815512)
		(end 89.4842 -29.767276)
		(width 0.09906)
		(layer "F.Cu")
		(net "FPGA_OUT_MAC_PPS_IN1N")
	)
	(arc
		(start 82.568288 -52.635912)
		(mid 82.407482 -52.743422)
		(end 82.217768 -52.7812)
		(width 0.09906)
		(layer "F.Cu")
		(net "FPGA_OUT_MAC_PPS_IN1N")
	)
	(arc
		(start 85.217 -34.622232)
		(mid 85.315428 -34.12749)
		(end 85.595714 -33.708086)
		(width 0.09906)
		(layer "F.Cu")
		(net "FPGA_OUT_MAC_PPS_IN1N")
	)
	(arc
		(start 82.872072 -52.519326)
		(mid 83.190464 -52.731976)
		(end 83.566 -52.8066)
		(width 0.09906)
		(layer "F.Cu")
		(net "FPGA_OUT_MAC_PPS_IN1N")
	)
	(segment
		(start 90.082878 -24.91105)
		(end 89.649808 -25.34412)
		(width 0.11684)
		(layer "In7.Cu")
		(net "FPGA_OUT_MAC_PPS_IN1N")
	)
	(segment
		(start 123.698 -34.99485)
		(end 123.698 -31.132018)
		(width 0.11684)
		(layer "In7.Cu")
		(net "FPGA_OUT_MAC_PPS_IN1N")
	)
	(segment
		(start 123.368308 -30.336236)
		(end 119.953786 -26.921714)
		(width 0.11684)
		(layer "In7.Cu")
		(net "FPGA_OUT_MAC_PPS_IN1N")
	)
	(segment
		(start 121.021094 -36.9316)
		(end 121.084594 -36.9951)
		(width 0.0889)
		(layer "In7.Cu")
		(net "FPGA_OUT_MAC_PPS_IN1N")
	)
	(segment
		(start 89.519506 -25.658572)
		(end 89.519506 -26.184352)
		(width 0.11684)
		(layer "In7.Cu")
		(net "FPGA_OUT_MAC_PPS_IN1N")
	)
	(segment
		(start 119.942102 -37.234368)
		(end 119.942102 -37.108638)
		(width 0.0889)
		(layer "In7.Cu")
		(net "FPGA_OUT_MAC_PPS_IN1N")
	)
	(segment
		(start 121.084594 -36.9951)
		(end 121.106692 -36.9951)
		(width 0.0889)
		(layer "In7.Cu")
		(net "FPGA_OUT_MAC_PPS_IN1N")
	)
	(segment
		(start 122.012202 -36.864798)
		(end 123.567698 -35.309302)
		(width 0.11684)
		(layer "In7.Cu")
		(net "FPGA_OUT_MAC_PPS_IN1N")
	)
	(segment
		(start 89.403936 -26.463498)
		(end 89.271856 -26.595578)
		(width 0.11684)
		(layer "In7.Cu")
		(net "FPGA_OUT_MAC_PPS_IN1N")
	)
	(segment
		(start 113.918746 -24.4221)
		(end 91.262962 -24.4221)
		(width 0.11684)
		(layer "In7.Cu")
		(net "FPGA_OUT_MAC_PPS_IN1N")
	)
	(segment
		(start 120.346978 -37.323268)
		(end 120.031002 -37.323268)
		(width 0.0889)
		(layer "In7.Cu")
		(net "FPGA_OUT_MAC_PPS_IN1N")
	)
	(segment
		(start 120.11914 -36.9316)
		(end 121.021094 -36.9316)
		(width 0.0889)
		(layer "In7.Cu")
		(net "FPGA_OUT_MAC_PPS_IN1N")
	)
	(segment
		(start 121.106692 -36.9951)
		(end 121.69775 -36.9951)
		(width 0.11684)
		(layer "In7.Cu")
		(net "FPGA_OUT_MAC_PPS_IN1N")
	)
	(arc
		(start 89.519506 -26.184352)
		(mid 89.508156 -26.278355)
		(end 89.474802 -26.366978)
		(width 0.11684)
		(layer "In7.Cu")
		(net "FPGA_OUT_MAC_PPS_IN1N")
	)
	(arc
		(start 91.262962 -24.4221)
		(mid 90.624279 -24.549178)
		(end 90.082878 -24.91105)
		(width 0.11684)
		(layer "In7.Cu")
		(net "FPGA_OUT_MAC_PPS_IN1N")
	)
	(arc
		(start 89.474802 -26.366978)
		(mid 89.443032 -26.417926)
		(end 89.403936 -26.463498)
		(width 0.11684)
		(layer "In7.Cu")
		(net "FPGA_OUT_MAC_PPS_IN1N")
	)
	(arc
		(start 120.031002 -37.323268)
		(mid 119.96814 -37.29723)
		(end 119.942102 -37.234368)
		(width 0.0889)
		(layer "In7.Cu")
		(net "FPGA_OUT_MAC_PPS_IN1N")
	)
	(arc
		(start 89.649808 -25.34412)
		(mid 89.553355 -25.488378)
		(end 89.519506 -25.658572)
		(width 0.11684)
		(layer "In7.Cu")
		(net "FPGA_OUT_MAC_PPS_IN1N")
	)
	(arc
		(start 123.567698 -35.309302)
		(mid 123.664151 -35.165044)
		(end 123.698 -34.99485)
		(width 0.11684)
		(layer "In7.Cu")
		(net "FPGA_OUT_MAC_PPS_IN1N")
	)
	(arc
		(start 119.942102 -37.108638)
		(mid 119.993955 -36.983453)
		(end 120.11914 -36.9316)
		(width 0.0889)
		(layer "In7.Cu")
		(net "FPGA_OUT_MAC_PPS_IN1N")
	)
	(arc
		(start 123.698 -31.132018)
		(mid 123.612313 -30.701332)
		(end 123.368308 -30.336236)
		(width 0.11684)
		(layer "In7.Cu")
		(net "FPGA_OUT_MAC_PPS_IN1N")
	)
	(arc
		(start 119.953786 -26.921714)
		(mid 117.184885 -25.071624)
		(end 113.918746 -24.4221)
		(width 0.11684)
		(layer "In7.Cu")
		(net "FPGA_OUT_MAC_PPS_IN1N")
	)
	(arc
		(start 121.69775 -36.9951)
		(mid 121.867936 -36.96123)
		(end 122.012202 -36.864798)
		(width 0.11684)
		(layer "In7.Cu")
		(net "FPGA_OUT_MAC_PPS_IN1N")
	)
	(segment
		(start 119.847106 -35.82289)
		(end 120.346978 -35.323018)
		(width 0.09906)
		(layer "F.Cu")
		(net "FPGA_OUT_MAC_PPS_IN0P")
	)
	(segment
		(start 84.561934 -33.598358)
		(end 87.230966 -30.929326)
		(width 0.09906)
		(layer "F.Cu")
		(net "FPGA_OUT_MAC_PPS_IN0P")
	)
	(segment
		(start 87.376 -30.578806)
		(end 87.376 -27.982926)
		(width 0.09906)
		(layer "F.Cu")
		(net "FPGA_OUT_MAC_PPS_IN0P")
	)
	(segment
		(start 84.532724 -49.985676)
		(end 84.532724 -33.668716)
		(width 0.09906)
		(layer "F.Cu")
		(net "FPGA_OUT_MAC_PPS_IN0P")
	)
	(segment
		(start 87.496142 -27.692858)
		(end 87.629746 -27.559254)
		(width 0.09906)
		(layer "F.Cu")
		(net "FPGA_OUT_MAC_PPS_IN0P")
	)
	(segment
		(start 83.53552 -50.6984)
		(end 83.82 -50.6984)
		(width 0.09906)
		(layer "F.Cu")
		(net "FPGA_OUT_MAC_PPS_IN0P")
	)
	(segment
		(start 81.932018 -50.782982)
		(end 81.534 -51.181)
		(width 0.09906)
		(layer "F.Cu")
		(net "FPGA_OUT_MAC_PPS_IN0P")
	)
	(segment
		(start 87.629746 -27.559254)
		(end 87.629746 -27.559)
		(width 0.09906)
		(layer "F.Cu")
		(net "FPGA_OUT_MAC_PPS_IN0P")
	)
	(segment
		(start 82.7786 -51.0794)
		(end 82.893916 -50.964338)
		(width 0.09906)
		(layer "F.Cu")
		(net "FPGA_OUT_MAC_PPS_IN0P")
	)
	(segment
		(start 82.7786 -51.0794)
		(end 82.482182 -50.782982)
		(width 0.09906)
		(layer "F.Cu")
		(net "FPGA_OUT_MAC_PPS_IN0P")
	)
	(segment
		(start 82.217006 -50.673)
		(end 82.197194 -50.673)
		(width 0.09906)
		(layer "F.Cu")
		(net "FPGA_OUT_MAC_PPS_IN0P")
	)
	(arc
		(start 87.230966 -30.929326)
		(mid 87.338339 -30.768491)
		(end 87.376 -30.578806)
		(width 0.09906)
		(layer "F.Cu")
		(net "FPGA_OUT_MAC_PPS_IN0P")
	)
	(arc
		(start 84.532724 -33.668716)
		(mid 84.540333 -33.630642)
		(end 84.561934 -33.598358)
		(width 0.09906)
		(layer "F.Cu")
		(net "FPGA_OUT_MAC_PPS_IN0P")
	)
	(arc
		(start 82.893916 -50.964338)
		(mid 83.188271 -50.767563)
		(end 83.53552 -50.6984)
		(width 0.09906)
		(layer "F.Cu")
		(net "FPGA_OUT_MAC_PPS_IN0P")
	)
	(arc
		(start 83.82 -50.6984)
		(mid 84.323972 -50.489648)
		(end 84.532724 -49.985676)
		(width 0.09906)
		(layer "F.Cu")
		(net "FPGA_OUT_MAC_PPS_IN0P")
	)
	(arc
		(start 82.197194 -50.673)
		(mid 82.053681 -50.70164)
		(end 81.932018 -50.782982)
		(width 0.09906)
		(layer "F.Cu")
		(net "FPGA_OUT_MAC_PPS_IN0P")
	)
	(arc
		(start 87.376 -27.982926)
		(mid 87.407225 -27.825945)
		(end 87.496142 -27.692858)
		(width 0.09906)
		(layer "F.Cu")
		(net "FPGA_OUT_MAC_PPS_IN0P")
	)
	(arc
		(start 82.482182 -50.782982)
		(mid 82.360533 -50.701606)
		(end 82.217006 -50.673)
		(width 0.09906)
		(layer "F.Cu")
		(net "FPGA_OUT_MAC_PPS_IN0P")
	)
	(segment
		(start 120.346978 -35.323018)
		(end 120.535446 -35.13455)
		(width 0.11684)
		(layer "In7.Cu")
		(net "FPGA_OUT_MAC_PPS_IN0P")
	)
	(segment
		(start 98.425254 -26.220674)
		(end 98.009964 -26.635964)
		(width 0.11684)
		(layer "In7.Cu")
		(net "FPGA_OUT_MAC_PPS_IN0P")
	)
	(segment
		(start 121.329196 -34.810446)
		(end 121.494804 -34.644838)
		(width 0.11684)
		(layer "In7.Cu")
		(net "FPGA_OUT_MAC_PPS_IN0P")
	)
	(segment
		(start 97.62109 -26.797)
		(end 93.01099 -26.797)
		(width 0.11684)
		(layer "In7.Cu")
		(net "FPGA_OUT_MAC_PPS_IN0P")
	)
	(segment
		(start 121.494804 -32.272732)
		(end 115.921536 -26.699464)
		(width 0.11684)
		(layer "In7.Cu")
		(net "FPGA_OUT_MAC_PPS_IN0P")
	)
	(segment
		(start 120.904254 -34.981642)
		(end 120.915938 -34.981642)
		(width 0.11684)
		(layer "In7.Cu")
		(net "FPGA_OUT_MAC_PPS_IN0P")
	)
	(segment
		(start 92.597732 -26.968196)
		(end 91.25966 -28.306268)
		(width 0.11684)
		(layer "In7.Cu")
		(net "FPGA_OUT_MAC_PPS_IN0P")
	)
	(segment
		(start 91.070938 -28.3845)
		(end 87.5665 -28.3845)
		(width 0.11684)
		(layer "In7.Cu")
		(net "FPGA_OUT_MAC_PPS_IN0P")
	)
	(segment
		(start 87.629746 -27.559254)
		(end 87.629746 -27.559)
		(width 0.11684)
		(layer "In7.Cu")
		(net "FPGA_OUT_MAC_PPS_IN0P")
	)
	(segment
		(start 114.457988 -26.09342)
		(end 98.732594 -26.09342)
		(width 0.11684)
		(layer "In7.Cu")
		(net "FPGA_OUT_MAC_PPS_IN0P")
	)
	(segment
		(start 87.382096 -28.200096)
		(end 87.382096 -27.970734)
		(width 0.11684)
		(layer "In7.Cu")
		(net "FPGA_OUT_MAC_PPS_IN0P")
	)
	(segment
		(start 87.49792 -27.69108)
		(end 87.629746 -27.559254)
		(width 0.11684)
		(layer "In7.Cu")
		(net "FPGA_OUT_MAC_PPS_IN0P")
	)
	(segment
		(start 121.666 -34.23158)
		(end 121.666 -32.68599)
		(width 0.11684)
		(layer "In7.Cu")
		(net "FPGA_OUT_MAC_PPS_IN0P")
	)
	(arc
		(start 98.732594 -26.09342)
		(mid 98.566282 -26.126501)
		(end 98.425254 -26.220674)
		(width 0.11684)
		(layer "In7.Cu")
		(net "FPGA_OUT_MAC_PPS_IN0P")
	)
	(arc
		(start 91.25966 -28.306268)
		(mid 91.173088 -28.364177)
		(end 91.070938 -28.3845)
		(width 0.11684)
		(layer "In7.Cu")
		(net "FPGA_OUT_MAC_PPS_IN0P")
	)
	(arc
		(start 87.382096 -27.970734)
		(mid 87.4122 -27.819391)
		(end 87.49792 -27.69108)
		(width 0.11684)
		(layer "In7.Cu")
		(net "FPGA_OUT_MAC_PPS_IN0P")
	)
	(arc
		(start 115.921536 -26.699464)
		(mid 115.250053 -26.250853)
		(end 114.457988 -26.09342)
		(width 0.11684)
		(layer "In7.Cu")
		(net "FPGA_OUT_MAC_PPS_IN0P")
	)
	(arc
		(start 98.009964 -26.635964)
		(mid 97.831533 -26.755125)
		(end 97.62109 -26.797)
		(width 0.11684)
		(layer "In7.Cu")
		(net "FPGA_OUT_MAC_PPS_IN0P")
	)
	(arc
		(start 120.915938 -34.981642)
		(mid 121.139599 -34.937153)
		(end 121.329196 -34.810446)
		(width 0.11684)
		(layer "In7.Cu")
		(net "FPGA_OUT_MAC_PPS_IN0P")
	)
	(arc
		(start 121.494804 -34.644838)
		(mid 121.621494 -34.455234)
		(end 121.666 -34.23158)
		(width 0.11684)
		(layer "In7.Cu")
		(net "FPGA_OUT_MAC_PPS_IN0P")
	)
	(arc
		(start 93.01099 -26.797)
		(mid 92.787329 -26.841489)
		(end 92.597732 -26.968196)
		(width 0.11684)
		(layer "In7.Cu")
		(net "FPGA_OUT_MAC_PPS_IN0P")
	)
	(arc
		(start 87.5665 -28.3845)
		(mid 87.436107 -28.330489)
		(end 87.382096 -28.200096)
		(width 0.11684)
		(layer "In7.Cu")
		(net "FPGA_OUT_MAC_PPS_IN0P")
	)
	(arc
		(start 120.535446 -35.13455)
		(mid 120.704642 -35.021404)
		(end 120.904254 -34.981642)
		(width 0.11684)
		(layer "In7.Cu")
		(net "FPGA_OUT_MAC_PPS_IN0P")
	)
	(arc
		(start 121.666 -32.68599)
		(mid 121.621511 -32.462329)
		(end 121.494804 -32.272732)
		(width 0.11684)
		(layer "In7.Cu")
		(net "FPGA_OUT_MAC_PPS_IN0P")
	)
	(segment
		(start 87.0712 -29.567124)
		(end 87.0712 -27.98318)
		(width 0.09906)
		(layer "F.Cu")
		(net "FPGA_OUT_MAC_PPS_IN0N")
	)
	(segment
		(start 81.845912 -50.222912)
		(end 81.534 -49.911)
		(width 0.09906)
		(layer "F.Cu")
		(net "FPGA_OUT_MAC_PPS_IN0N")
	)
	(segment
		(start 84.346288 -33.382458)
		(end 84.66963 -33.059116)
		(width 0.09906)
		(layer "F.Cu")
		(net "FPGA_OUT_MAC_PPS_IN0N")
	)
	(segment
		(start 85.230208 -32.333946)
		(end 85.428328 -32.13608)
		(width 0.09906)
		(layer "F.Cu")
		(net "FPGA_OUT_MAC_PPS_IN0N")
	)
	(segment
		(start 85.510624 -32.13608)
		(end 85.510878 -32.136334)
		(width 0.09906)
		(layer "F.Cu")
		(net "FPGA_OUT_MAC_PPS_IN0N")
	)
	(segment
		(start 85.230462 -32.416496)
		(end 85.230208 -32.416242)
		(width 0.09906)
		(layer "F.Cu")
		(net "FPGA_OUT_MAC_PPS_IN0N")
	)
	(segment
		(start 86.95944 -29.963364)
		(end 86.95944 -29.678884)
		(width 0.09906)
		(layer "F.Cu")
		(net "FPGA_OUT_MAC_PPS_IN0N")
	)
	(segment
		(start 84.949792 -32.696404)
		(end 84.950046 -32.696658)
		(width 0.09906)
		(layer "F.Cu")
		(net "FPGA_OUT_MAC_PPS_IN0N")
	)
	(segment
		(start 82.217768 -50.3682)
		(end 82.196432 -50.3682)
		(width 0.09906)
		(layer "F.Cu")
		(net "FPGA_OUT_MAC_PPS_IN0N")
	)
	(segment
		(start 119.847106 -34.822892)
		(end 120.346978 -34.32302)
		(width 0.09906)
		(layer "F.Cu")
		(net "FPGA_OUT_MAC_PPS_IN0N")
	)
	(segment
		(start 84.66963 -32.97682)
		(end 84.669376 -32.976566)
		(width 0.09906)
		(layer "F.Cu")
		(net "FPGA_OUT_MAC_PPS_IN0N")
	)
	(segment
		(start 85.593174 -32.136334)
		(end 87.01532 -30.71368)
		(width 0.09906)
		(layer "F.Cu")
		(net "FPGA_OUT_MAC_PPS_IN0N")
	)
	(segment
		(start 85.032342 -32.696658)
		(end 85.230462 -32.498792)
		(width 0.09906)
		(layer "F.Cu")
		(net "FPGA_OUT_MAC_PPS_IN0N")
	)
	(segment
		(start 83.535266 -50.3936)
		(end 83.82 -50.3936)
		(width 0.09906)
		(layer "F.Cu")
		(net "FPGA_OUT_MAC_PPS_IN0N")
	)
	(segment
		(start 86.951058 -27.693112)
		(end 86.816946 -27.559)
		(width 0.09906)
		(layer "F.Cu")
		(net "FPGA_OUT_MAC_PPS_IN0N")
	)
	(segment
		(start 82.7786 -50.0126)
		(end 82.893916 -50.127662)
		(width 0.09906)
		(layer "F.Cu")
		(net "FPGA_OUT_MAC_PPS_IN0N")
	)
	(segment
		(start 84.227924 -49.985676)
		(end 84.227924 -33.66897)
		(width 0.09906)
		(layer "F.Cu")
		(net "FPGA_OUT_MAC_PPS_IN0N")
	)
	(segment
		(start 84.669376 -32.89427)
		(end 84.867496 -32.696404)
		(width 0.09906)
		(layer "F.Cu")
		(net "FPGA_OUT_MAC_PPS_IN0N")
	)
	(segment
		(start 87.0712 -30.578806)
		(end 87.0712 -30.075124)
		(width 0.09906)
		(layer "F.Cu")
		(net "FPGA_OUT_MAC_PPS_IN0N")
	)
	(segment
		(start 82.7786 -50.0126)
		(end 82.568288 -50.222912)
		(width 0.09906)
		(layer "F.Cu")
		(net "FPGA_OUT_MAC_PPS_IN0N")
	)
	(arc
		(start 84.66963 -33.059116)
		(mid 84.686674 -33.017968)
		(end 84.66963 -32.97682)
		(width 0.09906)
		(layer "F.Cu")
		(net "FPGA_OUT_MAC_PPS_IN0N")
	)
	(arc
		(start 83.82 -50.3936)
		(mid 84.108446 -50.274122)
		(end 84.227924 -49.985676)
		(width 0.09906)
		(layer "F.Cu")
		(net "FPGA_OUT_MAC_PPS_IN0N")
	)
	(arc
		(start 84.227924 -33.66897)
		(mid 84.258539 -33.513912)
		(end 84.346288 -33.382458)
		(width 0.09906)
		(layer "F.Cu")
		(net "FPGA_OUT_MAC_PPS_IN0N")
	)
	(arc
		(start 87.01532 -29.623004)
		(mid 87.054833 -29.606637)
		(end 87.0712 -29.567124)
		(width 0.09906)
		(layer "F.Cu")
		(net "FPGA_OUT_MAC_PPS_IN0N")
	)
	(arc
		(start 82.568288 -50.222912)
		(mid 82.407482 -50.330422)
		(end 82.217768 -50.3682)
		(width 0.09906)
		(layer "F.Cu")
		(net "FPGA_OUT_MAC_PPS_IN0N")
	)
	(arc
		(start 85.230462 -32.498792)
		(mid 85.247506 -32.457644)
		(end 85.230462 -32.416496)
		(width 0.09906)
		(layer "F.Cu")
		(net "FPGA_OUT_MAC_PPS_IN0N")
	)
	(arc
		(start 85.230208 -32.416242)
		(mid 85.213164 -32.375094)
		(end 85.230208 -32.333946)
		(width 0.09906)
		(layer "F.Cu")
		(net "FPGA_OUT_MAC_PPS_IN0N")
	)
	(arc
		(start 87.0712 -27.98318)
		(mid 87.039975 -27.826199)
		(end 86.951058 -27.693112)
		(width 0.09906)
		(layer "F.Cu")
		(net "FPGA_OUT_MAC_PPS_IN0N")
	)
	(arc
		(start 84.950046 -32.696658)
		(mid 84.991194 -32.713702)
		(end 85.032342 -32.696658)
		(width 0.09906)
		(layer "F.Cu")
		(net "FPGA_OUT_MAC_PPS_IN0N")
	)
	(arc
		(start 84.867496 -32.696404)
		(mid 84.908644 -32.67936)
		(end 84.949792 -32.696404)
		(width 0.09906)
		(layer "F.Cu")
		(net "FPGA_OUT_MAC_PPS_IN0N")
	)
	(arc
		(start 84.669376 -32.976566)
		(mid 84.652332 -32.935418)
		(end 84.669376 -32.89427)
		(width 0.09906)
		(layer "F.Cu")
		(net "FPGA_OUT_MAC_PPS_IN0N")
	)
	(arc
		(start 85.428328 -32.13608)
		(mid 85.469476 -32.119036)
		(end 85.510624 -32.13608)
		(width 0.09906)
		(layer "F.Cu")
		(net "FPGA_OUT_MAC_PPS_IN0N")
	)
	(arc
		(start 87.0712 -30.075124)
		(mid 87.054833 -30.035611)
		(end 87.01532 -30.019244)
		(width 0.09906)
		(layer "F.Cu")
		(net "FPGA_OUT_MAC_PPS_IN0N")
	)
	(arc
		(start 82.893916 -50.127662)
		(mid 83.188154 -50.324388)
		(end 83.535266 -50.3936)
		(width 0.09906)
		(layer "F.Cu")
		(net "FPGA_OUT_MAC_PPS_IN0N")
	)
	(arc
		(start 85.510878 -32.136334)
		(mid 85.552026 -32.153378)
		(end 85.593174 -32.136334)
		(width 0.09906)
		(layer "F.Cu")
		(net "FPGA_OUT_MAC_PPS_IN0N")
	)
	(arc
		(start 82.196432 -50.3682)
		(mid 82.006709 -50.330444)
		(end 81.845912 -50.222912)
		(width 0.09906)
		(layer "F.Cu")
		(net "FPGA_OUT_MAC_PPS_IN0N")
	)
	(arc
		(start 86.95944 -29.678884)
		(mid 86.975807 -29.639371)
		(end 87.01532 -29.623004)
		(width 0.09906)
		(layer "F.Cu")
		(net "FPGA_OUT_MAC_PPS_IN0N")
	)
	(arc
		(start 87.01532 -30.71368)
		(mid 87.056667 -30.651799)
		(end 87.0712 -30.578806)
		(width 0.09906)
		(layer "F.Cu")
		(net "FPGA_OUT_MAC_PPS_IN0N")
	)
	(arc
		(start 87.01532 -30.019244)
		(mid 86.975807 -30.002877)
		(end 86.95944 -29.963364)
		(width 0.09906)
		(layer "F.Cu")
		(net "FPGA_OUT_MAC_PPS_IN0N")
	)
	(segment
		(start 121.10466 -34.58591)
		(end 121.270268 -34.420302)
		(width 0.11684)
		(layer "In7.Cu")
		(net "FPGA_OUT_MAC_PPS_IN0N")
	)
	(segment
		(start 97.62109 -27.1145)
		(end 95.112078 -27.1145)
		(width 0.11684)
		(layer "In7.Cu")
		(net "FPGA_OUT_MAC_PPS_IN0N")
	)
	(segment
		(start 120.84558 -34.664142)
		(end 120.915938 -34.664142)
		(width 0.11684)
		(layer "In7.Cu")
		(net "FPGA_OUT_MAC_PPS_IN0N")
	)
	(segment
		(start 91.070938 -28.702)
		(end 87.5665 -28.702)
		(width 0.11684)
		(layer "In7.Cu")
		(net "FPGA_OUT_MAC_PPS_IN0N")
	)
	(segment
		(start 86.949026 -27.69108)
		(end 86.816946 -27.559)
		(width 0.11684)
		(layer "In7.Cu")
		(net "FPGA_OUT_MAC_PPS_IN0N")
	)
	(segment
		(start 94.438978 -27.1145)
		(end 93.01099 -27.1145)
		(width 0.11684)
		(layer "In7.Cu")
		(net "FPGA_OUT_MAC_PPS_IN0N")
	)
	(segment
		(start 121.3485 -34.23158)
		(end 121.3485 -32.68599)
		(width 0.11684)
		(layer "In7.Cu")
		(net "FPGA_OUT_MAC_PPS_IN0N")
	)
	(segment
		(start 116.32438 -27.83078)
		(end 116.15928 -27.66568)
		(width 0.11684)
		(layer "In7.Cu")
		(net "FPGA_OUT_MAC_PPS_IN0N")
	)
	(segment
		(start 120.346978 -34.32302)
		(end 120.576594 -34.552636)
		(width 0.11684)
		(layer "In7.Cu")
		(net "FPGA_OUT_MAC_PPS_IN0N")
	)
	(segment
		(start 120.607836 -32.104076)
		(end 120.426988 -31.923228)
		(width 0.11684)
		(layer "In7.Cu")
		(net "FPGA_OUT_MAC_PPS_IN0N")
	)
	(segment
		(start 114.458242 -26.41092)
		(end 98.732594 -26.41092)
		(width 0.11684)
		(layer "In7.Cu")
		(net "FPGA_OUT_MAC_PPS_IN0N")
	)
	(segment
		(start 87.064596 -28.200096)
		(end 87.064596 -27.970226)
		(width 0.11684)
		(layer "In7.Cu")
		(net "FPGA_OUT_MAC_PPS_IN0N")
	)
	(segment
		(start 120.426988 -31.653988)
		(end 116.606574 -27.833574)
		(width 0.11684)
		(layer "In7.Cu")
		(net "FPGA_OUT_MAC_PPS_IN0N")
	)
	(segment
		(start 98.64979 -26.44521)
		(end 98.2345 -26.8605)
		(width 0.11684)
		(layer "In7.Cu")
		(net "FPGA_OUT_MAC_PPS_IN0N")
	)
	(segment
		(start 121.270268 -32.497268)
		(end 120.877076 -32.104076)
		(width 0.11684)
		(layer "In7.Cu")
		(net "FPGA_OUT_MAC_PPS_IN0N")
	)
	(segment
		(start 94.906338 -27.32024)
		(end 94.644718 -27.32024)
		(width 0.11684)
		(layer "In7.Cu")
		(net "FPGA_OUT_MAC_PPS_IN0N")
	)
	(segment
		(start 116.156486 -27.383486)
		(end 115.697 -26.924)
		(width 0.11684)
		(layer "In7.Cu")
		(net "FPGA_OUT_MAC_PPS_IN0N")
	)
	(segment
		(start 92.822268 -27.192732)
		(end 91.484196 -28.530804)
		(width 0.11684)
		(layer "In7.Cu")
		(net "FPGA_OUT_MAC_PPS_IN0N")
	)
	(arc
		(start 120.426988 -31.773368)
		(mid 120.451712 -31.713678)
		(end 120.426988 -31.653988)
		(width 0.11684)
		(layer "In7.Cu")
		(net "FPGA_OUT_MAC_PPS_IN0N")
	)
	(arc
		(start 95.112078 -27.1145)
		(mid 95.039338 -27.14463)
		(end 95.009208 -27.21737)
		(width 0.11684)
		(layer "In7.Cu")
		(net "FPGA_OUT_MAC_PPS_IN0N")
	)
	(arc
		(start 116.48821 -27.832304)
		(mid 116.406017 -27.864987)
		(end 116.32438 -27.83078)
		(width 0.11684)
		(layer "In7.Cu")
		(net "FPGA_OUT_MAC_PPS_IN0N")
	)
	(arc
		(start 120.915938 -34.664142)
		(mid 121.018083 -34.643806)
		(end 121.10466 -34.58591)
		(width 0.11684)
		(layer "In7.Cu")
		(net "FPGA_OUT_MAC_PPS_IN0N")
	)
	(arc
		(start 120.426988 -31.923228)
		(mid 120.395951 -31.848298)
		(end 120.426988 -31.773368)
		(width 0.11684)
		(layer "In7.Cu")
		(net "FPGA_OUT_MAC_PPS_IN0N")
	)
	(arc
		(start 95.009208 -27.21737)
		(mid 94.979078 -27.29011)
		(end 94.906338 -27.32024)
		(width 0.11684)
		(layer "In7.Cu")
		(net "FPGA_OUT_MAC_PPS_IN0N")
	)
	(arc
		(start 116.157756 -27.50185)
		(mid 116.181224 -27.442442)
		(end 116.156486 -27.383486)
		(width 0.11684)
		(layer "In7.Cu")
		(net "FPGA_OUT_MAC_PPS_IN0N")
	)
	(arc
		(start 120.757696 -32.104076)
		(mid 120.682766 -32.135113)
		(end 120.607836 -32.104076)
		(width 0.11684)
		(layer "In7.Cu")
		(net "FPGA_OUT_MAC_PPS_IN0N")
	)
	(arc
		(start 94.541848 -27.21737)
		(mid 94.511718 -27.14463)
		(end 94.438978 -27.1145)
		(width 0.11684)
		(layer "In7.Cu")
		(net "FPGA_OUT_MAC_PPS_IN0N")
	)
	(arc
		(start 87.5665 -28.702)
		(mid 87.2116 -28.554996)
		(end 87.064596 -28.200096)
		(width 0.11684)
		(layer "In7.Cu")
		(net "FPGA_OUT_MAC_PPS_IN0N")
	)
	(arc
		(start 116.606574 -27.833574)
		(mid 116.54762 -27.808676)
		(end 116.48821 -27.832304)
		(width 0.11684)
		(layer "In7.Cu")
		(net "FPGA_OUT_MAC_PPS_IN0N")
	)
	(arc
		(start 121.3485 -32.68599)
		(mid 121.328164 -32.583845)
		(end 121.270268 -32.497268)
		(width 0.11684)
		(layer "In7.Cu")
		(net "FPGA_OUT_MAC_PPS_IN0N")
	)
	(arc
		(start 120.576594 -34.552636)
		(mid 120.699992 -34.635151)
		(end 120.84558 -34.664142)
		(width 0.11684)
		(layer "In7.Cu")
		(net "FPGA_OUT_MAC_PPS_IN0N")
	)
	(arc
		(start 94.644718 -27.32024)
		(mid 94.571978 -27.29011)
		(end 94.541848 -27.21737)
		(width 0.11684)
		(layer "In7.Cu")
		(net "FPGA_OUT_MAC_PPS_IN0N")
	)
	(arc
		(start 115.697 -26.924)
		(mid 115.128667 -26.544189)
		(end 114.458242 -26.41092)
		(width 0.11684)
		(layer "In7.Cu")
		(net "FPGA_OUT_MAC_PPS_IN0N")
	)
	(arc
		(start 98.732594 -26.41092)
		(mid 98.687784 -26.419833)
		(end 98.64979 -26.44521)
		(width 0.11684)
		(layer "In7.Cu")
		(net "FPGA_OUT_MAC_PPS_IN0N")
	)
	(arc
		(start 116.15928 -27.66568)
		(mid 116.124838 -27.584045)
		(end 116.157756 -27.50185)
		(width 0.11684)
		(layer "In7.Cu")
		(net "FPGA_OUT_MAC_PPS_IN0N")
	)
	(arc
		(start 98.2345 -26.8605)
		(mid 97.953051 -27.048495)
		(end 97.62109 -27.1145)
		(width 0.11684)
		(layer "In7.Cu")
		(net "FPGA_OUT_MAC_PPS_IN0N")
	)
	(arc
		(start 87.064596 -27.970226)
		(mid 87.034565 -27.81916)
		(end 86.949026 -27.69108)
		(width 0.11684)
		(layer "In7.Cu")
		(net "FPGA_OUT_MAC_PPS_IN0N")
	)
	(arc
		(start 121.270268 -34.420302)
		(mid 121.328177 -34.33373)
		(end 121.3485 -34.23158)
		(width 0.11684)
		(layer "In7.Cu")
		(net "FPGA_OUT_MAC_PPS_IN0N")
	)
	(arc
		(start 120.877076 -32.104076)
		(mid 120.817386 -32.079352)
		(end 120.757696 -32.104076)
		(width 0.11684)
		(layer "In7.Cu")
		(net "FPGA_OUT_MAC_PPS_IN0N")
	)
	(arc
		(start 93.01099 -27.1145)
		(mid 92.908845 -27.134836)
		(end 92.822268 -27.192732)
		(width 0.11684)
		(layer "In7.Cu")
		(net "FPGA_OUT_MAC_PPS_IN0N")
	)
	(arc
		(start 91.484196 -28.530804)
		(mid 91.294592 -28.657494)
		(end 91.070938 -28.702)
		(width 0.11684)
		(layer "In7.Cu")
		(net "FPGA_OUT_MAC_PPS_IN0N")
	)
	(segment
		(start 115.847114 -47.82312)
		(end 116.346986 -48.322992)
		(width 0.11938)
		(layer "F.Cu")
		(net "FPGA_OUT_MACUSBPOWER_EN")
	)
	(via
		(at 63.372746 -51.816)
		(size 0.762)
		(drill 0.381)
		(layers "F.Cu" "B.Cu")
		(net "FPGA_OUT_MACUSBPOWER_EN")
	)
	(via
		(at 116.346986 -48.322992)
		(size 0.4572)
		(drill 0.2032)
		(layers "F.Cu" "B.Cu")
		(net "FPGA_OUT_MACUSBPOWER_EN")
	)
	(via
		(at 87.503 -46.101)
		(size 0.508)
		(drill 0.254)
		(layers "F.Cu" "B.Cu")
		(net "FPGA_OUT_MACUSBPOWER_EN")
	)
	(segment
		(start 68.267326 -44.38142)
		(end 73.08342 -44.38142)
		(width 0.11938)
		(layer "B.Cu")
		(net "FPGA_OUT_MACUSBPOWER_EN")
	)
	(segment
		(start 63.373 -56.515)
		(end 63.6016 -56.2864)
		(width 0.11938)
		(layer "B.Cu")
		(net "FPGA_OUT_MACUSBPOWER_EN")
	)
	(segment
		(start 62.625986 -52.56276)
		(end 63.372746 -51.816)
		(width 0.11938)
		(layer "B.Cu")
		(net "FPGA_OUT_MACUSBPOWER_EN")
	)
	(segment
		(start 62.625986 -55.7022)
		(end 62.625986 -56.275986)
		(width 0.11938)
		(layer "B.Cu")
		(net "FPGA_OUT_MACUSBPOWER_EN")
	)
	(segment
		(start 74.295 -45.593)
		(end 86.995 -45.593)
		(width 0.11938)
		(layer "B.Cu")
		(net "FPGA_OUT_MACUSBPOWER_EN")
	)
	(segment
		(start 63.6016 -56.2864)
		(end 64.516 -56.2864)
		(width 0.11938)
		(layer "B.Cu")
		(net "FPGA_OUT_MACUSBPOWER_EN")
	)
	(segment
		(start 62.865 -56.515)
		(end 63.373 -56.515)
		(width 0.11938)
		(layer "B.Cu")
		(net "FPGA_OUT_MACUSBPOWER_EN")
	)
	(segment
		(start 86.995 -45.593)
		(end 87.503 -46.101)
		(width 0.11938)
		(layer "B.Cu")
		(net "FPGA_OUT_MACUSBPOWER_EN")
	)
	(segment
		(start 64.516 -57.5056)
		(end 64.516 -56.2864)
		(width 0.11938)
		(layer "B.Cu")
		(net "FPGA_OUT_MACUSBPOWER_EN")
	)
	(segment
		(start 62.625986 -56.275986)
		(end 62.865 -56.515)
		(width 0.11938)
		(layer "B.Cu")
		(net "FPGA_OUT_MACUSBPOWER_EN")
	)
	(segment
		(start 63.372746 -49.276)
		(end 68.267326 -44.38142)
		(width 0.11938)
		(layer "B.Cu")
		(net "FPGA_OUT_MACUSBPOWER_EN")
	)
	(segment
		(start 73.08342 -44.38142)
		(end 74.295 -45.593)
		(width 0.11938)
		(layer "B.Cu")
		(net "FPGA_OUT_MACUSBPOWER_EN")
	)
	(segment
		(start 62.625986 -55.7022)
		(end 62.625986 -52.56276)
		(width 0.11938)
		(layer "B.Cu")
		(net "FPGA_OUT_MACUSBPOWER_EN")
	)
	(segment
		(start 63.372746 -51.816)
		(end 63.372746 -49.276)
		(width 0.11938)
		(layer "B.Cu")
		(net "FPGA_OUT_MACUSBPOWER_EN")
	)
	(segment
		(start 102.183946 -36.71697)
		(end 101.74097 -36.273994)
		(width 0.127)
		(layer "In2.Cu")
		(net "FPGA_OUT_MACUSBPOWER_EN")
	)
	(segment
		(start 109.728 -46.043342)
		(end 109.093 -45.408342)
		(width 0.127)
		(layer "In2.Cu")
		(net "FPGA_OUT_MACUSBPOWER_EN")
	)
	(segment
		(start 109.093 -45.408342)
		(end 109.093 -40.511984)
		(width 0.127)
		(layer "In2.Cu")
		(net "FPGA_OUT_MACUSBPOWER_EN")
	)
	(segment
		(start 105.344976 -39.878)
		(end 104.740964 -39.273988)
		(width 0.127)
		(layer "In2.Cu")
		(net "FPGA_OUT_MACUSBPOWER_EN")
	)
	(segment
		(start 109.093 -40.511984)
		(end 108.459016 -39.878)
		(width 0.127)
		(layer "In2.Cu")
		(net "FPGA_OUT_MACUSBPOWER_EN")
	)
	(segment
		(start 101.74097 -36.273994)
		(end 101.74097 -36.159948)
		(width 0.127)
		(layer "In2.Cu")
		(net "FPGA_OUT_MACUSBPOWER_EN")
	)
	(segment
		(start 98.141028 -35.716718)
		(end 97.5614 -36.296346)
		(width 0.127)
		(layer "In2.Cu")
		(net "FPGA_OUT_MACUSBPOWER_EN")
	)
	(segment
		(start 89.789 -46.101)
		(end 87.503 -46.101)
		(width 0.127)
		(layer "In2.Cu")
		(net "FPGA_OUT_MACUSBPOWER_EN")
	)
	(segment
		(start 93.0275 -45.4279)
		(end 90.4621 -45.4279)
		(width 0.127)
		(layer "In2.Cu")
		(net "FPGA_OUT_MACUSBPOWER_EN")
	)
	(segment
		(start 97.5614 -36.296346)
		(end 97.5614 -40.894)
		(width 0.127)
		(layer "In2.Cu")
		(net "FPGA_OUT_MACUSBPOWER_EN")
	)
	(segment
		(start 110.109254 -47.879)
		(end 109.728 -47.497746)
		(width 0.127)
		(layer "In2.Cu")
		(net "FPGA_OUT_MACUSBPOWER_EN")
	)
	(segment
		(start 116.346986 -48.322992)
		(end 115.902994 -47.879)
		(width 0.127)
		(layer "In2.Cu")
		(net "FPGA_OUT_MACUSBPOWER_EN")
	)
	(segment
		(start 101.29774 -35.716718)
		(end 98.141028 -35.716718)
		(width 0.127)
		(layer "In2.Cu")
		(net "FPGA_OUT_MACUSBPOWER_EN")
	)
	(segment
		(start 101.74097 -36.159948)
		(end 101.29774 -35.716718)
		(width 0.127)
		(layer "In2.Cu")
		(net "FPGA_OUT_MACUSBPOWER_EN")
	)
	(segment
		(start 104.740964 -39.273988)
		(end 104.740964 -38.142164)
		(width 0.127)
		(layer "In2.Cu")
		(net "FPGA_OUT_MACUSBPOWER_EN")
	)
	(segment
		(start 108.459016 -39.878)
		(end 105.344976 -39.878)
		(width 0.127)
		(layer "In2.Cu")
		(net "FPGA_OUT_MACUSBPOWER_EN")
	)
	(segment
		(start 102.297992 -36.71697)
		(end 102.183946 -36.71697)
		(width 0.127)
		(layer "In2.Cu")
		(net "FPGA_OUT_MACUSBPOWER_EN")
	)
	(segment
		(start 97.5614 -40.894)
		(end 93.0275 -45.4279)
		(width 0.127)
		(layer "In2.Cu")
		(net "FPGA_OUT_MACUSBPOWER_EN")
	)
	(segment
		(start 115.902994 -47.879)
		(end 110.109254 -47.879)
		(width 0.127)
		(layer "In2.Cu")
		(net "FPGA_OUT_MACUSBPOWER_EN")
	)
	(segment
		(start 104.483662 -37.884862)
		(end 103.351838 -37.884862)
		(width 0.127)
		(layer "In2.Cu")
		(net "FPGA_OUT_MACUSBPOWER_EN")
	)
	(segment
		(start 102.953566 -37.372544)
		(end 102.297992 -36.71697)
		(width 0.127)
		(layer "In2.Cu")
		(net "FPGA_OUT_MACUSBPOWER_EN")
	)
	(segment
		(start 102.953566 -37.48659)
		(end 102.953566 -37.372544)
		(width 0.127)
		(layer "In2.Cu")
		(net "FPGA_OUT_MACUSBPOWER_EN")
	)
	(segment
		(start 109.728 -47.497746)
		(end 109.728 -46.043342)
		(width 0.127)
		(layer "In2.Cu")
		(net "FPGA_OUT_MACUSBPOWER_EN")
	)
	(segment
		(start 104.740964 -38.142164)
		(end 104.483662 -37.884862)
		(width 0.127)
		(layer "In2.Cu")
		(net "FPGA_OUT_MACUSBPOWER_EN")
	)
	(segment
		(start 103.351838 -37.884862)
		(end 102.953566 -37.48659)
		(width 0.127)
		(layer "In2.Cu")
		(net "FPGA_OUT_MACUSBPOWER_EN")
	)
	(segment
		(start 90.4621 -45.4279)
		(end 89.789 -46.101)
		(width 0.127)
		(layer "In2.Cu")
		(net "FPGA_OUT_MACUSBPOWER_EN")
	)
	(segment
		(start 121.539 -87.884)
		(end 121.539 -89.0016)
		(width 0.11938)
		(layer "F.Cu")
		(net "FPGA_OUT_GPS_RST_N")
	)
	(segment
		(start 117.84711 -48.823118)
		(end 118.346982 -49.32299)
		(width 0.11938)
		(layer "F.Cu")
		(net "FPGA_OUT_GPS_RST_N")
	)
	(via
		(at 118.346982 -49.32299)
		(size 0.4572)
		(drill 0.2032)
		(layers "F.Cu" "B.Cu")
		(net "FPGA_OUT_GPS_RST_N")
	)
	(via
		(at 121.539 -87.884)
		(size 0.508)
		(drill 0.254)
		(layers "F.Cu" "B.Cu")
		(net "FPGA_OUT_GPS_RST_N")
	)
	(segment
		(start 118.872 -50.517806)
		(end 118.872 -49.848008)
		(width 0.127)
		(layer "In7.Cu")
		(net "FPGA_OUT_GPS_RST_N")
	)
	(segment
		(start 122.682 -57.5183)
		(end 122.682 -54.70906)
		(width 0.127)
		(layer "In7.Cu")
		(net "FPGA_OUT_GPS_RST_N")
	)
	(segment
		(start 123.1265 -53.68544)
		(end 120.30456 -50.8635)
		(width 0.127)
		(layer "In7.Cu")
		(net "FPGA_OUT_GPS_RST_N")
	)
	(segment
		(start 121.2088 -75.108054)
		(end 125.857 -70.459854)
		(width 0.127)
		(layer "In7.Cu")
		(net "FPGA_OUT_GPS_RST_N")
	)
	(segment
		(start 118.872 -49.848008)
		(end 118.346982 -49.32299)
		(width 0.127)
		(layer "In7.Cu")
		(net "FPGA_OUT_GPS_RST_N")
	)
	(segment
		(start 125.6157 -60.452)
		(end 122.682 -57.5183)
		(width 0.127)
		(layer "In7.Cu")
		(net "FPGA_OUT_GPS_RST_N")
	)
	(segment
		(start 125.857 -65.913)
		(end 125.6157 -65.6717)
		(width 0.127)
		(layer "In7.Cu")
		(net "FPGA_OUT_GPS_RST_N")
	)
	(segment
		(start 125.857 -70.459854)
		(end 125.857 -65.913)
		(width 0.127)
		(layer "In7.Cu")
		(net "FPGA_OUT_GPS_RST_N")
	)
	(segment
		(start 120.30456 -50.8635)
		(end 119.217694 -50.8635)
		(width 0.127)
		(layer "In7.Cu")
		(net "FPGA_OUT_GPS_RST_N")
	)
	(segment
		(start 125.6157 -65.6717)
		(end 125.6157 -60.452)
		(width 0.127)
		(layer "In7.Cu")
		(net "FPGA_OUT_GPS_RST_N")
	)
	(segment
		(start 121.2088 -87.5538)
		(end 121.2088 -75.108054)
		(width 0.127)
		(layer "In7.Cu")
		(net "FPGA_OUT_GPS_RST_N")
	)
	(segment
		(start 123.1265 -54.26456)
		(end 123.1265 -53.68544)
		(width 0.127)
		(layer "In7.Cu")
		(net "FPGA_OUT_GPS_RST_N")
	)
	(segment
		(start 122.682 -54.70906)
		(end 123.1265 -54.26456)
		(width 0.127)
		(layer "In7.Cu")
		(net "FPGA_OUT_GPS_RST_N")
	)
	(segment
		(start 121.539 -87.884)
		(end 121.2088 -87.5538)
		(width 0.127)
		(layer "In7.Cu")
		(net "FPGA_OUT_GPS_RST_N")
	)
	(segment
		(start 119.217694 -50.8635)
		(end 118.872 -50.517806)
		(width 0.127)
		(layer "In7.Cu")
		(net "FPGA_OUT_GPS_RST_N")
	)
	(segment
		(start 99.846892 -41.823132)
		(end 99.34702 -41.32326)
		(width 0.381)
		(layer "F.Cu")
		(net "FPGA_MGTAVTT")
	)
	(segment
		(start 100.84689 -36.823142)
		(end 100.347018 -36.32327)
		(width 0.381)
		(layer "F.Cu")
		(net "FPGA_MGTAVTT")
	)
	(segment
		(start 99.846892 -43.823128)
		(end 99.34702 -43.323256)
		(width 0.381)
		(layer "F.Cu")
		(net "FPGA_MGTAVTT")
	)
	(segment
		(start 99.846892 -39.823136)
		(end 99.34702 -39.323264)
		(width 0.381)
		(layer "F.Cu")
		(net "FPGA_MGTAVTT")
	)
	(segment
		(start 99.846892 -37.82314)
		(end 99.34702 -37.323268)
		(width 0.381)
		(layer "F.Cu")
		(net "FPGA_MGTAVTT")
	)
	(segment
		(start 100.84689 -40.823134)
		(end 100.347018 -40.323262)
		(width 0.381)
		(layer "F.Cu")
		(net "FPGA_MGTAVTT")
	)
	(via
		(at 97.028 -36.068)
		(size 0.508)
		(drill 0.254)
		(layers "F.Cu" "B.Cu")
		(net "FPGA_MGTAVTT")
	)
	(via
		(at 95.631 -35.814)
		(size 0.508)
		(drill 0.254)
		(layers "F.Cu" "B.Cu")
		(net "FPGA_MGTAVTT")
	)
	(via
		(at 99.34702 -43.323256)
		(size 0.4572)
		(drill 0.2032)
		(layers "F.Cu" "B.Cu")
		(net "FPGA_MGTAVTT")
	)
	(via
		(at 96.266 -35.814)
		(size 0.508)
		(drill 0.254)
		(layers "F.Cu" "B.Cu")
		(net "FPGA_MGTAVTT")
	)
	(via
		(at 94.996 -35.814)
		(size 0.508)
		(drill 0.254)
		(layers "F.Cu" "B.Cu")
		(net "FPGA_MGTAVTT")
	)
	(via
		(at 100.347018 -40.323262)
		(size 0.4572)
		(drill 0.2032)
		(layers "F.Cu" "B.Cu")
		(net "FPGA_MGTAVTT")
	)
	(via
		(at 99.34702 -41.32326)
		(size 0.4572)
		(drill 0.2032)
		(layers "F.Cu" "B.Cu")
		(net "FPGA_MGTAVTT")
	)
	(via
		(at 100.347018 -36.32327)
		(size 0.4572)
		(drill 0.2032)
		(layers "F.Cu" "B.Cu")
		(net "FPGA_MGTAVTT")
	)
	(via
		(at 99.34702 -39.323264)
		(size 0.4572)
		(drill 0.2032)
		(layers "F.Cu" "B.Cu")
		(net "FPGA_MGTAVTT")
	)
	(via
		(at 99.34702 -37.323268)
		(size 0.4572)
		(drill 0.2032)
		(layers "F.Cu" "B.Cu")
		(net "FPGA_MGTAVTT")
	)
	(via
		(at 93.3196 -44.2976)
		(size 0.508)
		(drill 0.254)
		(layers "F.Cu" "B.Cu")
		(net "FPGA_MGTAVTT")
	)
	(segment
		(start 99.846892 -37.82314)
		(end 99.34702 -37.323268)
		(width 0.381)
		(layer "B.Cu")
		(net "FPGA_MGTAVTT")
	)
	(segment
		(start 93.54566 -44.07154)
		(end 93.69806 -44.07154)
		(width 0.381)
		(layer "B.Cu")
		(net "FPGA_MGTAVTT")
	)
	(segment
		(start 98.71202 -43.958256)
		(end 98.71202 -44.323)
		(width 0.381)
		(layer "B.Cu")
		(net "FPGA_MGTAVTT")
	)
	(segment
		(start 100.84689 -36.823142)
		(end 100.347018 -36.32327)
		(width 0.381)
		(layer "B.Cu")
		(net "FPGA_MGTAVTT")
	)
	(segment
		(start 99.846892 -43.823128)
		(end 99.34702 -43.323256)
		(width 0.381)
		(layer "B.Cu")
		(net "FPGA_MGTAVTT")
	)
	(segment
		(start 93.69806 -44.07154)
		(end 94.0816 -43.688)
		(width 0.381)
		(layer "B.Cu")
		(net "FPGA_MGTAVTT")
	)
	(segment
		(start 99.846892 -41.823132)
		(end 99.34702 -41.32326)
		(width 0.381)
		(layer "B.Cu")
		(net "FPGA_MGTAVTT")
	)
	(segment
		(start 99.846892 -38.823392)
		(end 99.846892 -38.823138)
		(width 0.381)
		(layer "B.Cu")
		(net "FPGA_MGTAVTT")
	)
	(segment
		(start 99.34702 -43.323256)
		(end 98.71202 -43.958256)
		(width 0.381)
		(layer "B.Cu")
		(net "FPGA_MGTAVTT")
	)
	(segment
		(start 99.34702 -39.323264)
		(end 99.846892 -38.823392)
		(width 0.381)
		(layer "B.Cu")
		(net "FPGA_MGTAVTT")
	)
	(segment
		(start 93.3196 -44.2976)
		(end 93.54566 -44.07154)
		(width 0.381)
		(layer "B.Cu")
		(net "FPGA_MGTAVTT")
	)
	(segment
		(start 114.847116 -41.823132)
		(end 115.346988 -41.32326)
		(width 0.11938)
		(layer "F.Cu")
		(net "FPGA_M2")
	)
	(segment
		(start 125.9586 -35.179)
		(end 124.70638 -35.179)
		(width 0.11938)
		(layer "F.Cu")
		(net "FPGA_M2")
	)
	(segment
		(start 125.9586 -36.322)
		(end 125.9586 -35.179)
		(width 0.11938)
		(layer "F.Cu")
		(net "FPGA_M2")
	)
	(via
		(at 124.70638 -35.179)
		(size 0.4572)
		(drill 0.2032)
		(layers "F.Cu" "B.Cu")
		(net "FPGA_M2")
	)
	(via
		(at 115.346988 -41.32326)
		(size 0.4572)
		(drill 0.2032)
		(layers "F.Cu" "B.Cu")
		(net "FPGA_M2")
	)
	(segment
		(start 117.856 -39.116)
		(end 118.11 -38.862)
		(width 0.127)
		(layer "In2.Cu")
		(net "FPGA_M2")
	)
	(segment
		(start 115.824 -40.132)
		(end 116.078 -39.878)
		(width 0.127)
		(layer "In2.Cu")
		(net "FPGA_M2")
	)
	(segment
		(start 115.824 -40.894)
		(end 115.824 -40.132)
		(width 0.127)
		(layer "In2.Cu")
		(net "FPGA_M2")
	)
	(segment
		(start 116.078 -39.878)
		(end 117.5131 -39.878)
		(width 0.127)
		(layer "In2.Cu")
		(net "FPGA_M2")
	)
	(segment
		(start 117.5131 -39.878)
		(end 117.856 -39.5351)
		(width 0.127)
		(layer "In2.Cu")
		(net "FPGA_M2")
	)
	(segment
		(start 120.40108 -38.862)
		(end 120.78716 -38.47592)
		(width 0.127)
		(layer "In2.Cu")
		(net "FPGA_M2")
	)
	(segment
		(start 115.39474 -41.32326)
		(end 115.824 -40.894)
		(width 0.127)
		(layer "In2.Cu")
		(net "FPGA_M2")
	)
	(segment
		(start 118.11 -38.862)
		(end 120.40108 -38.862)
		(width 0.127)
		(layer "In2.Cu")
		(net "FPGA_M2")
	)
	(segment
		(start 120.78716 -38.47592)
		(end 120.78716 -37.77234)
		(width 0.127)
		(layer "In2.Cu")
		(net "FPGA_M2")
	)
	(segment
		(start 117.856 -39.5351)
		(end 117.856 -39.116)
		(width 0.127)
		(layer "In2.Cu")
		(net "FPGA_M2")
	)
	(segment
		(start 120.78716 -37.77234)
		(end 123.3805 -35.179)
		(width 0.127)
		(layer "In2.Cu")
		(net "FPGA_M2")
	)
	(segment
		(start 123.3805 -35.179)
		(end 124.70638 -35.179)
		(width 0.127)
		(layer "In2.Cu")
		(net "FPGA_M2")
	)
	(segment
		(start 115.346988 -41.32326)
		(end 115.39474 -41.32326)
		(width 0.127)
		(layer "In2.Cu")
		(net "FPGA_M2")
	)
	(segment
		(start 114.902996 -42.766996)
		(end 114.847116 -42.82313)
		(width 0.11938)
		(layer "F.Cu")
		(net "FPGA_M1")
	)
	(segment
		(start 115.346988 -42.323258)
		(end 114.902996 -42.766996)
		(width 0.11938)
		(layer "F.Cu")
		(net "FPGA_M1")
	)
	(via
		(at 122.936 -42.164)
		(size 0.508)
		(drill 0.254)
		(layers "F.Cu" "B.Cu")
		(net "FPGA_M1")
	)
	(via
		(at 115.346988 -42.323258)
		(size 0.4572)
		(drill 0.2032)
		(layers "F.Cu" "B.Cu")
		(net "FPGA_M1")
	)
	(segment
		(start 124.0536 -41.402)
		(end 124.0536 -42.545)
		(width 0.11938)
		(layer "B.Cu")
		(net "FPGA_M1")
	)
	(segment
		(start 122.936 -42.164)
		(end 123.317 -42.545)
		(width 0.11938)
		(layer "B.Cu")
		(net "FPGA_M1")
	)
	(segment
		(start 123.317 -42.545)
		(end 124.0536 -42.545)
		(width 0.11938)
		(layer "B.Cu")
		(net "FPGA_M1")
	)
	(segment
		(start 122.301 -42.799)
		(end 121.379742 -42.799)
		(width 0.127)
		(layer "In7.Cu")
		(net "FPGA_M1")
	)
	(segment
		(start 121.379742 -42.799)
		(end 120.4849 -41.904158)
		(width 0.127)
		(layer "In7.Cu")
		(net "FPGA_M1")
	)
	(segment
		(start 120.4849 -41.904158)
		(end 115.766088 -41.904158)
		(width 0.127)
		(layer "In7.Cu")
		(net "FPGA_M1")
	)
	(segment
		(start 122.936 -42.164)
		(end 122.301 -42.799)
		(width 0.127)
		(layer "In7.Cu")
		(net "FPGA_M1")
	)
	(segment
		(start 115.766088 -41.904158)
		(end 115.346988 -42.323258)
		(width 0.127)
		(layer "In7.Cu")
		(net "FPGA_M1")
	)
	(segment
		(start 124.0536 -43.688)
		(end 124.0536 -44.831)
		(width 0.11938)
		(layer "F.Cu")
		(net "FPGA_M0")
	)
	(segment
		(start 122.174 -43.815)
		(end 121.666 -44.323)
		(width 0.11938)
		(layer "F.Cu")
		(net "FPGA_M0")
	)
	(segment
		(start 115.346988 -44.323)
		(end 114.847116 -43.823128)
		(width 0.11938)
		(layer "F.Cu")
		(net "FPGA_M0")
	)
	(segment
		(start 124.0536 -43.688)
		(end 122.301 -43.688)
		(width 0.11938)
		(layer "F.Cu")
		(net "FPGA_M0")
	)
	(segment
		(start 121.666 -44.323)
		(end 115.346988 -44.323)
		(width 0.11938)
		(layer "F.Cu")
		(net "FPGA_M0")
	)
	(segment
		(start 122.301 -43.688)
		(end 122.174 -43.815)
		(width 0.11938)
		(layer "F.Cu")
		(net "FPGA_M0")
	)
	(via
		(at 122.174 -43.815)
		(size 0.508)
		(drill 0.254)
		(layers "F.Cu" "B.Cu")
		(net "FPGA_M0")
	)
	(segment
		(start 83.114134 -31.058866)
		(end 84.017866 -30.155134)
		(width 0.09906)
		(layer "F.Cu")
		(net "FPGA_IN_MAC_PPS_OUTP")
	)
	(segment
		(start 115.5954 -30.71622)
		(end 115.5954 -30.628844)
		(width 0.09906)
		(layer "F.Cu")
		(net "FPGA_IN_MAC_PPS_OUTP")
	)
	(segment
		(start 83.058 -44.625514)
		(end 83.058 -31.19374)
		(width 0.09906)
		(layer "F.Cu")
		(net "FPGA_IN_MAC_PPS_OUTP")
	)
	(segment
		(start 80.391 -45.72)
		(end 80.745838 -45.365162)
		(width 0.09906)
		(layer "F.Cu")
		(net "FPGA_IN_MAC_PPS_OUTP")
	)
	(segment
		(start 116.847112 -33.822894)
		(end 117.346984 -33.323022)
		(width 0.09906)
		(layer "F.Cu")
		(net "FPGA_IN_MAC_PPS_OUTP")
	)
	(segment
		(start 85.603588 -30.206442)
		(end 85.724746 -30.3276)
		(width 0.09906)
		(layer "F.Cu")
		(net "FPGA_IN_MAC_PPS_OUTP")
	)
	(segment
		(start 115.526058 -30.461458)
		(end 115.062 -29.9974)
		(width 0.09906)
		(layer "F.Cu")
		(net "FPGA_IN_MAC_PPS_OUTP")
	)
	(segment
		(start 82.796634 -45.092366)
		(end 82.912966 -44.976034)
		(width 0.09906)
		(layer "F.Cu")
		(net "FPGA_IN_MAC_PPS_OUTP")
	)
	(segment
		(start 81.054194 -45.2374)
		(end 82.446114 -45.2374)
		(width 0.09906)
		(layer "F.Cu")
		(net "FPGA_IN_MAC_PPS_OUTP")
	)
	(segment
		(start 85.724746 -30.3276)
		(end 85.725 -30.3276)
		(width 0.09906)
		(layer "F.Cu")
		(net "FPGA_IN_MAC_PPS_OUTP")
	)
	(segment
		(start 115.34902 -31.030418)
		(end 115.547394 -30.832044)
		(width 0.09906)
		(layer "F.Cu")
		(net "FPGA_IN_MAC_PPS_OUTP")
	)
	(segment
		(start 84.15274 -30.099)
		(end 85.344 -30.099)
		(width 0.09906)
		(layer "F.Cu")
		(net "FPGA_IN_MAC_PPS_OUTP")
	)
	(via
		(at 115.34902 -31.030418)
		(size 0.4572)
		(drill 0.2032)
		(layers "F.Cu" "B.Cu")
		(net "FPGA_IN_MAC_PPS_OUTP")
	)
	(arc
		(start 83.058 -31.19374)
		(mid 83.072653 -31.120727)
		(end 83.114134 -31.058866)
		(width 0.09906)
		(layer "F.Cu")
		(net "FPGA_IN_MAC_PPS_OUTP")
	)
	(arc
		(start 82.912966 -44.976034)
		(mid 83.020339 -44.815199)
		(end 83.058 -44.625514)
		(width 0.09906)
		(layer "F.Cu")
		(net "FPGA_IN_MAC_PPS_OUTP")
	)
	(arc
		(start 115.547394 -30.832044)
		(mid 115.582901 -30.778903)
		(end 115.5954 -30.71622)
		(width 0.09906)
		(layer "F.Cu")
		(net "FPGA_IN_MAC_PPS_OUTP")
	)
	(arc
		(start 85.344 -30.099)
		(mid 85.484471 -30.126923)
		(end 85.603588 -30.206442)
		(width 0.09906)
		(layer "F.Cu")
		(net "FPGA_IN_MAC_PPS_OUTP")
	)
	(arc
		(start 115.5954 -30.628844)
		(mid 115.57738 -30.538252)
		(end 115.526058 -30.461458)
		(width 0.09906)
		(layer "F.Cu")
		(net "FPGA_IN_MAC_PPS_OUTP")
	)
	(arc
		(start 82.446114 -45.2374)
		(mid 82.635808 -45.199761)
		(end 82.796634 -45.092366)
		(width 0.09906)
		(layer "F.Cu")
		(net "FPGA_IN_MAC_PPS_OUTP")
	)
	(arc
		(start 80.745838 -45.365162)
		(mid 80.887313 -45.270631)
		(end 81.054194 -45.2374)
		(width 0.09906)
		(layer "F.Cu")
		(net "FPGA_IN_MAC_PPS_OUTP")
	)
	(arc
		(start 84.017866 -30.155134)
		(mid 84.079703 -30.113596)
		(end 84.15274 -30.099)
		(width 0.09906)
		(layer "F.Cu")
		(net "FPGA_IN_MAC_PPS_OUTP")
	)
	(segment
		(start 115.34902 -31.030418)
		(end 115.581684 -30.797754)
		(width 0.09906)
		(layer "B.Cu")
		(net "FPGA_IN_MAC_PPS_OUTP")
	)
	(segment
		(start 115.53952 -30.47492)
		(end 115.062 -29.9974)
		(width 0.09906)
		(layer "B.Cu")
		(net "FPGA_IN_MAC_PPS_OUTP")
	)
	(segment
		(start 115.6081 -30.734)
		(end 115.6081 -30.640528)
		(width 0.09906)
		(layer "B.Cu")
		(net "FPGA_IN_MAC_PPS_OUTP")
	)
	(segment
		(start 116.846858 -32.822896)
		(end 117.346984 -33.323022)
		(width 0.09906)
		(layer "B.Cu")
		(net "FPGA_IN_MAC_PPS_OUTP")
	)
	(arc
		(start 115.6081 -30.640528)
		(mid 115.590273 -30.550908)
		(end 115.53952 -30.47492)
		(width 0.09906)
		(layer "B.Cu")
		(net "FPGA_IN_MAC_PPS_OUTP")
	)
	(arc
		(start 115.581684 -30.797754)
		(mid 115.601229 -30.768503)
		(end 115.6081 -30.734)
		(width 0.09906)
		(layer "B.Cu")
		(net "FPGA_IN_MAC_PPS_OUTP")
	)
	(segment
		(start 117.57152 -33.323022)
		(end 117.346984 -33.323022)
		(width 0.11684)
		(layer "In7.Cu")
		(net "FPGA_IN_MAC_PPS_OUTP")
	)
	(segment
		(start 103.323136 -27.813)
		(end 101.391974 -27.813)
		(width 0.11684)
		(layer "In7.Cu")
		(net "FPGA_IN_MAC_PPS_OUTP")
	)
	(segment
		(start 104.500172 -28.554172)
		(end 104.067356 -28.121356)
		(width 0.11684)
		(layer "In7.Cu")
		(net "FPGA_IN_MAC_PPS_OUTP")
	)
	(segment
		(start 113.986818 -28.829)
		(end 105.025698 -28.829)
		(width 0.11684)
		(layer "In7.Cu")
		(net "FPGA_IN_MAC_PPS_OUTP")
	)
	(segment
		(start 115.59667 -30.695392)
		(end 115.59667 -30.255464)
		(width 0.11684)
		(layer "In7.Cu")
		(net "FPGA_IN_MAC_PPS_OUTP")
	)
	(segment
		(start 85.884258 -30.168342)
		(end 85.725 -30.3276)
		(width 0.11684)
		(layer "In7.Cu")
		(net "FPGA_IN_MAC_PPS_OUTP")
	)
	(segment
		(start 94.362524 -29.15158)
		(end 94.090744 -29.15158)
		(width 0.11684)
		(layer "In7.Cu")
		(net "FPGA_IN_MAC_PPS_OUTP")
	)
	(segment
		(start 100.526596 -28.171394)
		(end 100.250244 -28.447746)
		(width 0.11684)
		(layer "In7.Cu")
		(net "FPGA_IN_MAC_PPS_OUTP")
	)
	(segment
		(start 99.023424 -28.956)
		(end 94.558104 -28.956)
		(width 0.11684)
		(layer "In7.Cu")
		(net "FPGA_IN_MAC_PPS_OUTP")
	)
	(segment
		(start 116.295932 -32.2072)
		(end 117.25656 -32.2072)
		(width 0.11684)
		(layer "In7.Cu")
		(net "FPGA_IN_MAC_PPS_OUTP")
	)
	(segment
		(start 117.68836 -32.639)
		(end 117.68836 -33.206182)
		(width 0.11684)
		(layer "In7.Cu")
		(net "FPGA_IN_MAC_PPS_OUTP")
	)
	(segment
		(start 115.584732 -31.369)
		(end 115.584732 -31.496)
		(width 0.11684)
		(layer "In7.Cu")
		(net "FPGA_IN_MAC_PPS_OUTP")
	)
	(segment
		(start 93.895164 -28.956)
		(end 93.437202 -28.956)
		(width 0.11684)
		(layer "In7.Cu")
		(net "FPGA_IN_MAC_PPS_OUTP")
	)
	(segment
		(start 114.735102 -29.469842)
		(end 114.735356 -29.469588)
		(width 0.11684)
		(layer "In7.Cu")
		(net "FPGA_IN_MAC_PPS_OUTP")
	)
	(segment
		(start 115.34902 -31.030418)
		(end 115.534948 -30.84449)
		(width 0.11684)
		(layer "In7.Cu")
		(net "FPGA_IN_MAC_PPS_OUTP")
	)
	(segment
		(start 93.24848 -29.034232)
		(end 92.428568 -29.854144)
		(width 0.11684)
		(layer "In7.Cu")
		(net "FPGA_IN_MAC_PPS_OUTP")
	)
	(segment
		(start 114.92865 -29.80055)
		(end 114.735102 -29.607002)
		(width 0.11684)
		(layer "In7.Cu")
		(net "FPGA_IN_MAC_PPS_OUTP")
	)
	(segment
		(start 115.066064 -29.800296)
		(end 115.06581 -29.80055)
		(width 0.11684)
		(layer "In7.Cu")
		(net "FPGA_IN_MAC_PPS_OUTP")
	)
	(segment
		(start 115.34902 -31.030418)
		(end 115.512088 -31.193232)
		(width 0.11684)
		(layer "In7.Cu")
		(net "FPGA_IN_MAC_PPS_OUTP")
	)
	(segment
		(start 115.552982 -30.150054)
		(end 115.203224 -29.800296)
		(width 0.11684)
		(layer "In7.Cu")
		(net "FPGA_IN_MAC_PPS_OUTP")
	)
	(segment
		(start 114.735356 -29.332428)
		(end 114.380264 -28.977336)
		(width 0.11684)
		(layer "In7.Cu")
		(net "FPGA_IN_MAC_PPS_OUTP")
	)
	(segment
		(start 92.01531 -30.02534)
		(end 86.22919 -30.02534)
		(width 0.11684)
		(layer "In7.Cu")
		(net "FPGA_IN_MAC_PPS_OUTP")
	)
	(arc
		(start 94.558104 -28.956)
		(mid 94.488956 -28.984642)
		(end 94.460314 -29.05379)
		(width 0.11684)
		(layer "In7.Cu")
		(net "FPGA_IN_MAC_PPS_OUTP")
	)
	(arc
		(start 117.68836 -33.206182)
		(mid 117.654138 -33.2888)
		(end 117.57152 -33.323022)
		(width 0.11684)
		(layer "In7.Cu")
		(net "FPGA_IN_MAC_PPS_OUTP")
	)
	(arc
		(start 114.735356 -29.469588)
		(mid 114.763763 -29.401008)
		(end 114.735356 -29.332428)
		(width 0.11684)
		(layer "In7.Cu")
		(net "FPGA_IN_MAC_PPS_OUTP")
	)
	(arc
		(start 115.512088 -31.193232)
		(mid 115.565889 -31.27389)
		(end 115.584732 -31.369)
		(width 0.11684)
		(layer "In7.Cu")
		(net "FPGA_IN_MAC_PPS_OUTP")
	)
	(arc
		(start 94.090744 -29.15158)
		(mid 94.021596 -29.122938)
		(end 93.992954 -29.05379)
		(width 0.11684)
		(layer "In7.Cu")
		(net "FPGA_IN_MAC_PPS_OUTP")
	)
	(arc
		(start 93.437202 -28.956)
		(mid 93.335057 -28.976336)
		(end 93.24848 -29.034232)
		(width 0.11684)
		(layer "In7.Cu")
		(net "FPGA_IN_MAC_PPS_OUTP")
	)
	(arc
		(start 115.534948 -30.84449)
		(mid 115.580656 -30.776083)
		(end 115.59667 -30.695392)
		(width 0.11684)
		(layer "In7.Cu")
		(net "FPGA_IN_MAC_PPS_OUTP")
	)
	(arc
		(start 115.203224 -29.800296)
		(mid 115.134644 -29.771889)
		(end 115.066064 -29.800296)
		(width 0.11684)
		(layer "In7.Cu")
		(net "FPGA_IN_MAC_PPS_OUTP")
	)
	(arc
		(start 94.460314 -29.05379)
		(mid 94.431672 -29.122938)
		(end 94.362524 -29.15158)
		(width 0.11684)
		(layer "In7.Cu")
		(net "FPGA_IN_MAC_PPS_OUTP")
	)
	(arc
		(start 114.380264 -28.977336)
		(mid 114.33599 -28.938772)
		(end 114.286792 -28.906724)
		(width 0.11684)
		(layer "In7.Cu")
		(net "FPGA_IN_MAC_PPS_OUTP")
	)
	(arc
		(start 92.428568 -29.854144)
		(mid 92.238964 -29.980834)
		(end 92.01531 -30.02534)
		(width 0.11684)
		(layer "In7.Cu")
		(net "FPGA_IN_MAC_PPS_OUTP")
	)
	(arc
		(start 85.9536 -30.110684)
		(mid 85.917588 -30.137901)
		(end 85.884258 -30.168342)
		(width 0.11684)
		(layer "In7.Cu")
		(net "FPGA_IN_MAC_PPS_OUTP")
	)
	(arc
		(start 104.067356 -28.121356)
		(mid 103.725919 -27.893152)
		(end 103.323136 -27.813)
		(width 0.11684)
		(layer "In7.Cu")
		(net "FPGA_IN_MAC_PPS_OUTP")
	)
	(arc
		(start 93.992954 -29.05379)
		(mid 93.964312 -28.984642)
		(end 93.895164 -28.956)
		(width 0.11684)
		(layer "In7.Cu")
		(net "FPGA_IN_MAC_PPS_OUTP")
	)
	(arc
		(start 117.25656 -32.2072)
		(mid 117.561889 -32.333671)
		(end 117.68836 -32.639)
		(width 0.11684)
		(layer "In7.Cu")
		(net "FPGA_IN_MAC_PPS_OUTP")
	)
	(arc
		(start 104.745282 -28.749244)
		(mid 104.617148 -28.658719)
		(end 104.500172 -28.554172)
		(width 0.11684)
		(layer "In7.Cu")
		(net "FPGA_IN_MAC_PPS_OUTP")
	)
	(arc
		(start 114.286792 -28.906724)
		(mid 114.141763 -28.848735)
		(end 113.986818 -28.829)
		(width 0.11684)
		(layer "In7.Cu")
		(net "FPGA_IN_MAC_PPS_OUTP")
	)
	(arc
		(start 115.59667 -30.255464)
		(mid 115.585306 -30.198421)
		(end 115.552982 -30.150054)
		(width 0.11684)
		(layer "In7.Cu")
		(net "FPGA_IN_MAC_PPS_OUTP")
	)
	(arc
		(start 101.391974 -27.813)
		(mid 100.923642 -27.906139)
		(end 100.526596 -28.171394)
		(width 0.11684)
		(layer "In7.Cu")
		(net "FPGA_IN_MAC_PPS_OUTP")
	)
	(arc
		(start 100.250244 -28.447746)
		(mid 99.687388 -28.823897)
		(end 99.023424 -28.956)
		(width 0.11684)
		(layer "In7.Cu")
		(net "FPGA_IN_MAC_PPS_OUTP")
	)
	(arc
		(start 115.06581 -29.80055)
		(mid 114.99723 -29.828957)
		(end 114.92865 -29.80055)
		(width 0.11684)
		(layer "In7.Cu")
		(net "FPGA_IN_MAC_PPS_OUTP")
	)
	(arc
		(start 114.735102 -29.607002)
		(mid 114.706695 -29.538422)
		(end 114.735102 -29.469842)
		(width 0.11684)
		(layer "In7.Cu")
		(net "FPGA_IN_MAC_PPS_OUTP")
	)
	(arc
		(start 86.22919 -30.02534)
		(mid 86.084938 -30.047163)
		(end 85.9536 -30.110684)
		(width 0.11684)
		(layer "In7.Cu")
		(net "FPGA_IN_MAC_PPS_OUTP")
	)
	(arc
		(start 105.025698 -28.829)
		(mid 104.879896 -28.808783)
		(end 104.745282 -28.749244)
		(width 0.11684)
		(layer "In7.Cu")
		(net "FPGA_IN_MAC_PPS_OUTP")
	)
	(arc
		(start 115.584732 -31.496)
		(mid 115.793038 -31.998894)
		(end 116.295932 -32.2072)
		(width 0.11684)
		(layer "In7.Cu")
		(net "FPGA_IN_MAC_PPS_OUTP")
	)
	(segment
		(start 81.054194 -44.9326)
		(end 82.446114 -44.9326)
		(width 0.09906)
		(layer "F.Cu")
		(net "FPGA_IN_MAC_PPS_OUTN")
	)
	(segment
		(start 82.580988 -44.87672)
		(end 82.69732 -44.760388)
		(width 0.09906)
		(layer "F.Cu")
		(net "FPGA_IN_MAC_PPS_OUTN")
	)
	(segment
		(start 80.391 -44.45)
		(end 80.745838 -44.804838)
		(width 0.09906)
		(layer "F.Cu")
		(net "FPGA_IN_MAC_PPS_OUTN")
	)
	(segment
		(start 82.7532 -44.625514)
		(end 82.7532 -31.19374)
		(width 0.09906)
		(layer "F.Cu")
		(net "FPGA_IN_MAC_PPS_OUTN")
	)
	(segment
		(start 85.578442 -29.661358)
		(end 85.725 -29.5148)
		(width 0.09906)
		(layer "F.Cu")
		(net "FPGA_IN_MAC_PPS_OUTN")
	)
	(segment
		(start 115.949222 -30.507178)
		(end 116.459 -29.9974)
		(width 0.09906)
		(layer "F.Cu")
		(net "FPGA_IN_MAC_PPS_OUTN")
	)
	(segment
		(start 117.84711 -33.822894)
		(end 118.346982 -33.323022)
		(width 0.09906)
		(layer "F.Cu")
		(net "FPGA_IN_MAC_PPS_OUTN")
	)
	(segment
		(start 116.16182 -31.030418)
		(end 115.92941 -30.798008)
		(width 0.09906)
		(layer "F.Cu")
		(net "FPGA_IN_MAC_PPS_OUTN")
	)
	(segment
		(start 84.15274 -29.7942)
		(end 85.257894 -29.7942)
		(width 0.09906)
		(layer "F.Cu")
		(net "FPGA_IN_MAC_PPS_OUTN")
	)
	(segment
		(start 82.898488 -30.84322)
		(end 83.80222 -29.939488)
		(width 0.09906)
		(layer "F.Cu")
		(net "FPGA_IN_MAC_PPS_OUTN")
	)
	(segment
		(start 115.9002 -30.72765)
		(end 115.9002 -30.625542)
		(width 0.09906)
		(layer "F.Cu")
		(net "FPGA_IN_MAC_PPS_OUTN")
	)
	(via
		(at 116.16182 -31.030418)
		(size 0.4572)
		(drill 0.2032)
		(layers "F.Cu" "B.Cu")
		(net "FPGA_IN_MAC_PPS_OUTN")
	)
	(arc
		(start 82.7532 -31.19374)
		(mid 82.790956 -31.004017)
		(end 82.898488 -30.84322)
		(width 0.09906)
		(layer "F.Cu")
		(net "FPGA_IN_MAC_PPS_OUTN")
	)
	(arc
		(start 82.446114 -44.9326)
		(mid 82.519112 -44.91808)
		(end 82.580988 -44.87672)
		(width 0.09906)
		(layer "F.Cu")
		(net "FPGA_IN_MAC_PPS_OUTN")
	)
	(arc
		(start 115.9002 -30.625542)
		(mid 115.912942 -30.561486)
		(end 115.949222 -30.507178)
		(width 0.09906)
		(layer "F.Cu")
		(net "FPGA_IN_MAC_PPS_OUTN")
	)
	(arc
		(start 80.745838 -44.804838)
		(mid 80.887313 -44.899369)
		(end 81.054194 -44.9326)
		(width 0.09906)
		(layer "F.Cu")
		(net "FPGA_IN_MAC_PPS_OUTN")
	)
	(arc
		(start 82.69732 -44.760388)
		(mid 82.738667 -44.698507)
		(end 82.7532 -44.625514)
		(width 0.09906)
		(layer "F.Cu")
		(net "FPGA_IN_MAC_PPS_OUTN")
	)
	(arc
		(start 115.92941 -30.798008)
		(mid 115.907787 -30.765742)
		(end 115.9002 -30.72765)
		(width 0.09906)
		(layer "F.Cu")
		(net "FPGA_IN_MAC_PPS_OUTN")
	)
	(arc
		(start 85.257894 -29.7942)
		(mid 85.431385 -29.759673)
		(end 85.578442 -29.661358)
		(width 0.09906)
		(layer "F.Cu")
		(net "FPGA_IN_MAC_PPS_OUTN")
	)
	(arc
		(start 83.80222 -29.939488)
		(mid 83.963026 -29.831978)
		(end 84.15274 -29.7942)
		(width 0.09906)
		(layer "F.Cu")
		(net "FPGA_IN_MAC_PPS_OUTN")
	)
	(segment
		(start 117.84711 -32.822896)
		(end 117.84711 -32.82315)
		(width 0.09906)
		(layer "B.Cu")
		(net "FPGA_IN_MAC_PPS_OUTN")
	)
	(segment
		(start 116.16182 -31.030418)
		(end 115.946428 -30.815026)
		(width 0.09906)
		(layer "B.Cu")
		(net "FPGA_IN_MAC_PPS_OUTN")
	)
	(segment
		(start 115.9129 -30.734)
		(end 115.9129 -30.640528)
		(width 0.09906)
		(layer "B.Cu")
		(net "FPGA_IN_MAC_PPS_OUTN")
	)
	(segment
		(start 115.98148 -30.47492)
		(end 116.459 -29.9974)
		(width 0.09906)
		(layer "B.Cu")
		(net "FPGA_IN_MAC_PPS_OUTN")
	)
	(segment
		(start 117.84711 -32.82315)
		(end 118.346982 -33.323022)
		(width 0.09906)
		(layer "B.Cu")
		(net "FPGA_IN_MAC_PPS_OUTN")
	)
	(arc
		(start 115.946428 -30.815026)
		(mid 115.921588 -30.777851)
		(end 115.9129 -30.734)
		(width 0.09906)
		(layer "B.Cu")
		(net "FPGA_IN_MAC_PPS_OUTN")
	)
	(arc
		(start 115.9129 -30.640528)
		(mid 115.930727 -30.550908)
		(end 115.98148 -30.47492)
		(width 0.09906)
		(layer "B.Cu")
		(net "FPGA_IN_MAC_PPS_OUTN")
	)
	(segment
		(start 115.902232 -31.369)
		(end 115.902232 -31.496)
		(width 0.11684)
		(layer "In7.Cu")
		(net "FPGA_IN_MAC_PPS_OUTN")
	)
	(segment
		(start 118.00586 -32.639)
		(end 118.00586 -33.206182)
		(width 0.11684)
		(layer "In7.Cu")
		(net "FPGA_IN_MAC_PPS_OUTN")
	)
	(segment
		(start 115.91417 -30.695646)
		(end 115.91417 -30.255718)
		(width 0.11684)
		(layer "In7.Cu")
		(net "FPGA_IN_MAC_PPS_OUTN")
	)
	(segment
		(start 116.295932 -31.8897)
		(end 117.25656 -31.8897)
		(width 0.11684)
		(layer "In7.Cu")
		(net "FPGA_IN_MAC_PPS_OUTN")
	)
	(segment
		(start 118.1227 -33.323022)
		(end 118.346982 -33.323022)
		(width 0.11684)
		(layer "In7.Cu")
		(net "FPGA_IN_MAC_PPS_OUTN")
	)
	(segment
		(start 116.16182 -31.030418)
		(end 115.975892 -30.844236)
		(width 0.11684)
		(layer "In7.Cu")
		(net "FPGA_IN_MAC_PPS_OUTN")
	)
	(segment
		(start 115.777518 -29.925518)
		(end 114.6048 -28.7528)
		(width 0.11684)
		(layer "In7.Cu")
		(net "FPGA_IN_MAC_PPS_OUTN")
	)
	(segment
		(start 103.32339 -27.4955)
		(end 101.391974 -27.4955)
		(width 0.11684)
		(layer "In7.Cu")
		(net "FPGA_IN_MAC_PPS_OUTN")
	)
	(segment
		(start 113.986818 -28.5115)
		(end 105.025698 -28.5115)
		(width 0.11684)
		(layer "In7.Cu")
		(net "FPGA_IN_MAC_PPS_OUTN")
	)
	(segment
		(start 99.023424 -28.6385)
		(end 93.437202 -28.6385)
		(width 0.11684)
		(layer "In7.Cu")
		(net "FPGA_IN_MAC_PPS_OUTN")
	)
	(segment
		(start 104.724708 -28.329636)
		(end 104.291892 -27.89682)
		(width 0.11684)
		(layer "In7.Cu")
		(net "FPGA_IN_MAC_PPS_OUTN")
	)
	(segment
		(start 116.16182 -31.030418)
		(end 115.958112 -31.234126)
		(width 0.11684)
		(layer "In7.Cu")
		(net "FPGA_IN_MAC_PPS_OUTN")
	)
	(segment
		(start 100.30206 -27.946858)
		(end 100.025708 -28.22321)
		(width 0.11684)
		(layer "In7.Cu")
		(net "FPGA_IN_MAC_PPS_OUTN")
	)
	(segment
		(start 93.023944 -28.809696)
		(end 92.204032 -29.629608)
		(width 0.11684)
		(layer "In7.Cu")
		(net "FPGA_IN_MAC_PPS_OUTN")
	)
	(segment
		(start 85.829648 -29.619448)
		(end 85.725 -29.5148)
		(width 0.11684)
		(layer "In7.Cu")
		(net "FPGA_IN_MAC_PPS_OUTN")
	)
	(segment
		(start 92.01531 -29.70784)
		(end 86.043008 -29.70784)
		(width 0.11684)
		(layer "In7.Cu")
		(net "FPGA_IN_MAC_PPS_OUTN")
	)
	(arc
		(start 114.6048 -28.7528)
		(mid 114.536403 -28.692202)
		(end 114.461036 -28.640532)
		(width 0.11684)
		(layer "In7.Cu")
		(net "FPGA_IN_MAC_PPS_OUTN")
	)
	(arc
		(start 115.958112 -31.234126)
		(mid 115.916765 -31.296007)
		(end 115.902232 -31.369)
		(width 0.11684)
		(layer "In7.Cu")
		(net "FPGA_IN_MAC_PPS_OUTN")
	)
	(arc
		(start 86.043008 -29.70784)
		(mid 85.927533 -29.68487)
		(end 85.829648 -29.619448)
		(width 0.11684)
		(layer "In7.Cu")
		(net "FPGA_IN_MAC_PPS_OUTN")
	)
	(arc
		(start 115.902232 -31.496)
		(mid 116.017544 -31.774388)
		(end 116.295932 -31.8897)
		(width 0.11684)
		(layer "In7.Cu")
		(net "FPGA_IN_MAC_PPS_OUTN")
	)
	(arc
		(start 100.025708 -28.22321)
		(mid 99.565885 -28.530581)
		(end 99.023424 -28.6385)
		(width 0.11684)
		(layer "In7.Cu")
		(net "FPGA_IN_MAC_PPS_OUTN")
	)
	(arc
		(start 114.461036 -28.640532)
		(mid 114.232562 -28.544272)
		(end 113.986818 -28.5115)
		(width 0.11684)
		(layer "In7.Cu")
		(net "FPGA_IN_MAC_PPS_OUTN")
	)
	(arc
		(start 104.913176 -28.479496)
		(mid 104.81465 -28.409964)
		(end 104.724708 -28.329636)
		(width 0.11684)
		(layer "In7.Cu")
		(net "FPGA_IN_MAC_PPS_OUTN")
	)
	(arc
		(start 92.204032 -29.629608)
		(mid 92.11746 -29.687517)
		(end 92.01531 -29.70784)
		(width 0.11684)
		(layer "In7.Cu")
		(net "FPGA_IN_MAC_PPS_OUTN")
	)
	(arc
		(start 118.00586 -33.206182)
		(mid 118.040082 -33.2888)
		(end 118.1227 -33.323022)
		(width 0.11684)
		(layer "In7.Cu")
		(net "FPGA_IN_MAC_PPS_OUTN")
	)
	(arc
		(start 101.391974 -27.4955)
		(mid 100.802141 -27.612807)
		(end 100.30206 -27.946858)
		(width 0.11684)
		(layer "In7.Cu")
		(net "FPGA_IN_MAC_PPS_OUTN")
	)
	(arc
		(start 115.975892 -30.844236)
		(mid 115.930257 -30.776077)
		(end 115.91417 -30.695646)
		(width 0.11684)
		(layer "In7.Cu")
		(net "FPGA_IN_MAC_PPS_OUTN")
	)
	(arc
		(start 117.25656 -31.8897)
		(mid 117.786395 -32.109165)
		(end 118.00586 -32.639)
		(width 0.11684)
		(layer "In7.Cu")
		(net "FPGA_IN_MAC_PPS_OUTN")
	)
	(arc
		(start 93.437202 -28.6385)
		(mid 93.213541 -28.682989)
		(end 93.023944 -28.809696)
		(width 0.11684)
		(layer "In7.Cu")
		(net "FPGA_IN_MAC_PPS_OUTN")
	)
	(arc
		(start 105.025698 -28.5115)
		(mid 104.967202 -28.503367)
		(end 104.913176 -28.479496)
		(width 0.11684)
		(layer "In7.Cu")
		(net "FPGA_IN_MAC_PPS_OUTN")
	)
	(arc
		(start 104.291892 -27.89682)
		(mid 103.847555 -27.59983)
		(end 103.32339 -27.4955)
		(width 0.11684)
		(layer "In7.Cu")
		(net "FPGA_IN_MAC_PPS_OUTN")
	)
	(arc
		(start 115.91417 -30.255718)
		(mid 115.878769 -30.076982)
		(end 115.777518 -29.925518)
		(width 0.11684)
		(layer "In7.Cu")
		(net "FPGA_IN_MAC_PPS_OUTN")
	)
	(segment
		(start 104.847136 -43.823128)
		(end 104.347264 -43.323256)
		(width 0.11938)
		(layer "F.Cu")
		(net "FPGA_DONE")
	)
	(via
		(at 104.347264 -43.323256)
		(size 0.4572)
		(drill 0.2032)
		(layers "F.Cu" "B.Cu")
		(net "FPGA_DONE")
	)
	(segment
		(start 133.9342 -105.638854)
		(end 135.2042 -105.638854)
		(width 0.11938)
		(layer "B.Cu")
		(net "FPGA_DONE")
	)
	(segment
		(start 135.2042 -105.638854)
		(end 135.2042 -103.8352)
		(width 0.11938)
		(layer "B.Cu")
		(net "FPGA_DONE")
	)
	(segment
		(start 135.2042 -103.8352)
		(end 134.62 -103.251)
		(width 0.11938)
		(layer "B.Cu")
		(net "FPGA_DONE")
	)
	(segment
		(start 93.2815 -67.627246)
		(end 91.7575 -66.103246)
		(width 0.127)
		(layer "In2.Cu")
		(net "FPGA_DONE")
	)
	(segment
		(start 105.801922 -80.82026)
		(end 105.801922 -76.316078)
		(width 0.127)
		(layer "In2.Cu")
		(net "FPGA_DONE")
	)
	(segment
		(start 111.506 -88.9)
		(end 107.94111 -85.33511)
		(width 0.127)
		(layer "In2.Cu")
		(net "FPGA_DONE")
	)
	(segment
		(start 103.251 -75.692)
		(end 102.1207 -74.5617)
		(width 0.127)
		(layer "In2.Cu")
		(net "FPGA_DONE")
	)
	(segment
		(start 88.011 -54.200806)
		(end 88.011 -51.943)
		(width 0.127)
		(layer "In2.Cu")
		(net "FPGA_DONE")
	)
	(segment
		(start 88.011 -51.943)
		(end 87.0458 -50.9778)
		(width 0.127)
		(layer "In2.Cu")
		(net "FPGA_DONE")
	)
	(segment
		(start 87.5411 -62.230508)
		(end 87.5411 -56.298846)
		(width 0.127)
		(layer "In2.Cu")
		(net "FPGA_DONE")
	)
	(segment
		(start 95.123 -67.691)
		(end 94.2975 -68.5165)
		(width 0.127)
		(layer "In2.Cu")
		(net "FPGA_DONE")
	)
	(segment
		(start 100.457 -44.196)
		(end 103.47452 -44.196)
		(width 0.127)
		(layer "In2.Cu")
		(net "FPGA_DONE")
	)
	(segment
		(start 102.1207 -70.147434)
		(end 101.569266 -69.596)
		(width 0.127)
		(layer "In2.Cu")
		(net "FPGA_DONE")
	)
	(segment
		(start 134.62 -103.251)
		(end 132.842 -103.251)
		(width 0.127)
		(layer "In2.Cu")
		(net "FPGA_DONE")
	)
	(segment
		(start 90.687398 -46.832012)
		(end 90.807286 -46.9519)
		(width 0.127)
		(layer "In2.Cu")
		(net "FPGA_DONE")
	)
	(segment
		(start 96.9899 -43.1419)
		(end 97.5995 -43.7515)
		(width 0.127)
		(layer "In2.Cu")
		(net "FPGA_DONE")
	)
	(segment
		(start 87.584534 -46.832012)
		(end 90.687398 -46.832012)
		(width 0.127)
		(layer "In2.Cu")
		(net "FPGA_DONE")
	)
	(segment
		(start 112.649 -88.9)
		(end 111.506 -88.9)
		(width 0.127)
		(layer "In2.Cu")
		(net "FPGA_DONE")
	)
	(segment
		(start 91.7575 -66.078862)
		(end 91.274138 -65.5955)
		(width 0.127)
		(layer "In2.Cu")
		(net "FPGA_DONE")
	)
	(segment
		(start 87.5411 -56.298846)
		(end 87.32012 -56.077866)
		(width 0.127)
		(layer "In2.Cu")
		(net "FPGA_DONE")
	)
	(segment
		(start 91.274138 -65.5955)
		(end 91.249754 -65.5955)
		(width 0.127)
		(layer "In2.Cu")
		(net "FPGA_DONE")
	)
	(segment
		(start 102.1207 -74.5617)
		(end 102.1207 -70.147434)
		(width 0.127)
		(layer "In2.Cu")
		(net "FPGA_DONE")
	)
	(segment
		(start 95.88246 -67.691)
		(end 95.123 -67.691)
		(width 0.127)
		(layer "In2.Cu")
		(net "FPGA_DONE")
	)
	(segment
		(start 89.954354 -64.3001)
		(end 89.610692 -64.3001)
		(width 0.127)
		(layer "In2.Cu")
		(net "FPGA_DONE")
	)
	(segment
		(start 107.94111 -85.33511)
		(end 107.94111 -82.959448)
		(width 0.127)
		(layer "In2.Cu")
		(net "FPGA_DONE")
	)
	(segment
		(start 101.569266 -69.596)
		(end 97.78746 -69.596)
		(width 0.127)
		(layer "In2.Cu")
		(net "FPGA_DONE")
	)
	(segment
		(start 103.47452 -44.196)
		(end 104.347264 -43.323256)
		(width 0.127)
		(layer "In2.Cu")
		(net "FPGA_DONE")
	)
	(segment
		(start 96.0501 -43.1419)
		(end 96.9899 -43.1419)
		(width 0.127)
		(layer "In2.Cu")
		(net "FPGA_DONE")
	)
	(segment
		(start 97.78746 -69.596)
		(end 95.88246 -67.691)
		(width 0.127)
		(layer "In2.Cu")
		(net "FPGA_DONE")
	)
	(segment
		(start 91.249754 -65.5955)
		(end 89.954354 -64.3001)
		(width 0.127)
		(layer "In2.Cu")
		(net "FPGA_DONE")
	)
	(segment
		(start 107.94111 -82.959448)
		(end 105.801922 -80.82026)
		(width 0.127)
		(layer "In2.Cu")
		(net "FPGA_DONE")
	)
	(segment
		(start 89.610692 -64.3001)
		(end 87.5411 -62.230508)
		(width 0.127)
		(layer "In2.Cu")
		(net "FPGA_DONE")
	)
	(segment
		(start 93.2815 -68.181982)
		(end 93.2815 -67.627246)
		(width 0.127)
		(layer "In2.Cu")
		(net "FPGA_DONE")
	)
	(segment
		(start 87.0458 -50.9778)
		(end 87.0458 -47.370746)
		(width 0.127)
		(layer "In2.Cu")
		(net "FPGA_DONE")
	)
	(segment
		(start 94.2975 -68.5165)
		(end 93.616018 -68.5165)
		(width 0.127)
		(layer "In2.Cu")
		(net "FPGA_DONE")
	)
	(segment
		(start 91.7575 -66.103246)
		(end 91.7575 -66.078862)
		(width 0.127)
		(layer "In2.Cu")
		(net "FPGA_DONE")
	)
	(segment
		(start 90.807286 -46.9519)
		(end 92.2401 -46.9519)
		(width 0.127)
		(layer "In2.Cu")
		(net "FPGA_DONE")
	)
	(segment
		(start 92.2401 -46.9519)
		(end 96.0501 -43.1419)
		(width 0.127)
		(layer "In2.Cu")
		(net "FPGA_DONE")
	)
	(segment
		(start 132.842 -103.251)
		(end 128.524 -98.933)
		(width 0.127)
		(layer "In2.Cu")
		(net "FPGA_DONE")
	)
	(segment
		(start 105.177844 -75.692)
		(end 103.251 -75.692)
		(width 0.127)
		(layer "In2.Cu")
		(net "FPGA_DONE")
	)
	(segment
		(start 128.524 -98.933)
		(end 122.682 -98.933)
		(width 0.127)
		(layer "In2.Cu")
		(net "FPGA_DONE")
	)
	(segment
		(start 97.5995 -43.7515)
		(end 100.0125 -43.7515)
		(width 0.127)
		(layer "In2.Cu")
		(net "FPGA_DONE")
	)
	(segment
		(start 105.801922 -76.316078)
		(end 105.177844 -75.692)
		(width 0.127)
		(layer "In2.Cu")
		(net "FPGA_DONE")
	)
	(segment
		(start 93.616018 -68.5165)
		(end 93.2815 -68.181982)
		(width 0.127)
		(layer "In2.Cu")
		(net "FPGA_DONE")
	)
	(segment
		(start 87.0458 -47.370746)
		(end 87.584534 -46.832012)
		(width 0.127)
		(layer "In2.Cu")
		(net "FPGA_DONE")
	)
	(segment
		(start 100.0125 -43.7515)
		(end 100.457 -44.196)
		(width 0.127)
		(layer "In2.Cu")
		(net "FPGA_DONE")
	)
	(segment
		(start 87.32012 -54.891686)
		(end 88.011 -54.200806)
		(width 0.127)
		(layer "In2.Cu")
		(net "FPGA_DONE")
	)
	(segment
		(start 122.682 -98.933)
		(end 112.649 -88.9)
		(width 0.127)
		(layer "In2.Cu")
		(net "FPGA_DONE")
	)
	(segment
		(start 87.32012 -56.077866)
		(end 87.32012 -54.891686)
		(width 0.127)
		(layer "In2.Cu")
		(net "FPGA_DONE")
	)
	(segment
		(start 110.847124 -50.823114)
		(end 111.346996 -51.322986)
		(width 0.11938)
		(layer "F.Cu")
		(net "FPGA_BRD_REV2")
	)
	(segment
		(start 111.633 -61.4426)
		(end 111.633 -59.944)
		(width 0.11938)
		(layer "F.Cu")
		(net "FPGA_BRD_REV2")
	)
	(segment
		(start 112.776 -61.4426)
		(end 111.633 -61.4426)
		(width 0.11938)
		(layer "F.Cu")
		(net "FPGA_BRD_REV2")
	)
	(segment
		(start 111.633 -59.944)
		(end 110.871 -59.182)
		(width 0.11938)
		(layer "F.Cu")
		(net "FPGA_BRD_REV2")
	)
	(via
		(at 111.346996 -51.322986)
		(size 0.4572)
		(drill 0.2032)
		(layers "F.Cu" "B.Cu")
		(net "FPGA_BRD_REV2")
	)
	(via
		(at 110.871 -59.182)
		(size 0.508)
		(drill 0.254)
		(layers "F.Cu" "B.Cu")
		(net "FPGA_BRD_REV2")
	)
	(segment
		(start 111.83366 -54.48808)
		(end 111.51616 -54.80558)
		(width 0.127)
		(layer "In7.Cu")
		(net "FPGA_BRD_REV2")
	)
	(segment
		(start 111.05642 -54.80558)
		(end 110.871 -54.991)
		(width 0.127)
		(layer "In7.Cu")
		(net "FPGA_BRD_REV2")
	)
	(segment
		(start 111.346996 -51.322986)
		(end 111.83366 -51.80965)
		(width 0.127)
		(layer "In7.Cu")
		(net "FPGA_BRD_REV2")
	)
	(segment
		(start 111.83366 -51.80965)
		(end 111.83366 -54.48808)
		(width 0.127)
		(layer "In7.Cu")
		(net "FPGA_BRD_REV2")
	)
	(segment
		(start 111.51616 -54.80558)
		(end 111.05642 -54.80558)
		(width 0.127)
		(layer "In7.Cu")
		(net "FPGA_BRD_REV2")
	)
	(segment
		(start 110.871 -54.991)
		(end 110.871 -59.182)
		(width 0.127)
		(layer "In7.Cu")
		(net "FPGA_BRD_REV2")
	)
	(segment
		(start 110.847124 -51.823112)
		(end 111.346996 -52.322984)
		(width 0.11938)
		(layer "F.Cu")
		(net "FPGA_BRD_REV1")
	)
	(via
		(at 111.346996 -52.322984)
		(size 0.4572)
		(drill 0.2032)
		(layers "F.Cu" "B.Cu")
		(net "FPGA_BRD_REV1")
	)
	(via
		(at 113.919 -60.325)
		(size 0.508)
		(drill 0.254)
		(layers "F.Cu" "B.Cu")
		(net "FPGA_BRD_REV1")
	)
	(segment
		(start 113.919 -61.4426)
		(end 113.919 -60.325)
		(width 0.11938)
		(layer "B.Cu")
		(net "FPGA_BRD_REV1")
	)
	(segment
		(start 113.919 -61.4426)
		(end 115.062 -61.4426)
		(width 0.11938)
		(layer "B.Cu")
		(net "FPGA_BRD_REV1")
	)
	(segment
		(start 113.284 -56.515)
		(end 111.887 -55.118)
		(width 0.127)
		(layer "In2.Cu")
		(net "FPGA_BRD_REV1")
	)
	(segment
		(start 113.919 -60.325)
		(end 113.284 -59.69)
		(width 0.127)
		(layer "In2.Cu")
		(net "FPGA_BRD_REV1")
	)
	(segment
		(start 111.887 -53.99024)
		(end 111.887 -53.086)
		(width 0.1016)
		(layer "In2.Cu")
		(net "FPGA_BRD_REV1")
	)
	(segment
		(start 111.887 -53.086)
		(end 111.346996 -52.545996)
		(width 0.1016)
		(layer "In2.Cu")
		(net "FPGA_BRD_REV1")
	)
	(segment
		(start 113.284 -59.69)
		(end 113.284 -56.515)
		(width 0.127)
		(layer "In2.Cu")
		(net "FPGA_BRD_REV1")
	)
	(segment
		(start 111.887 -55.118)
		(end 111.887 -53.99024)
		(width 0.127)
		(layer "In2.Cu")
		(net "FPGA_BRD_REV1")
	)
	(segment
		(start 111.346996 -52.545996)
		(end 111.346996 -52.322984)
		(width 0.1016)
		(layer "In2.Cu")
		(net "FPGA_BRD_REV1")
	)
	(segment
		(start 110.847124 -52.82311)
		(end 111.346996 -53.322982)
		(width 0.11938)
		(layer "F.Cu")
		(net "FPGA_BRD_REV0")
	)
	(via
		(at 110.934246 -57.15)
		(size 0.762)
		(drill 0.381)
		(layers "F.Cu" "B.Cu")
		(net "FPGA_BRD_REV0")
	)
	(via
		(at 111.346996 -53.322982)
		(size 0.4572)
		(drill 0.2032)
		(layers "F.Cu" "B.Cu")
		(net "FPGA_BRD_REV0")
	)
	(segment
		(start 111.346996 -53.322982)
		(end 110.87354 -53.796438)
		(width 0.11938)
		(layer "B.Cu")
		(net "FPGA_BRD_REV0")
	)
	(segment
		(start 110.87354 -53.796438)
		(end 110.87354 -57.089294)
		(width 0.11938)
		(layer "B.Cu")
		(net "FPGA_BRD_REV0")
	)
	(segment
		(start 110.934246 -57.15)
		(end 111.69269 -57.908444)
		(width 0.11938)
		(layer "B.Cu")
		(net "FPGA_BRD_REV0")
	)
	(segment
		(start 111.69269 -57.908444)
		(end 111.69269 -60.665614)
		(width 0.11938)
		(layer "B.Cu")
		(net "FPGA_BRD_REV0")
	)
	(segment
		(start 110.87354 -57.089294)
		(end 110.934246 -57.15)
		(width 0.11938)
		(layer "B.Cu")
		(net "FPGA_BRD_REV0")
	)
	(segment
		(start 111.633 -60.725304)
		(end 111.633 -61.4426)
		(width 0.11938)
		(layer "B.Cu")
		(net "FPGA_BRD_REV0")
	)
	(segment
		(start 111.69269 -60.665614)
		(end 111.633 -60.725304)
		(width 0.11938)
		(layer "B.Cu")
		(net "FPGA_BRD_REV0")
	)
	(segment
		(start 112.776 -61.4426)
		(end 111.633 -61.4426)
		(width 0.11938)
		(layer "B.Cu")
		(net "FPGA_BRD_REV0")
	)
	(segment
		(start 125.9586 -33.909)
		(end 124.70638 -33.909)
		(width 0.11938)
		(layer "F.Cu")
		(net "CFGBVS")
	)
	(segment
		(start 114.847116 -40.823134)
		(end 115.346988 -40.323262)
		(width 0.11938)
		(layer "F.Cu")
		(net "CFGBVS")
	)
	(via
		(at 115.346988 -40.323262)
		(size 0.4572)
		(drill 0.2032)
		(layers "F.Cu" "B.Cu")
		(net "CFGBVS")
	)
	(via
		(at 124.70638 -33.909)
		(size 0.4572)
		(drill 0.2032)
		(layers "F.Cu" "B.Cu")
		(net "CFGBVS")
	)
	(segment
		(start 115.824 -39.079424)
		(end 115.824 -39.751)
		(width 0.127)
		(layer "In2.Cu")
		(net "CFGBVS")
	)
	(segment
		(start 115.824 -39.751)
		(end 115.346988 -40.228012)
		(width 0.127)
		(layer "In2.Cu")
		(net "CFGBVS")
	)
	(segment
		(start 115.346988 -40.228012)
		(end 115.346988 -40.323262)
		(width 0.127)
		(layer "In2.Cu")
		(net "CFGBVS")
	)
	(segment
		(start 116.080286 -38.823138)
		(end 115.824 -39.079424)
		(width 0.127)
		(layer "In2.Cu")
		(net "CFGBVS")
	)
	(segment
		(start 117.856 -38.481)
		(end 117.513862 -38.823138)
		(width 0.127)
		(layer "In2.Cu")
		(net "CFGBVS")
	)
	(segment
		(start 117.513862 -38.823138)
		(end 116.080286 -38.823138)
		(width 0.127)
		(layer "In2.Cu")
		(net "CFGBVS")
	)
	(segment
		(start 123.842272 -33.909)
		(end 120.94718 -36.8046)
		(width 0.127)
		(layer "In2.Cu")
		(net "CFGBVS")
	)
	(segment
		(start 120.94718 -36.8046)
		(end 118.2116 -36.8046)
		(width 0.127)
		(layer "In2.Cu")
		(net "CFGBVS")
	)
	(segment
		(start 117.856 -37.1602)
		(end 117.856 -38.481)
		(width 0.127)
		(layer "In2.Cu")
		(net "CFGBVS")
	)
	(segment
		(start 124.70638 -33.909)
		(end 123.842272 -33.909)
		(width 0.127)
		(layer "In2.Cu")
		(net "CFGBVS")
	)
	(segment
		(start 118.2116 -36.8046)
		(end 117.856 -37.1602)
		(width 0.127)
		(layer "In2.Cu")
		(net "CFGBVS")
	)
	(segment
		(start 108.847128 -44.823126)
		(end 108.347256 -45.322998)
		(width 0.11938)
		(layer "F.Cu")
		(net "CCLK_0")
	)
	(via
		(at 110.871 -60.325)
		(size 0.508)
		(drill 0.254)
		(layers "F.Cu" "B.Cu")
		(net "CCLK_0")
	)
	(via
		(at 108.347256 -45.322998)
		(size 0.4572)
		(drill 0.2032)
		(layers "F.Cu" "B.Cu")
		(net "CCLK_0")
	)
	(segment
		(start 110.49 -61.4426)
		(end 110.49 -60.706)
		(width 0.11938)
		(layer "B.Cu")
		(net "CCLK_0")
	)
	(segment
		(start 110.49 -60.706)
		(end 110.871 -60.325)
		(width 0.11938)
		(layer "B.Cu")
		(net "CCLK_0")
	)
	(segment
		(start 109.2581 -46.233842)
		(end 108.347256 -45.322998)
		(width 0.127)
		(layer "In2.Cu")
		(net "CCLK_0")
	)
	(segment
		(start 109.2581 -58.7121)
		(end 109.2581 -46.233842)
		(width 0.127)
		(layer "In2.Cu")
		(net "CCLK_0")
	)
	(segment
		(start 110.871 -60.325)
		(end 109.2581 -58.7121)
		(width 0.127)
		(layer "In2.Cu")
		(net "CCLK_0")
	)
	(segment
		(start 89.217246 -45.402246)
		(end 88.011 -44.196)
		(width 0.11938)
		(layer "F.Cu")
		(net "XP5R0V_USB_CONN_DET")
	)
	(segment
		(start 90.2716 -46.155356)
		(end 90.2716 -45.402246)
		(width 0.11938)
		(layer "F.Cu")
		(net "XP5R0V_USB_CONN_DET")
	)
	(segment
		(start 89.817956 -47.889922)
		(end 89.817956 -46.609)
		(width 0.11938)
		(layer "F.Cu")
		(net "XP5R0V_USB_CONN_DET")
	)
	(segment
		(start 89.817956 -46.609)
		(end 90.2716 -46.155356)
		(width 0.11938)
		(layer "F.Cu")
		(net "XP5R0V_USB_CONN_DET")
	)
	(segment
		(start 90.2716 -45.402246)
		(end 89.217246 -45.402246)
		(width 0.11938)
		(layer "F.Cu")
		(net "XP5R0V_USB_CONN_DET")
	)
	(via
		(at 87.376 -26.162)
		(size 0.508)
		(drill 0.254)
		(layers "F.Cu" "B.Cu")
		(net "XP5R0V_USB_CONN_DET")
	)
	(via
		(at 159.639 -48.133)
		(size 0.508)
		(drill 0.254)
		(layers "F.Cu" "B.Cu")
		(net "XP5R0V_USB_CONN_DET")
	)
	(via
		(at 88.011 -44.196)
		(size 0.508)
		(drill 0.254)
		(layers "F.Cu" "B.Cu")
		(net "XP5R0V_USB_CONN_DET")
	)
	(segment
		(start 61.976 -55.7022)
		(end 61.976 -49.53)
		(width 0.11938)
		(layer "B.Cu")
		(net "XP5R0V_USB_CONN_DET")
	)
	(segment
		(start 87.05342 -45.15358)
		(end 88.011 -44.196)
		(width 0.11938)
		(layer "B.Cu")
		(net "XP5R0V_USB_CONN_DET")
	)
	(segment
		(start 74.477118 -45.15358)
		(end 87.05342 -45.15358)
		(width 0.11938)
		(layer "B.Cu")
		(net "XP5R0V_USB_CONN_DET")
	)
	(segment
		(start 158.877 -49.980596)
		(end 158.877 -48.895)
		(width 0.11938)
		(layer "B.Cu")
		(net "XP5R0V_USB_CONN_DET")
	)
	(segment
		(start 67.564 -43.942)
		(end 73.265538 -43.942)
		(width 0.11938)
		(layer "B.Cu")
		(net "XP5R0V_USB_CONN_DET")
	)
	(segment
		(start 61.976 -49.53)
		(end 67.564 -43.942)
		(width 0.11938)
		(layer "B.Cu")
		(net "XP5R0V_USB_CONN_DET")
	)
	(segment
		(start 160.02 -49.980596)
		(end 158.877 -49.980596)
		(width 0.11938)
		(layer "B.Cu")
		(net "XP5R0V_USB_CONN_DET")
	)
	(segment
		(start 158.877 -48.895)
		(end 159.639 -48.133)
		(width 0.11938)
		(layer "B.Cu")
		(net "XP5R0V_USB_CONN_DET")
	)
	(segment
		(start 73.265538 -43.942)
		(end 74.477118 -45.15358)
		(width 0.11938)
		(layer "B.Cu")
		(net "XP5R0V_USB_CONN_DET")
	)
	(segment
		(start 96.266 -33.655)
		(end 96.266 -31.369)
		(width 0.127)
		(layer "In2.Cu")
		(net "XP5R0V_USB_CONN_DET")
	)
	(segment
		(start 90.678 -36.703)
		(end 91.948 -35.433)
		(width 0.127)
		(layer "In2.Cu")
		(net "XP5R0V_USB_CONN_DET")
	)
	(segment
		(start 87.757 -43.942)
		(end 87.757 -38.608)
		(width 0.127)
		(layer "In2.Cu")
		(net "XP5R0V_USB_CONN_DET")
	)
	(segment
		(start 92.329 -26.797)
		(end 91.313 -25.781)
		(width 0.127)
		(layer "In2.Cu")
		(net "XP5R0V_USB_CONN_DET")
	)
	(segment
		(start 91.948 -35.433)
		(end 94.488 -35.433)
		(width 0.127)
		(layer "In2.Cu")
		(net "XP5R0V_USB_CONN_DET")
	)
	(segment
		(start 87.63 -26.162)
		(end 87.376 -26.162)
		(width 0.127)
		(layer "In2.Cu")
		(net "XP5R0V_USB_CONN_DET")
	)
	(segment
		(start 88.011 -25.781)
		(end 87.63 -26.162)
		(width 0.127)
		(layer "In2.Cu")
		(net "XP5R0V_USB_CONN_DET")
	)
	(segment
		(start 92.329 -27.432)
		(end 92.329 -26.797)
		(width 0.127)
		(layer "In2.Cu")
		(net "XP5R0V_USB_CONN_DET")
	)
	(segment
		(start 96.266 -31.369)
		(end 92.329 -27.432)
		(width 0.127)
		(layer "In2.Cu")
		(net "XP5R0V_USB_CONN_DET")
	)
	(segment
		(start 88.011 -44.196)
		(end 87.757 -43.942)
		(width 0.127)
		(layer "In2.Cu")
		(net "XP5R0V_USB_CONN_DET")
	)
	(segment
		(start 91.313 -25.781)
		(end 88.011 -25.781)
		(width 0.127)
		(layer "In2.Cu")
		(net "XP5R0V_USB_CONN_DET")
	)
	(segment
		(start 94.488 -35.433)
		(end 96.266 -33.655)
		(width 0.127)
		(layer "In2.Cu")
		(net "XP5R0V_USB_CONN_DET")
	)
	(segment
		(start 89.662 -36.703)
		(end 90.678 -36.703)
		(width 0.127)
		(layer "In2.Cu")
		(net "XP5R0V_USB_CONN_DET")
	)
	(segment
		(start 87.757 -38.608)
		(end 89.662 -36.703)
		(width 0.127)
		(layer "In2.Cu")
		(net "XP5R0V_USB_CONN_DET")
	)
	(segment
		(start 91.059 -19.6342)
		(end 94.58706 -16.10614)
		(width 0.127)
		(layer "In7.Cu")
		(net "XP5R0V_USB_CONN_DET")
	)
	(segment
		(start 91.059 -21.844)
		(end 91.059 -19.6342)
		(width 0.127)
		(layer "In7.Cu")
		(net "XP5R0V_USB_CONN_DET")
	)
	(segment
		(start 147.0279 -20.7899)
		(end 159.2199 -20.7899)
		(width 0.127)
		(layer "In7.Cu")
		(net "XP5R0V_USB_CONN_DET")
	)
	(segment
		(start 162.687 -24.257)
		(end 162.687 -41.656)
		(width 0.127)
		(layer "In7.Cu")
		(net "XP5R0V_USB_CONN_DET")
	)
	(segment
		(start 94.58706 -16.10614)
		(end 121.16054 -16.10614)
		(width 0.127)
		(layer "In7.Cu")
		(net "XP5R0V_USB_CONN_DET")
	)
	(segment
		(start 143.54556 -17.30756)
		(end 147.0279 -20.7899)
		(width 0.127)
		(layer "In7.Cu")
		(net "XP5R0V_USB_CONN_DET")
	)
	(segment
		(start 140.8557 -17.30756)
		(end 143.54556 -17.30756)
		(width 0.127)
		(layer "In7.Cu")
		(net "XP5R0V_USB_CONN_DET")
	)
	(segment
		(start 121.16054 -16.10614)
		(end 123.59386 -18.53946)
		(width 0.127)
		(layer "In7.Cu")
		(net "XP5R0V_USB_CONN_DET")
	)
	(segment
		(start 123.59386 -18.53946)
		(end 139.6238 -18.53946)
		(width 0.127)
		(layer "In7.Cu")
		(net "XP5R0V_USB_CONN_DET")
	)
	(segment
		(start 162.687 -41.656)
		(end 159.639 -44.704)
		(width 0.127)
		(layer "In7.Cu")
		(net "XP5R0V_USB_CONN_DET")
	)
	(segment
		(start 87.376 -26.162)
		(end 87.376 -25.527)
		(width 0.127)
		(layer "In7.Cu")
		(net "XP5R0V_USB_CONN_DET")
	)
	(segment
		(start 159.639 -44.704)
		(end 159.639 -48.133)
		(width 0.127)
		(layer "In7.Cu")
		(net "XP5R0V_USB_CONN_DET")
	)
	(segment
		(start 159.2199 -20.7899)
		(end 162.687 -24.257)
		(width 0.127)
		(layer "In7.Cu")
		(net "XP5R0V_USB_CONN_DET")
	)
	(segment
		(start 139.6238 -18.53946)
		(end 140.8557 -17.30756)
		(width 0.127)
		(layer "In7.Cu")
		(net "XP5R0V_USB_CONN_DET")
	)
	(segment
		(start 87.376 -25.527)
		(end 91.059 -21.844)
		(width 0.127)
		(layer "In7.Cu")
		(net "XP5R0V_USB_CONN_DET")
	)
	(segment
		(start 159.255206 -55.134002)
		(end 158.9532 -54.831996)
		(width 0.381)
		(layer "F.Cu")
		(net "XP5R0V_USB_CONN")
	)
	(segment
		(start 159.255206 -55.926736)
		(end 159.255206 -55.134002)
		(width 0.381)
		(layer "F.Cu")
		(net "XP5R0V_USB_CONN")
	)
	(segment
		(start 162.8267 -52.300124)
		(end 160.909 -52.300124)
		(width 0.381)
		(layer "F.Cu")
		(net "XP5R0V_USB_CONN")
	)
	(via
		(at 159.385 -52.164996)
		(size 0.508)
		(drill 0.254)
		(layers "F.Cu" "B.Cu")
		(net "XP5R0V_USB_CONN")
	)
	(via
		(at 160.909 -52.300124)
		(size 0.4572)
		(drill 0.2032)
		(layers "F.Cu" "B.Cu")
		(net "XP5R0V_USB_CONN")
	)
	(via
		(at 158.9532 -54.831996)
		(size 0.4572)
		(drill 0.2032)
		(layers "F.Cu" "B.Cu")
		(net "XP5R0V_USB_CONN")
	)
	(segment
		(start 159.385 -54.400196)
		(end 159.385 -52.164996)
		(width 0.381)
		(layer "B.Cu")
		(net "XP5R0V_USB_CONN")
	)
	(segment
		(start 160.02 -51.148996)
		(end 160.02 -51.047396)
		(width 0.381)
		(layer "B.Cu")
		(net "XP5R0V_USB_CONN")
	)
	(segment
		(start 160.909 -52.037996)
		(end 160.02 -51.148996)
		(width 0.381)
		(layer "B.Cu")
		(net "XP5R0V_USB_CONN")
	)
	(segment
		(start 158.9532 -54.831996)
		(end 159.385 -54.400196)
		(width 0.381)
		(layer "B.Cu")
		(net "XP5R0V_USB_CONN")
	)
	(segment
		(start 160.909 -52.300124)
		(end 160.909 -52.037996)
		(width 0.381)
		(layer "B.Cu")
		(net "XP5R0V_USB_CONN")
	)
	(segment
		(start 45.0596 -100.9904)
		(end 44.958 -101.092)
		(width 0.381)
		(layer "F.Cu")
		(net "XP5R0V_SW")
	)
	(segment
		(start 46.834298 -100.9904)
		(end 45.0596 -100.9904)
		(width 0.381)
		(layer "F.Cu")
		(net "XP5R0V_SW")
	)
	(via
		(at 44.958 -101.092)
		(size 0.508)
		(drill 0.254)
		(layers "F.Cu" "B.Cu")
		(net "XP5R0V_SW")
	)
	(via
		(at 44.45 -100.203)
		(size 0.508)
		(drill 0.254)
		(layers "F.Cu" "B.Cu")
		(net "XP5R0V_SW")
	)
	(segment
		(start 44.8564 -99.7966)
		(end 44.45 -100.203)
		(width 0.381)
		(layer "B.Cu")
		(net "XP5R0V_SW")
	)
	(segment
		(start 45.72 -102.2096)
		(end 45.72 -101.473)
		(width 0.381)
		(layer "B.Cu")
		(net "XP5R0V_SW")
	)
	(segment
		(start 45.72 -101.473)
		(end 45.339 -101.092)
		(width 0.381)
		(layer "B.Cu")
		(net "XP5R0V_SW")
	)
	(segment
		(start 45.339 -101.092)
		(end 44.958 -101.092)
		(width 0.381)
		(layer "B.Cu")
		(net "XP5R0V_SW")
	)
	(segment
		(start 44.8564 -99.314)
		(end 44.8564 -99.7966)
		(width 0.381)
		(layer "B.Cu")
		(net "XP5R0V_SW")
	)
	(segment
		(start 38.9001 -100.22586)
		(end 39.160704 -100.486464)
		(width 0.254)
		(layer "F.Cu")
		(net "XP5R0V_SS")
	)
	(segment
		(start 39.160704 -100.486464)
		(end 40.158416 -100.486464)
		(width 0.254)
		(layer "F.Cu")
		(net "XP5R0V_SS")
	)
	(segment
		(start 37.5158 -101.3714)
		(end 37.8968 -100.9904)
		(width 0.3048)
		(layer "F.Cu")
		(net "XP5R0V_SS")
	)
	(segment
		(start 38.13556 -100.9904)
		(end 38.9001 -100.22586)
		(width 0.3048)
		(layer "F.Cu")
		(net "XP5R0V_SS")
	)
	(segment
		(start 37.8968 -100.9904)
		(end 38.13556 -100.9904)
		(width 0.3048)
		(layer "F.Cu")
		(net "XP5R0V_SS")
	)
	(via
		(at 38.9001 -100.22586)
		(size 0.4572)
		(drill 0.2032)
		(layers "F.Cu" "B.Cu")
		(net "XP5R0V_SS")
	)
	(segment
		(start 38.7096 -104.648)
		(end 39.5224 -104.648)
		(width 0.381)
		(layer "F.Cu")
		(net "XP5R0V_RT")
	)
	(segment
		(start 38.5318 -104.2416)
		(end 39.497 -103.2764)
		(width 0.254)
		(layer "F.Cu")
		(net "XP5R0V_RT")
	)
	(segment
		(start 39.497 -103.2764)
		(end 39.497 -102.772718)
		(width 0.254)
		(layer "F.Cu")
		(net "XP5R0V_RT")
	)
	(segment
		(start 39.497 -102.772718)
		(end 40.158416 -102.111302)
		(width 0.254)
		(layer "F.Cu")
		(net "XP5R0V_RT")
	)
	(segment
		(start 38.5318 -104.4702)
		(end 38.7096 -104.648)
		(width 0.381)
		(layer "F.Cu")
		(net "XP5R0V_RT")
	)
	(segment
		(start 38.5318 -104.4702)
		(end 38.5318 -104.2416)
		(width 0.254)
		(layer "F.Cu")
		(net "XP5R0V_RT")
	)
	(via
		(at 38.5318 -104.4702)
		(size 0.508)
		(drill 0.254)
		(layers "F.Cu" "B.Cu")
		(net "XP5R0V_RT")
	)
	(segment
		(start 40.158416 -99.361498)
		(end 39.348918 -98.552)
		(width 0.11938)
		(layer "F.Cu")
		(net "XP5R0V_PG")
	)
	(segment
		(start 37.374322 -99.0854)
		(end 37.374322 -98.546666)
		(width 0.11938)
		(layer "F.Cu")
		(net "XP5R0V_PG")
	)
	(segment
		(start 39.0652 -98.552)
		(end 38.629082 -98.115882)
		(width 0.11938)
		(layer "F.Cu")
		(net "XP5R0V_PG")
	)
	(segment
		(start 37.2618 -98.434144)
		(end 37.2618 -97.8154)
		(width 0.11938)
		(layer "F.Cu")
		(net "XP5R0V_PG")
	)
	(segment
		(start 38.383718 -98.115882)
		(end 38.3794 -98.1202)
		(width 0.11938)
		(layer "F.Cu")
		(net "XP5R0V_PG")
	)
	(segment
		(start 38.083236 -97.8154)
		(end 37.2618 -97.8154)
		(width 0.11938)
		(layer "F.Cu")
		(net "XP5R0V_PG")
	)
	(segment
		(start 39.348918 -98.552)
		(end 39.0652 -98.552)
		(width 0.11938)
		(layer "F.Cu")
		(net "XP5R0V_PG")
	)
	(segment
		(start 38.383718 -98.115882)
		(end 38.083236 -97.8154)
		(width 0.11938)
		(layer "F.Cu")
		(net "XP5R0V_PG")
	)
	(segment
		(start 37.374322 -98.546666)
		(end 37.2618 -98.434144)
		(width 0.11938)
		(layer "F.Cu")
		(net "XP5R0V_PG")
	)
	(segment
		(start 38.629082 -98.115882)
		(end 38.383718 -98.115882)
		(width 0.11938)
		(layer "F.Cu")
		(net "XP5R0V_PG")
	)
	(via
		(at 38.3794 -98.1202)
		(size 0.4572)
		(drill 0.2032)
		(layers "F.Cu" "B.Cu")
		(net "XP5R0V_PG")
	)
	(segment
		(start 38.0746 -97.8154)
		(end 38.3794 -98.1202)
		(width 0.11938)
		(layer "B.Cu")
		(net "XP5R0V_PG")
	)
	(segment
		(start 37.2618 -97.8154)
		(end 38.0746 -97.8154)
		(width 0.11938)
		(layer "B.Cu")
		(net "XP5R0V_PG")
	)
	(segment
		(start 37.247322 -104.938322)
		(end 37.247322 -103.7844)
		(width 0.254)
		(layer "F.Cu")
		(net "XP5R0V_FB_R_TO_AGND")
	)
	(segment
		(start 38.48862 -102.48138)
		(end 39.483538 -101.486462)
		(width 0.254)
		(layer "F.Cu")
		(net "XP5R0V_FB_R_TO_AGND")
	)
	(segment
		(start 38.48862 -103.2002)
		(end 38.48862 -102.48138)
		(width 0.254)
		(layer "F.Cu")
		(net "XP5R0V_FB_R_TO_AGND")
	)
	(segment
		(start 39.483538 -101.486462)
		(end 40.158416 -101.486462)
		(width 0.254)
		(layer "F.Cu")
		(net "XP5R0V_FB_R_TO_AGND")
	)
	(segment
		(start 37.247322 -103.7844)
		(end 37.831522 -103.2002)
		(width 0.254)
		(layer "F.Cu")
		(net "XP5R0V_FB_R_TO_AGND")
	)
	(segment
		(start 37.831522 -103.2002)
		(end 38.48862 -103.2002)
		(width 0.254)
		(layer "F.Cu")
		(net "XP5R0V_FB_R_TO_AGND")
	)
	(segment
		(start 37.5158 -105.2068)
		(end 37.247322 -104.938322)
		(width 0.254)
		(layer "F.Cu")
		(net "XP5R0V_FB_R_TO_AGND")
	)
	(via
		(at 38.48862 -103.2002)
		(size 0.4572)
		(drill 0.2032)
		(layers "F.Cu" "B.Cu")
		(net "XP5R0V_FB_R_TO_AGND")
	)
	(segment
		(start 37.5158 -105.2068)
		(end 37.3888 -105.0798)
		(width 0.254)
		(layer "B.Cu")
		(net "XP5R0V_FB_R_TO_AGND")
	)
	(segment
		(start 37.3888 -105.0798)
		(end 37.3888 -103.886)
		(width 0.254)
		(layer "B.Cu")
		(net "XP5R0V_FB_R_TO_AGND")
	)
	(segment
		(start 38.0746 -103.2002)
		(end 37.3888 -103.886)
		(width 0.254)
		(layer "B.Cu")
		(net "XP5R0V_FB_R_TO_AGND")
	)
	(segment
		(start 38.48862 -103.2002)
		(end 38.0746 -103.2002)
		(width 0.254)
		(layer "B.Cu")
		(net "XP5R0V_FB_R_TO_AGND")
	)
	(segment
		(start 37.374322 -102.3874)
		(end 37.6682 -102.3874)
		(width 0.2032)
		(layer "F.Cu")
		(net "XP5R0V_COMP")
	)
	(segment
		(start 38.6334 -101.4222)
		(end 39.069264 -100.986336)
		(width 0.2032)
		(layer "F.Cu")
		(net "XP5R0V_COMP")
	)
	(segment
		(start 39.069264 -100.986336)
		(end 40.158416 -100.986336)
		(width 0.2032)
		(layer "F.Cu")
		(net "XP5R0V_COMP")
	)
	(segment
		(start 37.6682 -102.3874)
		(end 38.6334 -101.4222)
		(width 0.2032)
		(layer "F.Cu")
		(net "XP5R0V_COMP")
	)
	(via
		(at 38.6334 -101.4222)
		(size 0.4572)
		(drill 0.2032)
		(layers "F.Cu" "B.Cu")
		(net "XP5R0V_COMP")
	)
	(segment
		(start 38.5826 -101.3714)
		(end 37.5158 -101.3714)
		(width 0.2032)
		(layer "B.Cu")
		(net "XP5R0V_COMP")
	)
	(segment
		(start 38.6334 -101.4222)
		(end 38.5826 -101.3714)
		(width 0.2032)
		(layer "B.Cu")
		(net "XP5R0V_COMP")
	)
	(segment
		(start 40.2844 -98.3996)
		(end 40.1066 -98.3996)
		(width 0.2032)
		(layer "F.Cu")
		(net "XP5R0V_BT")
	)
	(segment
		(start 40.85844 -99.086416)
		(end 40.85844 -98.97364)
		(width 0.2032)
		(layer "F.Cu")
		(net "XP5R0V_BT")
	)
	(segment
		(start 40.85844 -98.97364)
		(end 40.2844 -98.3996)
		(width 0.2032)
		(layer "F.Cu")
		(net "XP5R0V_BT")
	)
	(via
		(at 40.1066 -98.3996)
		(size 0.508)
		(drill 0.254)
		(layers "F.Cu" "B.Cu")
		(net "XP5R0V_BT")
	)
	(segment
		(start 40.386 -98.679)
		(end 40.1066 -98.3996)
		(width 0.381)
		(layer "B.Cu")
		(net "XP5R0V_BT")
	)
	(segment
		(start 41.2496 -98.679)
		(end 40.386 -98.679)
		(width 0.381)
		(layer "B.Cu")
		(net "XP5R0V_BT")
	)
	(segment
		(start 36.449 -101.3714)
		(end 36.0426 -101.3714)
		(width 0.381)
		(layer "F.Cu")
		(net "XP5R0V_AGND")
	)
	(segment
		(start 36.0426 -101.3714)
		(end 35.56 -101.854)
		(width 0.381)
		(layer "F.Cu")
		(net "XP5R0V_AGND")
	)
	(segment
		(start 38.6842 -105.7148)
		(end 38.6588 -105.7402)
		(width 0.381)
		(layer "F.Cu")
		(net "XP5R0V_AGND")
	)
	(segment
		(start 36.449 -101.991922)
		(end 36.449 -101.3714)
		(width 0.3048)
		(layer "F.Cu")
		(net "XP5R0V_AGND")
	)
	(segment
		(start 40.324024 -102.9208)
		(end 40.259 -102.9208)
		(width 0.254)
		(layer "F.Cu")
		(net "XP5R0V_AGND")
	)
	(segment
		(start 40.85844 -102.386384)
		(end 40.324024 -102.9208)
		(width 0.254)
		(layer "F.Cu")
		(net "XP5R0V_AGND")
	)
	(segment
		(start 39.5224 -105.7148)
		(end 38.6842 -105.7148)
		(width 0.381)
		(layer "F.Cu")
		(net "XP5R0V_AGND")
	)
	(segment
		(start 36.844478 -102.3874)
		(end 36.449 -101.991922)
		(width 0.3048)
		(layer "F.Cu")
		(net "XP5R0V_AGND")
	)
	(via
		(at 40.259 -102.9208)
		(size 0.508)
		(drill 0.254)
		(layers "F.Cu" "B.Cu")
		(net "XP5R0V_AGND")
	)
	(via
		(at 35.56 -101.854)
		(size 0.508)
		(drill 0.254)
		(layers "F.Cu" "B.Cu")
		(net "XP5R0V_AGND")
	)
	(via
		(at 36.449 -106.172)
		(size 0.508)
		(drill 0.254)
		(layers "F.Cu" "B.Cu")
		(net "XP5R0V_AGND")
	)
	(via
		(at 38.6588 -105.7402)
		(size 0.4572)
		(drill 0.2032)
		(layers "F.Cu" "B.Cu")
		(net "XP5R0V_AGND")
	)
	(segment
		(start 39.7002 -102.9208)
		(end 40.259 -102.9208)
		(width 0.254)
		(layer "B.Cu")
		(net "XP5R0V_AGND")
	)
	(segment
		(start 37.5158 -102.5144)
		(end 37.719 -102.3112)
		(width 0.254)
		(layer "B.Cu")
		(net "XP5R0V_AGND")
	)
	(segment
		(start 36.2966 -104.1654)
		(end 36.0172 -103.886)
		(width 0.381)
		(layer "B.Cu")
		(net "XP5R0V_AGND")
	)
	(segment
		(start 36.449 -106.172)
		(end 36.449 -105.2068)
		(width 0.381)
		(layer "B.Cu")
		(net "XP5R0V_AGND")
	)
	(segment
		(start 37.719 -102.3112)
		(end 39.0906 -102.3112)
		(width 0.254)
		(layer "B.Cu")
		(net "XP5R0V_AGND")
	)
	(segment
		(start 39.0906 -102.3112)
		(end 39.7002 -102.9208)
		(width 0.254)
		(layer "B.Cu")
		(net "XP5R0V_AGND")
	)
	(segment
		(start 36.2966 -105.0544)
		(end 36.2966 -104.1654)
		(width 0.381)
		(layer "B.Cu")
		(net "XP5R0V_AGND")
	)
	(segment
		(start 36.449 -105.2068)
		(end 36.2966 -105.0544)
		(width 0.381)
		(layer "B.Cu")
		(net "XP5R0V_AGND")
	)
	(segment
		(start 35.179 -104.8004)
		(end 34.3154 -104.8004)
		(width 0.381)
		(layer "F.Cu")
		(net "XP5R0V")
	)
	(via
		(at 82.423 -75.057)
		(size 0.508)
		(drill 0.254)
		(layers "F.Cu" "B.Cu")
		(net "XP5R0V")
	)
	(via
		(at 55.626 -99.695)
		(size 0.508)
		(drill 0.254)
		(layers "F.Cu" "B.Cu")
		(net "XP5R0V")
	)
	(via
		(at 34.3154 -104.8004)
		(size 0.508)
		(drill 0.254)
		(layers "F.Cu" "B.Cu")
		(net "XP5R0V")
	)
	(via
		(at 80.645 -75.057)
		(size 0.508)
		(drill 0.254)
		(layers "F.Cu" "B.Cu")
		(net "XP5R0V")
	)
	(via
		(at 55.88 -100.584)
		(size 0.508)
		(drill 0.254)
		(layers "F.Cu" "B.Cu")
		(net "XP5R0V")
	)
	(via
		(at 81.534 -75.057)
		(size 0.508)
		(drill 0.254)
		(layers "F.Cu" "B.Cu")
		(net "XP5R0V")
	)
	(via
		(at 144.145 -102.362)
		(size 0.508)
		(drill 0.254)
		(layers "F.Cu" "B.Cu")
		(net "XP5R0V")
	)
	(via
		(at 131.572 -97.155)
		(size 0.508)
		(drill 0.254)
		(layers "F.Cu" "B.Cu")
		(net "XP5R0V")
	)
	(via
		(at 62.738 -87.503)
		(size 0.508)
		(drill 0.254)
		(layers "F.Cu" "B.Cu")
		(net "XP5R0V")
	)
	(via
		(at 39.624 -82.55)
		(size 0.508)
		(drill 0.254)
		(layers "F.Cu" "B.Cu")
		(net "XP5R0V")
	)
	(via
		(at 64.77 -87.503)
		(size 0.508)
		(drill 0.254)
		(layers "F.Cu" "B.Cu")
		(net "XP5R0V")
	)
	(via
		(at 54.991 -100.584)
		(size 0.508)
		(drill 0.254)
		(layers "F.Cu" "B.Cu")
		(net "XP5R0V")
	)
	(via
		(at 130.556 -94.996)
		(size 0.508)
		(drill 0.254)
		(layers "F.Cu" "B.Cu")
		(net "XP5R0V")
	)
	(via
		(at 63.754 -87.503)
		(size 0.508)
		(drill 0.254)
		(layers "F.Cu" "B.Cu")
		(net "XP5R0V")
	)
	(via
		(at 54.737 -99.695)
		(size 0.508)
		(drill 0.254)
		(layers "F.Cu" "B.Cu")
		(net "XP5R0V")
	)
	(via
		(at 39.624 -83.566)
		(size 0.508)
		(drill 0.254)
		(layers "F.Cu" "B.Cu")
		(net "XP5R0V")
	)
	(via
		(at 131.445 -94.996)
		(size 0.508)
		(drill 0.254)
		(layers "F.Cu" "B.Cu")
		(net "XP5R0V")
	)
	(via
		(at 65.786 -87.503)
		(size 0.508)
		(drill 0.254)
		(layers "F.Cu" "B.Cu")
		(net "XP5R0V")
	)
	(segment
		(start 144.145 -103.7336)
		(end 144.145 -102.362)
		(width 0.381)
		(layer "B.Cu")
		(net "XP5R0V")
	)
	(segment
		(start 143.637 -102.87)
		(end 144.145 -102.362)
		(width 0.381)
		(layer "In7.Cu")
		(net "XP5R0V")
	)
	(segment
		(start 137.287 -102.87)
		(end 143.637 -102.87)
		(width 0.381)
		(layer "In7.Cu")
		(net "XP5R0V")
	)
	(segment
		(start 133.6675 -102.0445)
		(end 136.4615 -102.0445)
		(width 0.381)
		(layer "In7.Cu")
		(net "XP5R0V")
	)
	(segment
		(start 131.572 -97.155)
		(end 131.572 -99.949)
		(width 0.381)
		(layer "In7.Cu")
		(net "XP5R0V")
	)
	(segment
		(start 54.991 -101.9556)
		(end 48.9966 -107.95)
		(width 0.381)
		(layer "In7.Cu")
		(net "XP5R0V")
	)
	(segment
		(start 54.991 -100.584)
		(end 54.991 -101.9556)
		(width 0.381)
		(layer "In7.Cu")
		(net "XP5R0V")
	)
	(segment
		(start 48.9966 -107.95)
		(end 36.322 -107.95)
		(width 0.381)
		(layer "In7.Cu")
		(net "XP5R0V")
	)
	(segment
		(start 34.29 -104.8258)
		(end 34.3154 -104.8004)
		(width 0.381)
		(layer "In7.Cu")
		(net "XP5R0V")
	)
	(segment
		(start 131.572 -99.949)
		(end 133.6675 -102.0445)
		(width 0.381)
		(layer "In7.Cu")
		(net "XP5R0V")
	)
	(segment
		(start 136.4615 -102.0445)
		(end 137.287 -102.87)
		(width 0.381)
		(layer "In7.Cu")
		(net "XP5R0V")
	)
	(segment
		(start 36.322 -107.95)
		(end 34.29 -105.918)
		(width 0.381)
		(layer "In7.Cu")
		(net "XP5R0V")
	)
	(segment
		(start 34.29 -105.918)
		(end 34.29 -104.8258)
		(width 0.381)
		(layer "In7.Cu")
		(net "XP5R0V")
	)
	(via
		(at 81.28 -101.219)
		(size 0.508)
		(drill 0.254)
		(layers "F.Cu" "B.Cu")
		(net "XP3R3V_SW")
	)
	(via
		(at 82.042 -101.981)
		(size 0.508)
		(drill 0.254)
		(layers "F.Cu" "B.Cu")
		(net "XP3R3V_SW")
	)
	(segment
		(start 82.042 -101.981)
		(end 82.042 -103.0224)
		(width 0.381)
		(layer "B.Cu")
		(net "XP3R3V_SW")
	)
	(segment
		(start 80.899 -100.838)
		(end 81.28 -101.219)
		(width 0.381)
		(layer "B.Cu")
		(net "XP3R3V_SW")
	)
	(segment
		(start 82.042 -103.0224)
		(end 82.3976 -103.378)
		(width 0.381)
		(layer "B.Cu")
		(net "XP3R3V_SW")
	)
	(segment
		(start 80.899 -99.5934)
		(end 80.899 -100.838)
		(width 0.381)
		(layer "B.Cu")
		(net "XP3R3V_SW")
	)
	(segment
		(start 88.345264 -102.154736)
		(end 88.773 -101.727)
		(width 0.254)
		(layer "F.Cu")
		(net "XP3R3V_SS")
	)
	(segment
		(start 88.773 -101.727)
		(end 89.0016 -101.727)
		(width 0.254)
		(layer "F.Cu")
		(net "XP3R3V_SS")
	)
	(segment
		(start 89.0016 -101.727)
		(end 89.4588 -101.2698)
		(width 0.254)
		(layer "F.Cu")
		(net "XP3R3V_SS")
	)
	(segment
		(start 86.816184 -102.154736)
		(end 88.345264 -102.154736)
		(width 0.254)
		(layer "F.Cu")
		(net "XP3R3V_SS")
	)
	(segment
		(start 87.4522 -97.9932)
		(end 87.4522 -99.893882)
		(width 0.254)
		(layer "F.Cu")
		(net "XP3R3V_RT")
	)
	(segment
		(start 87.4522 -99.893882)
		(end 86.816184 -100.529898)
		(width 0.254)
		(layer "F.Cu")
		(net "XP3R3V_RT")
	)
	(via
		(at 150.0251 -62.40272)
		(size 0.508)
		(drill 0.254)
		(layers "F.Cu" "B.Cu")
		(net "XP3R3V_PG")
	)
	(segment
		(start 91.2876 -106.6038)
		(end 91.2876 -105.9434)
		(width 0.11938)
		(layer "B.Cu")
		(net "XP3R3V_PG")
	)
	(segment
		(start 140.07338 -61.59246)
		(end 139.954 -61.47308)
		(width 0.11938)
		(layer "B.Cu")
		(net "XP3R3V_PG")
	)
	(segment
		(start 139.954 -61.47308)
		(end 139.954 -60.0964)
		(width 0.11938)
		(layer "B.Cu")
		(net "XP3R3V_PG")
	)
	(segment
		(start 143.370046 -61.59246)
		(end 140.07338 -61.59246)
		(width 0.11938)
		(layer "B.Cu")
		(net "XP3R3V_PG")
	)
	(segment
		(start 143.846804 -61.58611)
		(end 143.376396 -61.58611)
		(width 0.11938)
		(layer "B.Cu")
		(net "XP3R3V_PG")
	)
	(segment
		(start 93.472 -106.299)
		(end 95.123 -106.299)
		(width 0.11938)
		(layer "B.Cu")
		(net "XP3R3V_PG")
	)
	(segment
		(start 150.0251 -62.40272)
		(end 149.21484 -61.59246)
		(width 0.11938)
		(layer "B.Cu")
		(net "XP3R3V_PG")
	)
	(segment
		(start 143.853154 -61.59246)
		(end 143.846804 -61.58611)
		(width 0.11938)
		(layer "B.Cu")
		(net "XP3R3V_PG")
	)
	(segment
		(start 91.2876 -105.9434)
		(end 91.567 -105.664)
		(width 0.11938)
		(layer "B.Cu")
		(net "XP3R3V_PG")
	)
	(segment
		(start 149.21484 -61.59246)
		(end 143.853154 -61.59246)
		(width 0.11938)
		(layer "B.Cu")
		(net "XP3R3V_PG")
	)
	(segment
		(start 143.376396 -61.58611)
		(end 143.370046 -61.59246)
		(width 0.11938)
		(layer "B.Cu")
		(net "XP3R3V_PG")
	)
	(segment
		(start 91.567 -105.664)
		(end 92.837 -105.664)
		(width 0.11938)
		(layer "B.Cu")
		(net "XP3R3V_PG")
	)
	(segment
		(start 92.837 -105.664)
		(end 93.472 -106.299)
		(width 0.11938)
		(layer "B.Cu")
		(net "XP3R3V_PG")
	)
	(segment
		(start 144.08912 -88.8746)
		(end 144.6276 -88.33612)
		(width 0.127)
		(layer "In7.Cu")
		(net "XP3R3V_PG")
	)
	(segment
		(start 129.794 -92.82684)
		(end 132.89026 -89.73058)
		(width 0.127)
		(layer "In7.Cu")
		(net "XP3R3V_PG")
	)
	(segment
		(start 142.76832 -88.8746)
		(end 144.08912 -88.8746)
		(width 0.127)
		(layer "In7.Cu")
		(net "XP3R3V_PG")
	)
	(segment
		(start 128.7145 -96.9645)
		(end 129.794 -95.885)
		(width 0.127)
		(layer "In7.Cu")
		(net "XP3R3V_PG")
	)
	(segment
		(start 144.6276 -80.1624)
		(end 146.39798 -78.39202)
		(width 0.127)
		(layer "In7.Cu")
		(net "XP3R3V_PG")
	)
	(segment
		(start 149.352 -63.07582)
		(end 150.0251 -62.40272)
		(width 0.127)
		(layer "In7.Cu")
		(net "XP3R3V_PG")
	)
	(segment
		(start 95.123 -106.299)
		(end 97.409 -108.585)
		(width 0.127)
		(layer "In7.Cu")
		(net "XP3R3V_PG")
	)
	(segment
		(start 148.45538 -76.96962)
		(end 148.45538 -76.073)
		(width 0.127)
		(layer "In7.Cu")
		(net "XP3R3V_PG")
	)
	(segment
		(start 129.794 -95.885)
		(end 129.794 -92.82684)
		(width 0.127)
		(layer "In7.Cu")
		(net "XP3R3V_PG")
	)
	(segment
		(start 97.409 -108.585)
		(end 113.665 -108.585)
		(width 0.127)
		(layer "In7.Cu")
		(net "XP3R3V_PG")
	)
	(segment
		(start 146.39798 -78.39202)
		(end 147.03298 -78.39202)
		(width 0.127)
		(layer "In7.Cu")
		(net "XP3R3V_PG")
	)
	(segment
		(start 132.89026 -89.73058)
		(end 141.91234 -89.73058)
		(width 0.127)
		(layer "In7.Cu")
		(net "XP3R3V_PG")
	)
	(segment
		(start 113.665 -108.585)
		(end 125.2855 -96.9645)
		(width 0.127)
		(layer "In7.Cu")
		(net "XP3R3V_PG")
	)
	(segment
		(start 125.2855 -96.9645)
		(end 128.7145 -96.9645)
		(width 0.127)
		(layer "In7.Cu")
		(net "XP3R3V_PG")
	)
	(segment
		(start 148.45538 -76.073)
		(end 149.352 -75.17638)
		(width 0.127)
		(layer "In7.Cu")
		(net "XP3R3V_PG")
	)
	(segment
		(start 149.352 -75.17638)
		(end 149.352 -63.07582)
		(width 0.127)
		(layer "In7.Cu")
		(net "XP3R3V_PG")
	)
	(segment
		(start 144.6276 -88.33612)
		(end 144.6276 -80.1624)
		(width 0.127)
		(layer "In7.Cu")
		(net "XP3R3V_PG")
	)
	(segment
		(start 147.03298 -78.39202)
		(end 148.45538 -76.96962)
		(width 0.127)
		(layer "In7.Cu")
		(net "XP3R3V_PG")
	)
	(segment
		(start 141.91234 -89.73058)
		(end 142.76832 -88.8746)
		(width 0.127)
		(layer "In7.Cu")
		(net "XP3R3V_PG")
	)
	(segment
		(start 87.9602 -99.5426)
		(end 88.138 -99.3648)
		(width 0.254)
		(layer "F.Cu")
		(net "XP3R3V_FB_R_TO_AGND")
	)
	(segment
		(start 88.138 -99.3648)
		(end 89.092278 -99.3648)
		(width 0.254)
		(layer "F.Cu")
		(net "XP3R3V_FB_R_TO_AGND")
	)
	(segment
		(start 89.5477 -96.2787)
		(end 89.8144 -96.012)
		(width 0.381)
		(layer "F.Cu")
		(net "XP3R3V_FB_R_TO_AGND")
	)
	(segment
		(start 86.816184 -101.154738)
		(end 87.414862 -101.154738)
		(width 0.254)
		(layer "F.Cu")
		(net "XP3R3V_FB_R_TO_AGND")
	)
	(segment
		(start 89.092278 -99.3648)
		(end 89.600278 -98.8568)
		(width 0.254)
		(layer "F.Cu")
		(net "XP3R3V_FB_R_TO_AGND")
	)
	(segment
		(start 89.4588 -98.044)
		(end 89.4588 -97.3582)
		(width 0.254)
		(layer "F.Cu")
		(net "XP3R3V_FB_R_TO_AGND")
	)
	(segment
		(start 87.414862 -101.154738)
		(end 87.9602 -100.6094)
		(width 0.254)
		(layer "F.Cu")
		(net "XP3R3V_FB_R_TO_AGND")
	)
	(segment
		(start 87.9602 -100.6094)
		(end 87.9602 -99.5426)
		(width 0.254)
		(layer "F.Cu")
		(net "XP3R3V_FB_R_TO_AGND")
	)
	(segment
		(start 89.4588 -97.3582)
		(end 89.4588 -96.6978)
		(width 0.381)
		(layer "F.Cu")
		(net "XP3R3V_FB_R_TO_AGND")
	)
	(segment
		(start 89.4588 -96.6978)
		(end 89.5477 -96.6089)
		(width 0.381)
		(layer "F.Cu")
		(net "XP3R3V_FB_R_TO_AGND")
	)
	(segment
		(start 89.600278 -98.8568)
		(end 89.600278 -98.185478)
		(width 0.254)
		(layer "F.Cu")
		(net "XP3R3V_FB_R_TO_AGND")
	)
	(segment
		(start 89.600278 -98.185478)
		(end 89.4588 -98.044)
		(width 0.254)
		(layer "F.Cu")
		(net "XP3R3V_FB_R_TO_AGND")
	)
	(segment
		(start 89.5477 -96.6089)
		(end 89.5477 -96.2787)
		(width 0.381)
		(layer "F.Cu")
		(net "XP3R3V_FB_R_TO_AGND")
	)
	(via
		(at 88.138 -99.3648)
		(size 0.508)
		(drill 0.254)
		(layers "F.Cu" "B.Cu")
		(net "XP3R3V_FB_R_TO_AGND")
	)
	(segment
		(start 88.6714 -99.3648)
		(end 88.138 -99.3648)
		(width 0.254)
		(layer "B.Cu")
		(net "XP3R3V_FB_R_TO_AGND")
	)
	(segment
		(start 89.3064 -98.7298)
		(end 88.6714 -99.3648)
		(width 0.254)
		(layer "B.Cu")
		(net "XP3R3V_FB_R_TO_AGND")
	)
	(segment
		(start 89.4588 -103.5558)
		(end 89.4588 -102.4128)
		(width 0.11938)
		(layer "F.Cu")
		(net "XP3R3V_EN")
	)
	(segment
		(start 88.075516 -102.654862)
		(end 88.462866 -103.042212)
		(width 0.11938)
		(layer "F.Cu")
		(net "XP3R3V_EN")
	)
	(segment
		(start 86.816184 -102.654862)
		(end 88.075516 -102.654862)
		(width 0.11938)
		(layer "F.Cu")
		(net "XP3R3V_EN")
	)
	(segment
		(start 88.462866 -103.042212)
		(end 89.092278 -102.4128)
		(width 0.11938)
		(layer "F.Cu")
		(net "XP3R3V_EN")
	)
	(segment
		(start 89.092278 -102.4128)
		(end 89.4588 -102.4128)
		(width 0.11938)
		(layer "F.Cu")
		(net "XP3R3V_EN")
	)
	(via
		(at 88.462866 -103.042212)
		(size 0.508)
		(drill 0.254)
		(layers "F.Cu" "B.Cu")
		(net "XP3R3V_EN")
	)
	(segment
		(start 89.092278 -102.4128)
		(end 88.462866 -103.042212)
		(width 0.11938)
		(layer "B.Cu")
		(net "XP3R3V_EN")
	)
	(segment
		(start 89.4588 -102.4128)
		(end 89.092278 -102.4128)
		(width 0.11938)
		(layer "B.Cu")
		(net "XP3R3V_EN")
	)
	(segment
		(start 89.4588 -102.4128)
		(end 89.4588 -103.5558)
		(width 0.11938)
		(layer "B.Cu")
		(net "XP3R3V_EN")
	)
	(segment
		(start 90.322654 -104.902)
		(end 88.462866 -103.042212)
		(width 0.127)
		(layer "In7.Cu")
		(net "XP3R3V_EN")
	)
	(segment
		(start 93.726 -105.029)
		(end 93.091 -105.664)
		(width 0.127)
		(layer "In7.Cu")
		(net "XP3R3V_EN")
	)
	(segment
		(start 93.091 -105.664)
		(end 92.202 -105.664)
		(width 0.127)
		(layer "In7.Cu")
		(net "XP3R3V_EN")
	)
	(segment
		(start 91.44 -104.902)
		(end 90.322654 -104.902)
		(width 0.127)
		(layer "In7.Cu")
		(net "XP3R3V_EN")
	)
	(segment
		(start 92.202 -105.664)
		(end 91.44 -104.902)
		(width 0.127)
		(layer "In7.Cu")
		(net "XP3R3V_EN")
	)
	(segment
		(start 88.2904 -101.2952)
		(end 88.2904 -101.1682)
		(width 0.254)
		(layer "F.Cu")
		(net "XP3R3V_COMP")
	)
	(segment
		(start 89.2048 -100.2538)
		(end 89.600278 -100.2538)
		(width 0.254)
		(layer "F.Cu")
		(net "XP3R3V_COMP")
	)
	(segment
		(start 86.816184 -101.654864)
		(end 87.956136 -101.654864)
		(width 0.254)
		(layer "F.Cu")
		(net "XP3R3V_COMP")
	)
	(segment
		(start 87.956136 -101.654864)
		(end 88.2904 -101.3206)
		(width 0.254)
		(layer "F.Cu")
		(net "XP3R3V_COMP")
	)
	(segment
		(start 88.2904 -101.3206)
		(end 88.2904 -101.2952)
		(width 0.254)
		(layer "F.Cu")
		(net "XP3R3V_COMP")
	)
	(segment
		(start 88.2904 -101.1682)
		(end 89.2048 -100.2538)
		(width 0.254)
		(layer "F.Cu")
		(net "XP3R3V_COMP")
	)
	(via
		(at 88.2904 -101.2952)
		(size 0.508)
		(drill 0.254)
		(layers "F.Cu" "B.Cu")
		(net "XP3R3V_COMP")
	)
	(segment
		(start 89.4588 -101.2698)
		(end 89.4334 -101.2952)
		(width 0.254)
		(layer "B.Cu")
		(net "XP3R3V_COMP")
	)
	(segment
		(start 89.4334 -101.2952)
		(end 88.2904 -101.2952)
		(width 0.254)
		(layer "B.Cu")
		(net "XP3R3V_COMP")
	)
	(segment
		(start 87.2998 -104.1146)
		(end 86.42096 -104.1146)
		(width 0.3048)
		(layer "F.Cu")
		(net "XP3R3V_BT")
	)
	(segment
		(start 86.42096 -104.1146)
		(end 86.11616 -103.8098)
		(width 0.3048)
		(layer "F.Cu")
		(net "XP3R3V_BT")
	)
	(segment
		(start 86.11616 -103.8098)
		(end 86.11616 -103.554784)
		(width 0.3048)
		(layer "F.Cu")
		(net "XP3R3V_BT")
	)
	(via
		(at 87.2998 -104.1146)
		(size 0.508)
		(drill 0.254)
		(layers "F.Cu" "B.Cu")
		(net "XP3R3V_BT")
	)
	(segment
		(start 86.0044 -104.013)
		(end 86.106 -104.1146)
		(width 0.381)
		(layer "B.Cu")
		(net "XP3R3V_BT")
	)
	(segment
		(start 86.106 -104.1146)
		(end 87.2998 -104.1146)
		(width 0.381)
		(layer "B.Cu")
		(net "XP3R3V_BT")
	)
	(segment
		(start 86.11616 -100.254816)
		(end 86.11616 -99.83724)
		(width 0.3048)
		(layer "F.Cu")
		(net "XP3R3V_AGND")
	)
	(segment
		(start 90.130122 -100.2538)
		(end 91.059 -100.2538)
		(width 0.254)
		(layer "F.Cu")
		(net "XP3R3V_AGND")
	)
	(segment
		(start 91.3892 -100.584)
		(end 91.3892 -101.0158)
		(width 0.254)
		(layer "F.Cu")
		(net "XP3R3V_AGND")
	)
	(segment
		(start 91.3892 -101.0158)
		(end 91.1352 -101.2698)
		(width 0.254)
		(layer "F.Cu")
		(net "XP3R3V_AGND")
	)
	(segment
		(start 88.392 -96.3676)
		(end 88.7476 -96.012)
		(width 0.381)
		(layer "F.Cu")
		(net "XP3R3V_AGND")
	)
	(segment
		(start 86.11616 -99.83724)
		(end 86.487 -99.4664)
		(width 0.3048)
		(layer "F.Cu")
		(net "XP3R3V_AGND")
	)
	(segment
		(start 91.1352 -101.2698)
		(end 90.5256 -101.2698)
		(width 0.254)
		(layer "F.Cu")
		(net "XP3R3V_AGND")
	)
	(segment
		(start 91.059 -100.2538)
		(end 91.3892 -100.584)
		(width 0.254)
		(layer "F.Cu")
		(net "XP3R3V_AGND")
	)
	(segment
		(start 88.392 -96.8502)
		(end 88.392 -96.3676)
		(width 0.381)
		(layer "F.Cu")
		(net "XP3R3V_AGND")
	)
	(segment
		(start 87.4522 -96.9264)
		(end 88.3158 -96.9264)
		(width 0.381)
		(layer "F.Cu")
		(net "XP3R3V_AGND")
	)
	(segment
		(start 88.3158 -96.9264)
		(end 88.392 -96.8502)
		(width 0.381)
		(layer "F.Cu")
		(net "XP3R3V_AGND")
	)
	(via
		(at 88.3158 -96.9264)
		(size 0.508)
		(drill 0.254)
		(layers "F.Cu" "B.Cu")
		(net "XP3R3V_AGND")
	)
	(via
		(at 91.3892 -101.0158)
		(size 0.508)
		(drill 0.254)
		(layers "F.Cu" "B.Cu")
		(net "XP3R3V_AGND")
	)
	(via
		(at 86.487 -99.4664)
		(size 0.508)
		(drill 0.254)
		(layers "F.Cu" "B.Cu")
		(net "XP3R3V_AGND")
	)
	(segment
		(start 91.3892 -101.0158)
		(end 91.3892 -99.441)
		(width 0.381)
		(layer "B.Cu")
		(net "XP3R3V_AGND")
	)
	(segment
		(start 86.487 -99.4664)
		(end 87.4014 -100.3808)
		(width 0.3048)
		(layer "B.Cu")
		(net "XP3R3V_AGND")
	)
	(segment
		(start 91.3892 -99.441)
		(end 90.678 -98.7298)
		(width 0.381)
		(layer "B.Cu")
		(net "XP3R3V_AGND")
	)
	(segment
		(start 87.4014 -100.3808)
		(end 89.2048 -100.3808)
		(width 0.3048)
		(layer "B.Cu")
		(net "XP3R3V_AGND")
	)
	(segment
		(start 89.2048 -100.3808)
		(end 89.4588 -100.1268)
		(width 0.3048)
		(layer "B.Cu")
		(net "XP3R3V_AGND")
	)
	(segment
		(start 144.025874 -94.2848)
		(end 143.891 -94.419674)
		(width 0.2032)
		(layer "F.Cu")
		(net "XP12R0V_A_TIMER")
	)
	(segment
		(start 144.354804 -94.2848)
		(end 144.025874 -94.2848)
		(width 0.2032)
		(layer "F.Cu")
		(net "XP12R0V_A_TIMER")
	)
	(segment
		(start 143.891 -94.419674)
		(end 142.054834 -94.419674)
		(width 0.2032)
		(layer "F.Cu")
		(net "XP12R0V_A_TIMER")
	)
	(segment
		(start 145.048478 -94.2848)
		(end 144.354804 -94.2848)
		(width 0.2032)
		(layer "F.Cu")
		(net "XP12R0V_A_TIMER")
	)
	(via
		(at 144.354804 -94.2848)
		(size 0.508)
		(drill 0.254)
		(layers "F.Cu" "B.Cu")
		(net "XP12R0V_A_TIMER")
	)
	(segment
		(start 143.273526 -95.419926)
		(end 142.054834 -95.419926)
		(width 0.2032)
		(layer "F.Cu")
		(net "XP12R0V_A_SS")
	)
	(segment
		(start 145.288 -96.6978)
		(end 144.4244 -96.6978)
		(width 0.2032)
		(layer "F.Cu")
		(net "XP12R0V_A_SS")
	)
	(segment
		(start 144.4244 -96.5708)
		(end 143.273526 -95.419926)
		(width 0.2032)
		(layer "F.Cu")
		(net "XP12R0V_A_SS")
	)
	(segment
		(start 144.4244 -96.6978)
		(end 144.4244 -96.5708)
		(width 0.2032)
		(layer "F.Cu")
		(net "XP12R0V_A_SS")
	)
	(via
		(at 144.4244 -96.6978)
		(size 0.508)
		(drill 0.254)
		(layers "F.Cu" "B.Cu")
		(net "XP12R0V_A_SS")
	)
	(segment
		(start 137.1854 -101.4984)
		(end 136.1948 -100.5078)
		(width 0.2032)
		(layer "F.Cu")
		(net "XP12R0V_A_OV")
	)
	(segment
		(start 139.863322 -100.7618)
		(end 139.863322 -101.8286)
		(width 0.2032)
		(layer "F.Cu")
		(net "XP12R0V_A_OV")
	)
	(segment
		(start 140.114274 -97.397824)
		(end 140.114274 -99.113848)
		(width 0.2032)
		(layer "F.Cu")
		(net "XP12R0V_A_OV")
	)
	(segment
		(start 138.201146 -101.4984)
		(end 137.1854 -101.4984)
		(width 0.2032)
		(layer "F.Cu")
		(net "XP12R0V_A_OV")
	)
	(segment
		(start 139.863322 -101.8286)
		(end 138.531346 -101.8286)
		(width 0.2032)
		(layer "F.Cu")
		(net "XP12R0V_A_OV")
	)
	(segment
		(start 140.114274 -99.113848)
		(end 139.863322 -99.3648)
		(width 0.2032)
		(layer "F.Cu")
		(net "XP12R0V_A_OV")
	)
	(segment
		(start 139.863322 -99.3648)
		(end 139.863322 -100.7618)
		(width 0.2032)
		(layer "F.Cu")
		(net "XP12R0V_A_OV")
	)
	(segment
		(start 138.531346 -101.8286)
		(end 138.201146 -101.4984)
		(width 0.2032)
		(layer "F.Cu")
		(net "XP12R0V_A_OV")
	)
	(via
		(at 139.863322 -101.8286)
		(size 0.4572)
		(drill 0.2032)
		(layers "F.Cu" "B.Cu")
		(net "XP12R0V_A_OV")
	)
	(segment
		(start 143.8402 -94.9198)
		(end 142.054834 -94.9198)
		(width 0.2032)
		(layer "F.Cu")
		(net "XP12R0V_A_ISET")
	)
	(segment
		(start 145.288 -95.4278)
		(end 145.2118 -95.504)
		(width 0.2032)
		(layer "F.Cu")
		(net "XP12R0V_A_ISET")
	)
	(segment
		(start 145.2118 -95.504)
		(end 144.4244 -95.504)
		(width 0.2032)
		(layer "F.Cu")
		(net "XP12R0V_A_ISET")
	)
	(segment
		(start 144.4244 -95.504)
		(end 143.8402 -94.9198)
		(width 0.2032)
		(layer "F.Cu")
		(net "XP12R0V_A_ISET")
	)
	(via
		(at 144.4244 -95.504)
		(size 0.508)
		(drill 0.254)
		(layers "F.Cu" "B.Cu")
		(net "XP12R0V_A_ISET")
	)
	(segment
		(start 145.0848 -98.171)
		(end 144.145 -98.171)
		(width 0.2032)
		(layer "F.Cu")
		(net "XP12R0V_A_IMON")
	)
	(segment
		(start 142.749524 -96.419924)
		(end 142.054834 -96.419924)
		(width 0.2032)
		(layer "F.Cu")
		(net "XP12R0V_A_IMON")
	)
	(segment
		(start 144.145 -98.171)
		(end 144.145 -97.8154)
		(width 0.2032)
		(layer "F.Cu")
		(net "XP12R0V_A_IMON")
	)
	(segment
		(start 145.288 -97.9678)
		(end 145.0848 -98.171)
		(width 0.2032)
		(layer "F.Cu")
		(net "XP12R0V_A_IMON")
	)
	(segment
		(start 144.145 -97.8154)
		(end 142.749524 -96.419924)
		(width 0.2032)
		(layer "F.Cu")
		(net "XP12R0V_A_IMON")
	)
	(via
		(at 144.145 -98.171)
		(size 0.508)
		(drill 0.254)
		(layers "F.Cu" "B.Cu")
		(net "XP12R0V_A_IMON")
	)
	(segment
		(start 144.3482 -97.9678)
		(end 144.145 -98.171)
		(width 0.381)
		(layer "B.Cu")
		(net "XP12R0V_A_IMON")
	)
	(segment
		(start 145.288 -97.9678)
		(end 144.3482 -97.9678)
		(width 0.381)
		(layer "B.Cu")
		(net "XP12R0V_A_IMON")
	)
	(segment
		(start 143.4592 -97.8662)
		(end 142.512796 -96.919796)
		(width 0.11938)
		(layer "F.Cu")
		(net "XP12R0V_A_FLTB")
	)
	(segment
		(start 145.288 -99.2378)
		(end 145.288 -100.6602)
		(width 0.11938)
		(layer "F.Cu")
		(net "XP12R0V_A_FLTB")
	)
	(segment
		(start 145.288 -99.2378)
		(end 144.1958 -99.2378)
		(width 0.11938)
		(layer "F.Cu")
		(net "XP12R0V_A_FLTB")
	)
	(segment
		(start 144.1958 -99.2378)
		(end 143.4592 -98.5012)
		(width 0.11938)
		(layer "F.Cu")
		(net "XP12R0V_A_FLTB")
	)
	(segment
		(start 145.288 -100.6602)
		(end 145.2372 -100.711)
		(width 0.11938)
		(layer "F.Cu")
		(net "XP12R0V_A_FLTB")
	)
	(segment
		(start 143.4592 -98.5012)
		(end 143.4592 -97.8662)
		(width 0.11938)
		(layer "F.Cu")
		(net "XP12R0V_A_FLTB")
	)
	(segment
		(start 142.512796 -96.919796)
		(end 142.054834 -96.919796)
		(width 0.11938)
		(layer "F.Cu")
		(net "XP12R0V_A_FLTB")
	)
	(segment
		(start 145.2372 -100.711)
		(end 145.288 -100.6602)
		(width 0.11938)
		(layer "B.Cu")
		(net "XP12R0V_A_FLTB")
	)
	(segment
		(start 145.288 -100.6602)
		(end 145.288 -99.2378)
		(width 0.11938)
		(layer "B.Cu")
		(net "XP12R0V_A_FLTB")
	)
	(via
		(at 21.971 -97.663)
		(size 0.508)
		(drill 0.254)
		(layers "F.Cu" "B.Cu")
		(net "XP12R0V_EXT")
	)
	(via
		(at 23.876 -97.663)
		(size 0.508)
		(drill 0.254)
		(layers "F.Cu" "B.Cu")
		(net "XP12R0V_EXT")
	)
	(via
		(at 22.987 -92.583)
		(size 0.508)
		(drill 0.254)
		(layers "F.Cu" "B.Cu")
		(net "XP12R0V_EXT")
	)
	(via
		(at 24.003 -93.726)
		(size 0.508)
		(drill 0.254)
		(layers "F.Cu" "B.Cu")
		(net "XP12R0V_EXT")
	)
	(via
		(at 24.003 -95.631)
		(size 0.508)
		(drill 0.254)
		(layers "F.Cu" "B.Cu")
		(net "XP12R0V_EXT")
	)
	(via
		(at 24.003 -92.583)
		(size 0.508)
		(drill 0.254)
		(layers "F.Cu" "B.Cu")
		(net "XP12R0V_EXT")
	)
	(via
		(at 24.003 -96.647)
		(size 0.508)
		(drill 0.254)
		(layers "F.Cu" "B.Cu")
		(net "XP12R0V_EXT")
	)
	(via
		(at 21.0312 -97.6884)
		(size 0.508)
		(drill 0.254)
		(layers "F.Cu" "B.Cu")
		(net "XP12R0V_EXT")
	)
	(via
		(at 22.987 -97.663)
		(size 0.508)
		(drill 0.254)
		(layers "F.Cu" "B.Cu")
		(net "XP12R0V_EXT")
	)
	(via
		(at 24.003 -94.742)
		(size 0.508)
		(drill 0.254)
		(layers "F.Cu" "B.Cu")
		(net "XP12R0V_EXT")
	)
	(via
		(at 21.0312 -92.6084)
		(size 0.508)
		(drill 0.254)
		(layers "F.Cu" "B.Cu")
		(net "XP12R0V_EXT")
	)
	(via
		(at 21.971 -92.583)
		(size 0.508)
		(drill 0.254)
		(layers "F.Cu" "B.Cu")
		(net "XP12R0V_EXT")
	)
	(segment
		(start 145.288 -88.0618)
		(end 145.288 -89.3318)
		(width 0.11938)
		(layer "F.Cu")
		(net "XP12R0V_A_EN")
	)
	(segment
		(start 144.272 -90.6018)
		(end 145.288 -90.6018)
		(width 0.11938)
		(layer "F.Cu")
		(net "XP12R0V_A_EN")
	)
	(segment
		(start 143.383 -91.694)
		(end 144.272 -90.805)
		(width 0.11938)
		(layer "F.Cu")
		(net "XP12R0V_A_EN")
	)
	(segment
		(start 142.538196 -92.919804)
		(end 143.383 -92.075)
		(width 0.11938)
		(layer "F.Cu")
		(net "XP12R0V_A_EN")
	)
	(segment
		(start 145.2118 -88.138)
		(end 145.288 -88.0618)
		(width 0.11938)
		(layer "F.Cu")
		(net "XP12R0V_A_EN")
	)
	(segment
		(start 143.383 -92.075)
		(end 143.383 -91.694)
		(width 0.11938)
		(layer "F.Cu")
		(net "XP12R0V_A_EN")
	)
	(segment
		(start 145.288 -90.6018)
		(end 145.288 -89.3318)
		(width 0.11938)
		(layer "F.Cu")
		(net "XP12R0V_A_EN")
	)
	(segment
		(start 142.054834 -92.919804)
		(end 142.538196 -92.919804)
		(width 0.11938)
		(layer "F.Cu")
		(net "XP12R0V_A_EN")
	)
	(segment
		(start 144.272 -90.805)
		(end 144.272 -90.6018)
		(width 0.11938)
		(layer "F.Cu")
		(net "XP12R0V_A_EN")
	)
	(segment
		(start 143.764 -88.138)
		(end 145.2118 -88.138)
		(width 0.11938)
		(layer "F.Cu")
		(net "XP12R0V_A_EN")
	)
	(via
		(at 144.272 -90.6018)
		(size 0.4572)
		(drill 0.2032)
		(layers "F.Cu" "B.Cu")
		(net "XP12R0V_A_EN")
	)
	(via
		(at 137.3124 -98.1202)
		(size 0.508)
		(drill 0.254)
		(layers "F.Cu" "B.Cu")
		(net "XP12R0V_A_AVIN")
	)
	(segment
		(start 146.3548 -99.2378)
		(end 147.3962 -99.2378)
		(width 0.381)
		(layer "F.Cu")
		(net "XP12R0V")
	)
	(segment
		(start 142.2654 -100.584)
		(end 142.4432 -100.7618)
		(width 0.381)
		(layer "F.Cu")
		(net "XP12R0V")
	)
	(segment
		(start 142.4432 -100.7618)
		(end 143.3576 -100.7618)
		(width 0.381)
		(layer "F.Cu")
		(net "XP12R0V")
	)
	(via
		(at 88.773 -105.41)
		(size 0.508)
		(drill 0.254)
		(layers "F.Cu" "B.Cu")
		(net "XP12R0V")
	)
	(via
		(at 136.906 -91.44)
		(size 0.508)
		(drill 0.254)
		(layers "F.Cu" "B.Cu")
		(net "XP12R0V")
	)
	(via
		(at 137.922 -93.98)
		(size 0.508)
		(drill 0.254)
		(layers "F.Cu" "B.Cu")
		(net "XP12R0V")
	)
	(via
		(at 136.9822 -92.7354)
		(size 0.508)
		(drill 0.254)
		(layers "F.Cu" "B.Cu")
		(net "XP12R0V")
	)
	(via
		(at 143.3576 -100.7618)
		(size 0.508)
		(drill 0.254)
		(layers "F.Cu" "B.Cu")
		(net "XP12R0V")
	)
	(via
		(at 137.9982 -92.7354)
		(size 0.508)
		(drill 0.254)
		(layers "F.Cu" "B.Cu")
		(net "XP12R0V")
	)
	(via
		(at 87.884 -105.664)
		(size 0.508)
		(drill 0.254)
		(layers "F.Cu" "B.Cu")
		(net "XP12R0V")
	)
	(via
		(at 88.9 -106.553)
		(size 0.508)
		(drill 0.254)
		(layers "F.Cu" "B.Cu")
		(net "XP12R0V")
	)
	(via
		(at 147.3962 -99.2378)
		(size 0.508)
		(drill 0.254)
		(layers "F.Cu" "B.Cu")
		(net "XP12R0V")
	)
	(via
		(at 136.906 -93.98)
		(size 0.508)
		(drill 0.254)
		(layers "F.Cu" "B.Cu")
		(net "XP12R0V")
	)
	(via
		(at 37.719 -95.504)
		(size 0.4572)
		(drill 0.2032)
		(layers "F.Cu" "B.Cu")
		(net "XP12R0V")
	)
	(via
		(at 89.662 -105.791)
		(size 0.508)
		(drill 0.254)
		(layers "F.Cu" "B.Cu")
		(net "XP12R0V")
	)
	(via
		(at 135.636 -58.801)
		(size 0.508)
		(drill 0.254)
		(layers "F.Cu" "B.Cu")
		(net "XP12R0V")
	)
	(via
		(at 36.83 -96.012)
		(size 0.508)
		(drill 0.254)
		(layers "F.Cu" "B.Cu")
		(net "XP12R0V")
	)
	(via
		(at 37.719 -96.52)
		(size 0.508)
		(drill 0.254)
		(layers "F.Cu" "B.Cu")
		(net "XP12R0V")
	)
	(via
		(at 136.525 -58.928)
		(size 0.508)
		(drill 0.254)
		(layers "F.Cu" "B.Cu")
		(net "XP12R0V")
	)
	(via
		(at 137.922 -91.44)
		(size 0.508)
		(drill 0.254)
		(layers "F.Cu" "B.Cu")
		(net "XP12R0V")
	)
	(via
		(at 146.5326 -102.3874)
		(size 0.508)
		(drill 0.254)
		(layers "F.Cu" "B.Cu")
		(net "XP12R0V")
	)
	(segment
		(start 146.5326 -103.505)
		(end 146.5326 -102.3874)
		(width 0.381)
		(layer "B.Cu")
		(net "XP12R0V")
	)
	(via
		(at 40.7797 -105.0036)
		(size 0.508)
		(drill 0.254)
		(layers "F.Cu" "B.Cu")
		(net "VIN_XP5R0V")
	)
	(via
		(at 40.4114 -97.1804)
		(size 0.508)
		(drill 0.254)
		(layers "F.Cu" "B.Cu")
		(net "VIN_XP5R0V")
	)
	(via
		(at 40.787828 -104.14)
		(size 0.508)
		(drill 0.254)
		(layers "F.Cu" "B.Cu")
		(net "VIN_XP5R0V")
	)
	(via
		(at 41.5544 -96.1644)
		(size 0.508)
		(drill 0.254)
		(layers "F.Cu" "B.Cu")
		(net "VIN_XP5R0V")
	)
	(via
		(at 41.4782 -97.2566)
		(size 0.4572)
		(drill 0.2032)
		(layers "F.Cu" "B.Cu")
		(net "VIN_XP5R0V")
	)
	(via
		(at 40.7924 -106.0196)
		(size 0.4572)
		(drill 0.2032)
		(layers "F.Cu" "B.Cu")
		(net "VIN_XP5R0V")
	)
	(segment
		(start 41.3004 -95.9104)
		(end 41.5544 -96.1644)
		(width 0.381)
		(layer "B.Cu")
		(net "VIN_XP5R0V")
	)
	(segment
		(start 40.1828 -95.9104)
		(end 41.3004 -95.9104)
		(width 0.381)
		(layer "B.Cu")
		(net "VIN_XP5R0V")
	)
	(via
		(at 86.5632 -105.4608)
		(size 0.508)
		(drill 0.254)
		(layers "F.Cu" "B.Cu")
		(net "VIN_XP3R3")
	)
	(via
		(at 86.1822 -97.536)
		(size 0.508)
		(drill 0.254)
		(layers "F.Cu" "B.Cu")
		(net "VIN_XP3R3")
	)
	(via
		(at 85.4202 -105.4608)
		(size 0.508)
		(drill 0.254)
		(layers "F.Cu" "B.Cu")
		(net "VIN_XP3R3")
	)
	(via
		(at 85.4202 -106.4768)
		(size 0.508)
		(drill 0.254)
		(layers "F.Cu" "B.Cu")
		(net "VIN_XP3R3")
	)
	(via
		(at 85.4202 -107.4928)
		(size 0.508)
		(drill 0.254)
		(layers "F.Cu" "B.Cu")
		(net "VIN_XP3R3")
	)
	(via
		(at 86.1568 -96.5962)
		(size 0.508)
		(drill 0.254)
		(layers "F.Cu" "B.Cu")
		(net "VIN_XP3R3")
	)
	(via
		(at 86.1822 -98.4758)
		(size 0.508)
		(drill 0.254)
		(layers "F.Cu" "B.Cu")
		(net "VIN_XP3R3")
	)
	(via
		(at 91.6178 -103.1748)
		(size 0.508)
		(drill 0.254)
		(layers "F.Cu" "B.Cu")
		(net "VIN_XP3R3")
	)
	(segment
		(start 90.9066 -103.1748)
		(end 91.6178 -103.1748)
		(width 0.381)
		(layer "B.Cu")
		(net "VIN_XP3R3")
	)
	(segment
		(start 90.5256 -103.5558)
		(end 90.9066 -103.1748)
		(width 0.381)
		(layer "B.Cu")
		(net "VIN_XP3R3")
	)
	(segment
		(start 87.122 -102.108)
		(end 89.408 -102.108)
		(width 0.381)
		(layer "In2.Cu")
		(net "VIN_XP3R3")
	)
	(segment
		(start 89.408 -102.108)
		(end 90.4748 -103.1748)
		(width 0.381)
		(layer "In2.Cu")
		(net "VIN_XP3R3")
	)
	(segment
		(start 90.4748 -103.1748)
		(end 91.6178 -103.1748)
		(width 0.381)
		(layer "In2.Cu")
		(net "VIN_XP3R3")
	)
	(via
		(at 67.691 -52.451)
		(size 0.762)
		(drill 0.381)
		(layers "F.Cu" "B.Cu")
		(net "USB_PWR_EN")
	)
	(segment
		(start 74.041 -46.101)
		(end 72.771 -44.831)
		(width 0.11938)
		(layer "B.Cu")
		(net "USB_PWR_EN")
	)
	(segment
		(start 61.326014 -57.418986)
		(end 61.468 -57.277)
		(width 0.11938)
		(layer "B.Cu")
		(net "USB_PWR_EN")
	)
	(segment
		(start 72.771 -44.831)
		(end 69.342 -44.831)
		(width 0.11938)
		(layer "B.Cu")
		(net "USB_PWR_EN")
	)
	(segment
		(start 66.294 -53.848)
		(end 66.294 -56.347106)
		(width 0.11938)
		(layer "B.Cu")
		(net "USB_PWR_EN")
	)
	(segment
		(start 63.627 -57.785)
		(end 63.627 -58.42)
		(width 0.11938)
		(layer "B.Cu")
		(net "USB_PWR_EN")
	)
	(segment
		(start 67.691 -46.482)
		(end 67.691 -52.451)
		(width 0.11938)
		(layer "B.Cu")
		(net "USB_PWR_EN")
	)
	(segment
		(start 65.786 -58.5724)
		(end 64.516 -58.5724)
		(width 0.11938)
		(layer "B.Cu")
		(net "USB_PWR_EN")
	)
	(segment
		(start 69.342 -44.831)
		(end 67.691 -46.482)
		(width 0.11938)
		(layer "B.Cu")
		(net "USB_PWR_EN")
	)
	(segment
		(start 63.627 -58.42)
		(end 63.7794 -58.5724)
		(width 0.11938)
		(layer "B.Cu")
		(net "USB_PWR_EN")
	)
	(segment
		(start 63.7794 -58.5724)
		(end 64.516 -58.5724)
		(width 0.11938)
		(layer "B.Cu")
		(net "USB_PWR_EN")
	)
	(segment
		(start 67.363086 -57.416192)
		(end 67.363086 -58.572146)
		(width 0.11938)
		(layer "B.Cu")
		(net "USB_PWR_EN")
	)
	(segment
		(start 79.4004 -56.3118)
		(end 80.137 -55.5752)
		(width 0.11938)
		(layer "B.Cu")
		(net "USB_PWR_EN")
	)
	(segment
		(start 63.119 -57.277)
		(end 63.627 -57.785)
		(width 0.11938)
		(layer "B.Cu")
		(net "USB_PWR_EN")
	)
	(segment
		(start 67.36334 -58.5724)
		(end 65.786 -58.5724)
		(width 0.11938)
		(layer "B.Cu")
		(net "USB_PWR_EN")
	)
	(segment
		(start 80.137 -55.5752)
		(end 80.137 -48.768)
		(width 0.11938)
		(layer "B.Cu")
		(net "USB_PWR_EN")
	)
	(segment
		(start 67.37604 -58.5851)
		(end 67.36334 -58.5724)
		(width 0.11938)
		(layer "B.Cu")
		(net "USB_PWR_EN")
	)
	(segment
		(start 67.363086 -58.572146)
		(end 67.36334 -58.5724)
		(width 0.11938)
		(layer "B.Cu")
		(net "USB_PWR_EN")
	)
	(segment
		(start 66.294 -56.347106)
		(end 67.363086 -57.416192)
		(width 0.11938)
		(layer "B.Cu")
		(net "USB_PWR_EN")
	)
	(segment
		(start 77.5589 -56.3118)
		(end 79.4004 -56.3118)
		(width 0.11938)
		(layer "B.Cu")
		(net "USB_PWR_EN")
	)
	(segment
		(start 61.468 -57.277)
		(end 63.119 -57.277)
		(width 0.11938)
		(layer "B.Cu")
		(net "USB_PWR_EN")
	)
	(segment
		(start 61.326014 -58.0898)
		(end 61.326014 -57.418986)
		(width 0.11938)
		(layer "B.Cu")
		(net "USB_PWR_EN")
	)
	(segment
		(start 77.47 -46.101)
		(end 74.041 -46.101)
		(width 0.11938)
		(layer "B.Cu")
		(net "USB_PWR_EN")
	)
	(segment
		(start 80.137 -48.768)
		(end 77.47 -46.101)
		(width 0.11938)
		(layer "B.Cu")
		(net "USB_PWR_EN")
	)
	(segment
		(start 67.691 -52.451)
		(end 66.294 -53.848)
		(width 0.11938)
		(layer "B.Cu")
		(net "USB_PWR_EN")
	)
	(segment
		(start 90.130122 -98.312224)
		(end 90.5256 -97.916746)
		(width 0.254)
		(layer "F.Cu")
		(net "UNNAMED_517_CAPACITOR_I30_1")
	)
	(segment
		(start 91.6178 -98.8568)
		(end 91.6686 -98.8568)
		(width 0.254)
		(layer "F.Cu")
		(net "UNNAMED_517_CAPACITOR_I30_1")
	)
	(segment
		(start 91.6686 -98.8568)
		(end 92.0242 -98.5012)
		(width 0.254)
		(layer "F.Cu")
		(net "UNNAMED_517_CAPACITOR_I30_1")
	)
	(segment
		(start 90.5256 -97.916746)
		(end 90.5256 -97.3582)
		(width 0.254)
		(layer "F.Cu")
		(net "UNNAMED_517_CAPACITOR_I30_1")
	)
	(segment
		(start 90.130122 -98.8568)
		(end 91.6178 -98.8568)
		(width 0.3048)
		(layer "F.Cu")
		(net "UNNAMED_517_CAPACITOR_I30_1")
	)
	(segment
		(start 90.130122 -98.8568)
		(end 90.130122 -98.312224)
		(width 0.254)
		(layer "F.Cu")
		(net "UNNAMED_517_CAPACITOR_I30_1")
	)
	(segment
		(start 80.899 -98.5266)
		(end 80.899 -97.1042)
		(width 0.381)
		(layer "B.Cu")
		(net "UNNAMED_517_CAPACITOR_I29_2")
	)
	(via
		(at 83.82 -104.4702)
		(size 0.762)
		(drill 0.381)
		(layers "F.Cu" "B.Cu")
		(net "UNNAMED_517_CAPACITOR_I27_1")
	)
	(segment
		(start 84.4804 -104.4702)
		(end 83.82 -104.4702)
		(width 0.381)
		(layer "B.Cu")
		(net "UNNAMED_517_CAPACITOR_I27_1")
	)
	(segment
		(start 83.82 -104.4702)
		(end 83.4644 -104.1146)
		(width 0.381)
		(layer "B.Cu")
		(net "UNNAMED_517_CAPACITOR_I27_1")
	)
	(segment
		(start 83.4644 -104.1146)
		(end 83.4644 -103.378)
		(width 0.381)
		(layer "B.Cu")
		(net "UNNAMED_517_CAPACITOR_I27_1")
	)
	(segment
		(start 84.9376 -104.013)
		(end 84.4804 -104.4702)
		(width 0.381)
		(layer "B.Cu")
		(net "UNNAMED_517_CAPACITOR_I27_1")
	)
	(segment
		(start 90.5256 -100.1268)
		(end 90.5256 -101.2698)
		(width 0.381)
		(layer "B.Cu")
		(net "UNNAMED_517_CAPACITOR_I17_1")
	)
	(segment
		(start 45.8978 -103.4542)
		(end 45.72 -103.2764)
		(width 0.381)
		(layer "B.Cu")
		(net "UNNAMED_516_CAPACITOR_I37_2")
	)
	(segment
		(start 45.8978 -104.902)
		(end 45.8978 -103.4542)
		(width 0.381)
		(layer "B.Cu")
		(net "UNNAMED_516_CAPACITOR_I37_2")
	)
	(segment
		(start 36.666678 -103.7336)
		(end 35.179 -103.7336)
		(width 0.3048)
		(layer "F.Cu")
		(net "UNNAMED_516_CAPACITOR_I29_1")
	)
	(segment
		(start 36.717478 -104.405176)
		(end 36.717478 -103.7844)
		(width 0.254)
		(layer "F.Cu")
		(net "UNNAMED_516_CAPACITOR_I29_1")
	)
	(segment
		(start 36.449 -105.2068)
		(end 36.449 -104.673654)
		(width 0.254)
		(layer "F.Cu")
		(net "UNNAMED_516_CAPACITOR_I29_1")
	)
	(segment
		(start 35.179 -103.7336)
		(end 34.3408 -103.7336)
		(width 0.381)
		(layer "F.Cu")
		(net "UNNAMED_516_CAPACITOR_I29_1")
	)
	(segment
		(start 36.449 -104.673654)
		(end 36.717478 -104.405176)
		(width 0.254)
		(layer "F.Cu")
		(net "UNNAMED_516_CAPACITOR_I29_1")
	)
	(segment
		(start 36.717478 -103.7844)
		(end 36.666678 -103.7336)
		(width 0.3048)
		(layer "F.Cu")
		(net "UNNAMED_516_CAPACITOR_I29_1")
	)
	(via
		(at 34.3408 -103.7336)
		(size 0.508)
		(drill 0.254)
		(layers "F.Cu" "B.Cu")
		(net "UNNAMED_516_CAPACITOR_I29_1")
	)
	(via
		(at 42.6212 -99.7458)
		(size 0.762)
		(drill 0.381)
		(layers "F.Cu" "B.Cu")
		(net "UNNAMED_516_CAPACITOR_I27_1")
	)
	(segment
		(start 43.7896 -99.314)
		(end 43.3578 -99.7458)
		(width 0.381)
		(layer "B.Cu")
		(net "UNNAMED_516_CAPACITOR_I27_1")
	)
	(segment
		(start 43.3578 -99.7458)
		(end 42.6212 -99.7458)
		(width 0.381)
		(layer "B.Cu")
		(net "UNNAMED_516_CAPACITOR_I27_1")
	)
	(segment
		(start 42.6212 -99.7458)
		(end 42.3164 -99.441)
		(width 0.381)
		(layer "B.Cu")
		(net "UNNAMED_516_CAPACITOR_I27_1")
	)
	(segment
		(start 42.3164 -99.441)
		(end 42.3164 -98.679)
		(width 0.381)
		(layer "B.Cu")
		(net "UNNAMED_516_CAPACITOR_I27_1")
	)
	(segment
		(start 36.449 -102.5144)
		(end 36.449 -101.3714)
		(width 0.381)
		(layer "B.Cu")
		(net "UNNAMED_516_CAPACITOR_I13_1")
	)
	(segment
		(start 50.74158 -14.440662)
		(end 50.74158 -14.986)
		(width 0.11938)
		(layer "F.Cu")
		(net "UNNAMED_3_G2201019801_I100_EN")
	)
	(segment
		(start 49.53 -14.45006)
		(end 49.53 -13.8557)
		(width 0.11938)
		(layer "F.Cu")
		(net "UNNAMED_3_G2201019801_I100_EN")
	)
	(segment
		(start 48.99406 -14.986)
		(end 49.53 -14.45006)
		(width 0.11938)
		(layer "F.Cu")
		(net "UNNAMED_3_G2201019801_I100_EN")
	)
	(segment
		(start 47.83328 -14.986)
		(end 48.99406 -14.986)
		(width 0.11938)
		(layer "F.Cu")
		(net "UNNAMED_3_G2201019801_I100_EN")
	)
	(segment
		(start 50.156618 -13.8557)
		(end 50.74158 -14.440662)
		(width 0.11938)
		(layer "F.Cu")
		(net "UNNAMED_3_G2201019801_I100_EN")
	)
	(segment
		(start 49.53 -13.8557)
		(end 50.156618 -13.8557)
		(width 0.11938)
		(layer "F.Cu")
		(net "UNNAMED_3_G2201019801_I100_EN")
	)
	(segment
		(start 50.74158 -14.986)
		(end 52.01158 -14.986)
		(width 0.11938)
		(layer "F.Cu")
		(net "UNNAMED_3_G2201019801_I100_EN")
	)
	(via
		(at 49.53 -13.8557)
		(size 0.4572)
		(drill 0.2032)
		(layers "F.Cu" "B.Cu")
		(net "UNNAMED_3_G2201019801_I100_EN")
	)
	(segment
		(start 145.288 -91.8718)
		(end 144.2974 -91.8718)
		(width 0.2032)
		(layer "F.Cu")
		(net "UNNAMED_15_MP5022CGQVZQFN22_I_2")
	)
	(segment
		(start 142.749524 -93.419676)
		(end 142.054834 -93.419676)
		(width 0.2032)
		(layer "F.Cu")
		(net "UNNAMED_15_MP5022CGQVZQFN22_I_2")
	)
	(segment
		(start 144.2974 -91.8718)
		(end 142.749524 -93.419676)
		(width 0.2032)
		(layer "F.Cu")
		(net "UNNAMED_15_MP5022CGQVZQFN22_I_2")
	)
	(via
		(at 144.2974 -91.8718)
		(size 0.508)
		(drill 0.254)
		(layers "F.Cu" "B.Cu")
		(net "UNNAMED_15_MP5022CGQVZQFN22_I_2")
	)
	(segment
		(start 144.3736 -93.1418)
		(end 144.2974 -93.0656)
		(width 0.2032)
		(layer "F.Cu")
		(net "UNNAMED_15_MP5022CGQVZQFN22_I21")
	)
	(segment
		(start 143.062198 -93.919802)
		(end 142.054834 -93.919802)
		(width 0.2032)
		(layer "F.Cu")
		(net "UNNAMED_15_MP5022CGQVZQFN22_I21")
	)
	(segment
		(start 145.288 -93.1418)
		(end 144.3736 -93.1418)
		(width 0.2032)
		(layer "F.Cu")
		(net "UNNAMED_15_MP5022CGQVZQFN22_I21")
	)
	(segment
		(start 143.9164 -93.0656)
		(end 143.062198 -93.919802)
		(width 0.2032)
		(layer "F.Cu")
		(net "UNNAMED_15_MP5022CGQVZQFN22_I21")
	)
	(segment
		(start 144.2974 -93.0656)
		(end 143.9164 -93.0656)
		(width 0.2032)
		(layer "F.Cu")
		(net "UNNAMED_15_MP5022CGQVZQFN22_I21")
	)
	(via
		(at 144.2974 -93.0656)
		(size 0.508)
		(drill 0.254)
		(layers "F.Cu" "B.Cu")
		(net "UNNAMED_15_MP5022CGQVZQFN22_I21")
	)
	(segment
		(start 137.663428 -69.1134)
		(end 137.240772 -68.690744)
		(width 0.11938)
		(layer "F.Cu")
		(net "UNNAMED_127_G2001028301_I427_4")
	)
	(segment
		(start 139.838176 -69.1134)
		(end 137.663428 -69.1134)
		(width 0.11938)
		(layer "F.Cu")
		(net "UNNAMED_127_G2001028301_I427_4")
	)
	(via
		(at 137.240772 -68.690744)
		(size 0.4572)
		(drill 0.2032)
		(layers "F.Cu" "B.Cu")
		(net "UNNAMED_127_G2001028301_I427_4")
	)
	(segment
		(start 139.7508 -69.1134)
		(end 137.663428 -69.1134)
		(width 0.11938)
		(layer "B.Cu")
		(net "UNNAMED_127_G2001028301_I427_4")
	)
	(segment
		(start 137.663428 -69.1134)
		(end 137.240772 -68.690744)
		(width 0.11938)
		(layer "B.Cu")
		(net "UNNAMED_127_G2001028301_I427_4")
	)
	(segment
		(start 13.462 -36.6776)
		(end 14.204188 -35.935412)
		(width 0.11938)
		(layer "F.Cu")
		(net "UNNAMED_12_74HCT2G125DPTSSOP8_I")
	)
	(segment
		(start 14.149832 -35.612832)
		(end 14.149832 -34.29)
		(width 0.11938)
		(layer "F.Cu")
		(net "UNNAMED_12_74HCT2G125DPTSSOP8_I")
	)
	(segment
		(start 14.204188 -35.667188)
		(end 14.149832 -35.612832)
		(width 0.11938)
		(layer "F.Cu")
		(net "UNNAMED_12_74HCT2G125DPTSSOP8_I")
	)
	(segment
		(start 14.204188 -35.697922)
		(end 14.204188 -35.667188)
		(width 0.11938)
		(layer "F.Cu")
		(net "UNNAMED_12_74HCT2G125DPTSSOP8_I")
	)
	(segment
		(start 14.204188 -35.935412)
		(end 14.204188 -35.697922)
		(width 0.11938)
		(layer "F.Cu")
		(net "UNNAMED_12_74HCT2G125DPTSSOP8_I")
	)
	(via
		(at 14.204188 -35.697922)
		(size 0.508)
		(drill 0.254)
		(layers "F.Cu" "B.Cu")
		(net "UNNAMED_12_74HCT2G125DPTSSOP8_I")
	)
	(segment
		(start 14.204188 -35.697922)
		(end 14.204188 -35.935412)
		(width 0.11938)
		(layer "B.Cu")
		(net "UNNAMED_12_74HCT2G125DPTSSOP8_I")
	)
	(segment
		(start 14.204188 -35.935412)
		(end 13.462 -36.6776)
		(width 0.11938)
		(layer "B.Cu")
		(net "UNNAMED_12_74HCT2G125DPTSSOP8_I")
	)
	(segment
		(start 13.589 -22.098)
		(end 13.589 -22.4536)
		(width 0.11938)
		(layer "F.Cu")
		(net "UNNAMED_12_74HCT2G125DPTSSOP8_3")
	)
	(segment
		(start 14.149832 -19.790156)
		(end 14.149832 -20.880832)
		(width 0.11938)
		(layer "F.Cu")
		(net "UNNAMED_12_74HCT2G125DPTSSOP8_3")
	)
	(segment
		(start 14.149832 -20.880832)
		(end 14.478 -21.209)
		(width 0.11938)
		(layer "F.Cu")
		(net "UNNAMED_12_74HCT2G125DPTSSOP8_3")
	)
	(segment
		(start 14.478 -21.209)
		(end 13.589 -22.098)
		(width 0.11938)
		(layer "F.Cu")
		(net "UNNAMED_12_74HCT2G125DPTSSOP8_3")
	)
	(via
		(at 14.478 -21.209)
		(size 0.508)
		(drill 0.254)
		(layers "F.Cu" "B.Cu")
		(net "UNNAMED_12_74HCT2G125DPTSSOP8_3")
	)
	(segment
		(start 13.589 -22.4536)
		(end 13.589 -22.098)
		(width 0.11938)
		(layer "B.Cu")
		(net "UNNAMED_12_74HCT2G125DPTSSOP8_3")
	)
	(segment
		(start 13.589 -22.098)
		(end 14.478 -21.209)
		(width 0.11938)
		(layer "B.Cu")
		(net "UNNAMED_12_74HCT2G125DPTSSOP8_3")
	)
	(via
		(at 158.242 -52.16525)
		(size 0.762)
		(drill 0.381)
		(layers "F.Cu" "B.Cu")
		(net "UNNAMED_527_RESISTOR_I201_2")
	)
	(segment
		(start 158.877 -51.597306)
		(end 158.309056 -52.16525)
		(width 0.11938)
		(layer "B.Cu")
		(net "UNNAMED_527_RESISTOR_I201_2")
	)
	(segment
		(start 157.734 -51.65725)
		(end 157.734 -51.047396)
		(width 0.11938)
		(layer "B.Cu")
		(net "UNNAMED_527_RESISTOR_I201_2")
	)
	(segment
		(start 158.309056 -52.16525)
		(end 158.242 -52.16525)
		(width 0.11938)
		(layer "B.Cu")
		(net "UNNAMED_527_RESISTOR_I201_2")
	)
	(segment
		(start 158.877 -51.047396)
		(end 158.877 -51.597306)
		(width 0.11938)
		(layer "B.Cu")
		(net "UNNAMED_527_RESISTOR_I201_2")
	)
	(segment
		(start 158.242 -52.16525)
		(end 157.734 -51.65725)
		(width 0.11938)
		(layer "B.Cu")
		(net "UNNAMED_527_RESISTOR_I201_2")
	)
	(segment
		(start 90.9828 -46.4058)
		(end 91.0336 -46.4058)
		(width 0.11938)
		(layer "F.Cu")
		(net "UNNAMED_527_RESISTOR_I126_1")
	)
	(segment
		(start 91.0336 -46.4058)
		(end 91.5416 -45.8978)
		(width 0.11938)
		(layer "F.Cu")
		(net "UNNAMED_527_RESISTOR_I126_1")
	)
	(segment
		(start 91.5416 -45.8978)
		(end 91.5416 -45.402246)
		(width 0.11938)
		(layer "F.Cu")
		(net "UNNAMED_527_RESISTOR_I126_1")
	)
	(segment
		(start 90.218006 -47.170594)
		(end 90.9828 -46.4058)
		(width 0.11938)
		(layer "F.Cu")
		(net "UNNAMED_527_RESISTOR_I126_1")
	)
	(segment
		(start 90.218006 -47.889922)
		(end 90.218006 -47.170594)
		(width 0.11938)
		(layer "F.Cu")
		(net "UNNAMED_527_RESISTOR_I126_1")
	)
	(via
		(at 91.0336 -46.4058)
		(size 0.4572)
		(drill 0.2032)
		(layers "F.Cu" "B.Cu")
		(net "UNNAMED_527_RESISTOR_I126_1")
	)
	(segment
		(start 40.158416 -99.986338)
		(end 39.788338 -99.986338)
		(width 0.11938)
		(layer "F.Cu")
		(net "R_XP5R0V_EN")
	)
	(segment
		(start 38.5572 -99.187)
		(end 37.5158 -100.2284)
		(width 0.11938)
		(layer "F.Cu")
		(net "R_XP5R0V_EN")
	)
	(segment
		(start 39.788338 -99.986338)
		(end 38.989 -99.187)
		(width 0.11938)
		(layer "F.Cu")
		(net "R_XP5R0V_EN")
	)
	(segment
		(start 38.989 -99.187)
		(end 38.5572 -99.187)
		(width 0.11938)
		(layer "F.Cu")
		(net "R_XP5R0V_EN")
	)
	(via
		(at 39.0906 -97.0788)
		(size 0.762)
		(drill 0.381)
		(layers "F.Cu" "B.Cu")
		(net "R_XP5R0V_EN")
	)
	(via
		(at 38.989 -99.187)
		(size 0.4572)
		(drill 0.2032)
		(layers "F.Cu" "B.Cu")
		(net "R_XP5R0V_EN")
	)
	(segment
		(start 38.8366 -99.0346)
		(end 37.5666 -99.0346)
		(width 0.11938)
		(layer "B.Cu")
		(net "R_XP5R0V_EN")
	)
	(segment
		(start 37.5158 -99.0854)
		(end 37.5158 -100.2284)
		(width 0.11938)
		(layer "B.Cu")
		(net "R_XP5R0V_EN")
	)
	(segment
		(start 38.989 -99.187)
		(end 39.2176 -98.9584)
		(width 0.11938)
		(layer "B.Cu")
		(net "R_XP5R0V_EN")
	)
	(segment
		(start 39.2176 -97.2058)
		(end 39.0906 -97.0788)
		(width 0.11938)
		(layer "B.Cu")
		(net "R_XP5R0V_EN")
	)
	(segment
		(start 39.2176 -98.9584)
		(end 39.2176 -97.2058)
		(width 0.11938)
		(layer "B.Cu")
		(net "R_XP5R0V_EN")
	)
	(segment
		(start 37.5666 -99.0346)
		(end 37.5158 -99.0854)
		(width 0.11938)
		(layer "B.Cu")
		(net "R_XP5R0V_EN")
	)
	(segment
		(start 39.116 -95.9104)
		(end 39.116 -97.0534)
		(width 0.11938)
		(layer "B.Cu")
		(net "R_XP5R0V_EN")
	)
	(segment
		(start 38.989 -99.187)
		(end 38.8366 -99.0346)
		(width 0.11938)
		(layer "B.Cu")
		(net "R_XP5R0V_EN")
	)
	(segment
		(start 39.116 -97.0534)
		(end 39.0906 -97.0788)
		(width 0.11938)
		(layer "B.Cu")
		(net "R_XP5R0V_EN")
	)
	(segment
		(start 43.51782 -17.526)
		(end 42.21988 -17.526)
		(width 0.11938)
		(layer "F.Cu")
		(net "PCIE_CONN_SMDAT")
	)
	(segment
		(start 50.649886 -3.500374)
		(end 50.649886 -8.947404)
		(width 0.11938)
		(layer "F.Cu")
		(net "PCIE_CONN_SMDAT")
	)
	(segment
		(start 50.649886 -8.947404)
		(end 50.32629 -9.271)
		(width 0.11938)
		(layer "F.Cu")
		(net "PCIE_CONN_SMDAT")
	)
	(segment
		(start 43.98518 -17.99336)
		(end 43.51782 -17.526)
		(width 0.11938)
		(layer "F.Cu")
		(net "PCIE_CONN_SMDAT")
	)
	(via
		(at 43.98518 -17.99336)
		(size 0.508)
		(drill 0.254)
		(layers "F.Cu" "B.Cu")
		(net "PCIE_CONN_SMDAT")
	)
	(via
		(at 50.32629 -9.271)
		(size 0.4572)
		(drill 0.2032)
		(layers "F.Cu" "B.Cu")
		(net "PCIE_CONN_SMDAT")
	)
	(segment
		(start 48.006 -11.811)
		(end 44.704 -15.113)
		(width 0.127)
		(layer "In7.Cu")
		(net "PCIE_CONN_SMDAT")
	)
	(segment
		(start 48.006 -10.287)
		(end 48.006 -11.811)
		(width 0.127)
		(layer "In7.Cu")
		(net "PCIE_CONN_SMDAT")
	)
	(segment
		(start 44.704 -17.27454)
		(end 43.98518 -17.99336)
		(width 0.127)
		(layer "In7.Cu")
		(net "PCIE_CONN_SMDAT")
	)
	(segment
		(start 49.022 -9.271)
		(end 48.006 -10.287)
		(width 0.127)
		(layer "In7.Cu")
		(net "PCIE_CONN_SMDAT")
	)
	(segment
		(start 50.32629 -9.271)
		(end 49.022 -9.271)
		(width 0.127)
		(layer "In7.Cu")
		(net "PCIE_CONN_SMDAT")
	)
	(segment
		(start 44.704 -15.113)
		(end 44.704 -17.27454)
		(width 0.127)
		(layer "In7.Cu")
		(net "PCIE_CONN_SMDAT")
	)
	(segment
		(start 49.649888 -9.430258)
		(end 49.649888 -3.500374)
		(width 0.11938)
		(layer "F.Cu")
		(net "PCIE_CONN_SMCLK")
	)
	(segment
		(start 46.25594 -17.526)
		(end 47.83328 -17.526)
		(width 0.11938)
		(layer "F.Cu")
		(net "PCIE_CONN_SMCLK")
	)
	(segment
		(start 45.81906 -17.96288)
		(end 46.25594 -17.526)
		(width 0.11938)
		(layer "F.Cu")
		(net "PCIE_CONN_SMCLK")
	)
	(segment
		(start 48.64989 -10.430256)
		(end 49.649888 -9.430258)
		(width 0.11938)
		(layer "F.Cu")
		(net "PCIE_CONN_SMCLK")
	)
	(segment
		(start 48.64989 -10.4648)
		(end 48.64989 -10.430256)
		(width 0.11938)
		(layer "F.Cu")
		(net "PCIE_CONN_SMCLK")
	)
	(via
		(at 48.64989 -10.4648)
		(size 0.4572)
		(drill 0.2032)
		(layers "F.Cu" "B.Cu")
		(net "PCIE_CONN_SMCLK")
	)
	(via
		(at 45.81906 -17.96288)
		(size 0.4572)
		(drill 0.2032)
		(layers "F.Cu" "B.Cu")
		(net "PCIE_CONN_SMCLK")
	)
	(segment
		(start 48.64989 -12.310364)
		(end 48.64989 -10.4648)
		(width 0.127)
		(layer "In7.Cu")
		(net "PCIE_CONN_SMCLK")
	)
	(segment
		(start 47.54499 -15.368524)
		(end 46.988476 -14.81201)
		(width 0.127)
		(layer "In7.Cu")
		(net "PCIE_CONN_SMCLK")
	)
	(segment
		(start 45.81906 -17.96288)
		(end 45.40504 -17.54886)
		(width 0.127)
		(layer "In7.Cu")
		(net "PCIE_CONN_SMCLK")
	)
	(segment
		(start 45.40504 -17.54886)
		(end 45.40504 -15.874746)
		(width 0.127)
		(layer "In7.Cu")
		(net "PCIE_CONN_SMCLK")
	)
	(segment
		(start 47.27575 -15.817596)
		(end 47.54499 -15.548356)
		(width 0.127)
		(layer "In7.Cu")
		(net "PCIE_CONN_SMCLK")
	)
	(segment
		(start 47.258224 -13.70203)
		(end 48.64989 -12.310364)
		(width 0.127)
		(layer "In7.Cu")
		(net "PCIE_CONN_SMCLK")
	)
	(segment
		(start 45.724826 -15.55496)
		(end 46.065694 -15.55496)
		(width 0.127)
		(layer "In7.Cu")
		(net "PCIE_CONN_SMCLK")
	)
	(segment
		(start 46.539404 -15.261082)
		(end 47.095918 -15.817596)
		(width 0.127)
		(layer "In7.Cu")
		(net "PCIE_CONN_SMCLK")
	)
	(segment
		(start 47.54499 -15.548356)
		(end 47.54499 -15.368524)
		(width 0.127)
		(layer "In7.Cu")
		(net "PCIE_CONN_SMCLK")
	)
	(segment
		(start 46.065694 -15.55496)
		(end 46.359572 -15.261082)
		(width 0.127)
		(layer "In7.Cu")
		(net "PCIE_CONN_SMCLK")
	)
	(segment
		(start 46.359572 -15.261082)
		(end 46.539404 -15.261082)
		(width 0.127)
		(layer "In7.Cu")
		(net "PCIE_CONN_SMCLK")
	)
	(segment
		(start 47.095918 -15.817596)
		(end 47.27575 -15.817596)
		(width 0.127)
		(layer "In7.Cu")
		(net "PCIE_CONN_SMCLK")
	)
	(segment
		(start 46.988476 -14.81201)
		(end 46.988476 -14.632178)
		(width 0.127)
		(layer "In7.Cu")
		(net "PCIE_CONN_SMCLK")
	)
	(segment
		(start 45.40504 -15.874746)
		(end 45.724826 -15.55496)
		(width 0.127)
		(layer "In7.Cu")
		(net "PCIE_CONN_SMCLK")
	)
	(segment
		(start 47.258224 -14.36243)
		(end 47.258224 -13.70203)
		(width 0.127)
		(layer "In7.Cu")
		(net "PCIE_CONN_SMCLK")
	)
	(segment
		(start 46.988476 -14.632178)
		(end 47.258224 -14.36243)
		(width 0.127)
		(layer "In7.Cu")
		(net "PCIE_CONN_SMCLK")
	)
	(segment
		(start 80.733646 -47.76724)
		(end 82.03692 -47.76724)
		(width 0.14478)
		(layer "F.Cu")
		(net "MUX_USB_DP")
	)
	(segment
		(start 89.05113 -48.47082)
		(end 89.05113 -48.453548)
		(width 0.14478)
		(layer "F.Cu")
		(net "MUX_USB_DP")
	)
	(segment
		(start 82.17662 -47.881794)
		(end 82.17662 -48.035718)
		(width 0.14478)
		(layer "F.Cu")
		(net "MUX_USB_DP")
	)
	(segment
		(start 82.111596 -48.19269)
		(end 81.96834 -48.335946)
		(width 0.14478)
		(layer "F.Cu")
		(net "MUX_USB_DP")
	)
	(segment
		(start 87.996522 -48.453548)
		(end 88.040464 -48.47082)
		(width 0.14478)
		(layer "F.Cu")
		(net "MUX_USB_DP")
	)
	(segment
		(start 87.706454 -48.234346)
		(end 87.792052 -48.31969)
		(width 0.14478)
		(layer "F.Cu")
		(net "MUX_USB_DP")
	)
	(segment
		(start 88.040464 -48.47082)
		(end 89.05113 -48.47082)
		(width 0.14478)
		(layer "F.Cu")
		(net "MUX_USB_DP")
	)
	(segment
		(start 80.2894 -48.133)
		(end 80.505808 -47.916592)
		(width 0.14478)
		(layer "F.Cu")
		(net "MUX_USB_DP")
	)
	(segment
		(start 82.173572 -47.864776)
		(end 82.17662 -47.881794)
		(width 0.14478)
		(layer "F.Cu")
		(net "MUX_USB_DP")
	)
	(via
		(at 87.706454 -48.234346)
		(size 0.4572)
		(drill 0.2032)
		(layers "F.Cu" "B.Cu")
		(net "MUX_USB_DP")
	)
	(via
		(at 81.96834 -48.335946)
		(size 0.4572)
		(drill 0.2032)
		(layers "F.Cu" "B.Cu")
		(net "MUX_USB_DP")
	)
	(arc
		(start 82.17662 -48.035718)
		(mid 82.159722 -48.120672)
		(end 82.111596 -48.19269)
		(width 0.14478)
		(layer "F.Cu")
		(net "MUX_USB_DP")
	)
	(arc
		(start 80.505808 -47.916592)
		(mid 80.612045 -47.830193)
		(end 80.733646 -47.76724)
		(width 0.14478)
		(layer "F.Cu")
		(net "MUX_USB_DP")
	)
	(arc
		(start 82.03692 -47.76724)
		(mid 82.120871 -47.794122)
		(end 82.173572 -47.864776)
		(width 0.14478)
		(layer "F.Cu")
		(net "MUX_USB_DP")
	)
	(arc
		(start 87.792052 -48.31969)
		(mid 87.887367 -48.397189)
		(end 87.996522 -48.453548)
		(width 0.14478)
		(layer "F.Cu")
		(net "MUX_USB_DP")
	)
	(segment
		(start 86.952836 -48.46066)
		(end 86.623398 -48.46066)
		(width 0.14478)
		(layer "B.Cu")
		(net "MUX_USB_DP")
	)
	(segment
		(start 82.559144 -47.16907)
		(end 82.330798 -47.397416)
		(width 0.14478)
		(layer "B.Cu")
		(net "MUX_USB_DP")
	)
	(segment
		(start 84.6963 -46.9646)
		(end 83.05292 -46.9646)
		(width 0.14478)
		(layer "B.Cu")
		(net "MUX_USB_DP")
	)
	(segment
		(start 87.706454 -48.234346)
		(end 87.498936 -48.234346)
		(width 0.14478)
		(layer "B.Cu")
		(net "MUX_USB_DP")
	)
	(segment
		(start 82.17662 -47.769526)
		(end 82.17662 -47.994824)
		(width 0.14478)
		(layer "B.Cu")
		(net "MUX_USB_DP")
	)
	(segment
		(start 82.08264 -48.221646)
		(end 81.96834 -48.335946)
		(width 0.14478)
		(layer "B.Cu")
		(net "MUX_USB_DP")
	)
	(segment
		(start 89.7382 -47.916846)
		(end 89.470484 -48.184562)
		(width 0.14478)
		(layer "B.Cu")
		(net "MUX_USB_DP")
	)
	(segment
		(start 88.641936 -48.387)
		(end 88.199722 -48.387)
		(width 0.14478)
		(layer "B.Cu")
		(net "MUX_USB_DP")
	)
	(segment
		(start 87.818722 -48.346614)
		(end 87.706454 -48.234346)
		(width 0.14478)
		(layer "B.Cu")
		(net "MUX_USB_DP")
	)
	(segment
		(start 86.407498 -48.371252)
		(end 85.216238 -47.179992)
		(width 0.14478)
		(layer "B.Cu")
		(net "MUX_USB_DP")
	)
	(arc
		(start 89.319354 -48.279304)
		(mid 89.263411 -48.272379)
		(end 89.207086 -48.27016)
		(width 0.14478)
		(layer "B.Cu")
		(net "MUX_USB_DP")
	)
	(arc
		(start 87.945468 -48.423576)
		(mid 87.877492 -48.392678)
		(end 87.818722 -48.346614)
		(width 0.14478)
		(layer "B.Cu")
		(net "MUX_USB_DP")
	)
	(arc
		(start 83.05292 -46.9646)
		(mid 82.785713 -47.017751)
		(end 82.559144 -47.16907)
		(width 0.14478)
		(layer "B.Cu")
		(net "MUX_USB_DP")
	)
	(arc
		(start 82.330798 -47.397416)
		(mid 82.216669 -47.568127)
		(end 82.17662 -47.769526)
		(width 0.14478)
		(layer "B.Cu")
		(net "MUX_USB_DP")
	)
	(arc
		(start 89.207086 -48.27016)
		(mid 89.062619 -48.284892)
		(end 88.92413 -48.32858)
		(width 0.14478)
		(layer "B.Cu")
		(net "MUX_USB_DP")
	)
	(arc
		(start 82.17662 -47.994824)
		(mid 82.1522 -48.11759)
		(end 82.08264 -48.221646)
		(width 0.14478)
		(layer "B.Cu")
		(net "MUX_USB_DP")
	)
	(arc
		(start 87.498936 -48.234346)
		(mid 87.368632 -48.260171)
		(end 87.258144 -48.333914)
		(width 0.14478)
		(layer "B.Cu")
		(net "MUX_USB_DP")
	)
	(arc
		(start 87.258144 -48.333914)
		(mid 87.118111 -48.427701)
		(end 86.952836 -48.46066)
		(width 0.14478)
		(layer "B.Cu")
		(net "MUX_USB_DP")
	)
	(arc
		(start 88.199722 -48.387)
		(mid 88.071284 -48.396163)
		(end 87.945468 -48.423576)
		(width 0.14478)
		(layer "B.Cu")
		(net "MUX_USB_DP")
	)
	(arc
		(start 89.470484 -48.184562)
		(mid 89.400282 -48.24049)
		(end 89.319354 -48.279304)
		(width 0.14478)
		(layer "B.Cu")
		(net "MUX_USB_DP")
	)
	(arc
		(start 86.623398 -48.46066)
		(mid 86.506562 -48.43742)
		(end 86.407498 -48.371252)
		(width 0.14478)
		(layer "B.Cu")
		(net "MUX_USB_DP")
	)
	(arc
		(start 85.216238 -47.179992)
		(mid 84.977703 -47.020545)
		(end 84.6963 -46.9646)
		(width 0.14478)
		(layer "B.Cu")
		(net "MUX_USB_DP")
	)
	(arc
		(start 88.92413 -48.32858)
		(mid 88.786016 -48.372206)
		(end 88.641936 -48.387)
		(width 0.14478)
		(layer "B.Cu")
		(net "MUX_USB_DP")
	)
	(segment
		(start 82.78114 -48.335946)
		(end 82.675984 -48.23079)
		(width 0.14478)
		(layer "F.Cu")
		(net "MUX_USB_DM")
	)
	(segment
		(start 82.55762 -47.94504)
		(end 82.55762 -47.882048)
		(width 0.14478)
		(layer "F.Cu")
		(net "MUX_USB_DM")
	)
	(segment
		(start 82.03692 -47.38624)
		(end 80.81899 -47.38624)
		(width 0.14478)
		(layer "F.Cu")
		(net "MUX_USB_DM")
	)
	(segment
		(start 89.05113 -48.85182)
		(end 89.05113 -48.853344)
		(width 0.14478)
		(layer "F.Cu")
		(net "MUX_USB_DM")
	)
	(segment
		(start 87.988902 -48.85182)
		(end 89.05113 -48.85182)
		(width 0.14478)
		(layer "F.Cu")
		(net "MUX_USB_DM")
	)
	(segment
		(start 80.81899 -47.38624)
		(end 80.7593 -47.365412)
		(width 0.14478)
		(layer "F.Cu")
		(net "MUX_USB_DM")
	)
	(segment
		(start 87.706454 -49.047146)
		(end 87.748364 -49.004982)
		(width 0.14478)
		(layer "F.Cu")
		(net "MUX_USB_DM")
	)
	(segment
		(start 80.505808 -47.206408)
		(end 80.2894 -46.99)
		(width 0.14478)
		(layer "F.Cu")
		(net "MUX_USB_DM")
	)
	(via
		(at 87.706454 -49.047146)
		(size 0.4572)
		(drill 0.2032)
		(layers "F.Cu" "B.Cu")
		(net "MUX_USB_DM")
	)
	(via
		(at 82.78114 -48.335946)
		(size 0.4572)
		(drill 0.2032)
		(layers "F.Cu" "B.Cu")
		(net "MUX_USB_DM")
	)
	(arc
		(start 87.748364 -49.004982)
		(mid 87.86025 -48.915238)
		(end 87.988902 -48.85182)
		(width 0.14478)
		(layer "F.Cu")
		(net "MUX_USB_DM")
	)
	(arc
		(start 82.53349 -47.739046)
		(mid 82.341507 -47.483384)
		(end 82.03692 -47.38624)
		(width 0.14478)
		(layer "F.Cu")
		(net "MUX_USB_DM")
	)
	(arc
		(start 80.7593 -47.365412)
		(mid 80.623574 -47.300229)
		(end 80.505808 -47.206408)
		(width 0.14478)
		(layer "F.Cu")
		(net "MUX_USB_DM")
	)
	(arc
		(start 82.55762 -47.882048)
		(mid 82.55156 -47.809535)
		(end 82.53349 -47.739046)
		(width 0.14478)
		(layer "F.Cu")
		(net "MUX_USB_DM")
	)
	(arc
		(start 82.675984 -48.23079)
		(mid 82.588384 -48.099687)
		(end 82.55762 -47.94504)
		(width 0.14478)
		(layer "F.Cu")
		(net "MUX_USB_DM")
	)
	(segment
		(start 82.55762 -47.769526)
		(end 82.55762 -47.994824)
		(width 0.14478)
		(layer "B.Cu")
		(net "MUX_USB_DM")
	)
	(segment
		(start 88.64219 -48.768)
		(end 88.199722 -48.768)
		(width 0.14478)
		(layer "B.Cu")
		(net "MUX_USB_DM")
	)
	(segment
		(start 84.696554 -47.3456)
		(end 83.05292 -47.3456)
		(width 0.14478)
		(layer "B.Cu")
		(net "MUX_USB_DM")
	)
	(segment
		(start 86.138004 -48.640746)
		(end 84.946744 -47.449486)
		(width 0.14478)
		(layer "B.Cu")
		(net "MUX_USB_DM")
	)
	(segment
		(start 82.828638 -47.438564)
		(end 82.600292 -47.66691)
		(width 0.14478)
		(layer "B.Cu")
		(net "MUX_USB_DM")
	)
	(segment
		(start 86.952582 -48.84166)
		(end 86.623144 -48.84166)
		(width 0.14478)
		(layer "B.Cu")
		(net "MUX_USB_DM")
	)
	(segment
		(start 87.706454 -49.047146)
		(end 87.498936 -49.047146)
		(width 0.14478)
		(layer "B.Cu")
		(net "MUX_USB_DM")
	)
	(segment
		(start 82.65541 -48.210216)
		(end 82.78114 -48.335946)
		(width 0.14478)
		(layer "B.Cu")
		(net "MUX_USB_DM")
	)
	(segment
		(start 89.7382 -49.059846)
		(end 89.415874 -48.73752)
		(width 0.14478)
		(layer "B.Cu")
		(net "MUX_USB_DM")
	)
	(segment
		(start 87.834216 -48.919384)
		(end 87.706454 -49.047146)
		(width 0.14478)
		(layer "B.Cu")
		(net "MUX_USB_DM")
	)
	(arc
		(start 88.199722 -48.768)
		(mid 88.001931 -48.807361)
		(end 87.834216 -48.919384)
		(width 0.14478)
		(layer "B.Cu")
		(net "MUX_USB_DM")
	)
	(arc
		(start 86.623144 -48.84166)
		(mid 86.360588 -48.789452)
		(end 86.138004 -48.640746)
		(width 0.14478)
		(layer "B.Cu")
		(net "MUX_USB_DM")
	)
	(arc
		(start 83.05292 -47.3456)
		(mid 82.931515 -47.369749)
		(end 82.828638 -47.438564)
		(width 0.14478)
		(layer "B.Cu")
		(net "MUX_USB_DM")
	)
	(arc
		(start 87.2744 -48.962818)
		(mid 87.124508 -48.87299)
		(end 86.952582 -48.84166)
		(width 0.14478)
		(layer "B.Cu")
		(net "MUX_USB_DM")
	)
	(arc
		(start 87.498936 -49.047146)
		(mid 87.378998 -49.025409)
		(end 87.2744 -48.962818)
		(width 0.14478)
		(layer "B.Cu")
		(net "MUX_USB_DM")
	)
	(arc
		(start 84.946744 -47.449486)
		(mid 84.831985 -47.37265)
		(end 84.696554 -47.3456)
		(width 0.14478)
		(layer "B.Cu")
		(net "MUX_USB_DM")
	)
	(arc
		(start 89.07526 -48.678338)
		(mid 88.863305 -48.745298)
		(end 88.64219 -48.768)
		(width 0.14478)
		(layer "B.Cu")
		(net "MUX_USB_DM")
	)
	(arc
		(start 82.557112 -48.026066)
		(mid 82.592609 -48.12543)
		(end 82.65541 -48.210216)
		(width 0.14478)
		(layer "B.Cu")
		(net "MUX_USB_DM")
	)
	(arc
		(start 89.415874 -48.73752)
		(mid 89.320223 -48.673601)
		(end 89.20734 -48.651414)
		(width 0.14478)
		(layer "B.Cu")
		(net "MUX_USB_DM")
	)
	(arc
		(start 82.600292 -47.66691)
		(mid 82.568697 -47.713961)
		(end 82.55762 -47.769526)
		(width 0.14478)
		(layer "B.Cu")
		(net "MUX_USB_DM")
	)
	(arc
		(start 89.20734 -48.651414)
		(mid 89.139923 -48.658116)
		(end 89.07526 -48.678338)
		(width 0.14478)
		(layer "B.Cu")
		(net "MUX_USB_DM")
	)
	(arc
		(start 82.55762 -47.994824)
		(mid 82.557542 -48.010448)
		(end 82.557112 -48.026066)
		(width 0.14478)
		(layer "B.Cu")
		(net "MUX_USB_DM")
	)
	(segment
		(start 24.778716 -71.9074)
		(end 23.0632 -71.9074)
		(width 0.11938)
		(layer "B.Cu")
		(net "ANALOG_TUNING_IN")
	)
	(segment
		(start 29.619194 -67.066922)
		(end 24.778716 -71.9074)
		(width 0.11938)
		(layer "B.Cu")
		(net "ANALOG_TUNING_IN")
	)
	(segment
		(start 32.021018 -67.066922)
		(end 29.619194 -67.066922)
		(width 0.11938)
		(layer "B.Cu")
		(net "ANALOG_TUNING_IN")
	)
	(via
		(at 127.889 -100.203)
		(size 0.508)
		(drill 0.254)
		(layers "F.Cu" "B.Cu")
		(net "XP5R0V_VCC_ANT")
	)
	(via
		(at 128.905 -100.203)
		(size 0.508)
		(drill 0.254)
		(layers "F.Cu" "B.Cu")
		(net "XP5R0V_VCC_ANT")
	)
	(segment
		(start 75.565762 -47.996602)
		(end 74.354436 -47.996602)
		(width 0.254)
		(layer "F.Cu")
		(net "XP5R0V_MAC_USB")
	)
	(segment
		(start 75.634088 -47.928276)
		(end 75.565762 -47.996602)
		(width 0.254)
		(layer "F.Cu")
		(net "XP5R0V_MAC_USB")
	)
	(segment
		(start 76.45273 -47.653194)
		(end 76.177648 -47.928276)
		(width 0.381)
		(layer "F.Cu")
		(net "XP5R0V_MAC_USB")
	)
	(segment
		(start 76.177648 -47.928276)
		(end 75.634088 -47.928276)
		(width 0.381)
		(layer "F.Cu")
		(net "XP5R0V_MAC_USB")
	)
	(via
		(at 75.634088 -47.928276)
		(size 0.508)
		(drill 0.254)
		(layers "F.Cu" "B.Cu")
		(net "XP5R0V_MAC_USB")
	)
	(via
		(at 73.025 -51.689)
		(size 0.762)
		(drill 0.381)
		(layers "F.Cu" "B.Cu")
		(net "XP5R0V_MAC_USB")
	)
	(via
		(at 76.45273 -47.653194)
		(size 0.508)
		(drill 0.254)
		(layers "F.Cu" "B.Cu")
		(net "XP5R0V_MAC_USB")
	)
	(segment
		(start 52.649882 -3.500374)
		(end 52.649882 -6.929882)
		(width 0.381)
		(layer "F.Cu")
		(net "XP3R3V_PCIE")
	)
	(segment
		(start 87.63 -17.272)
		(end 86.487 -16.129)
		(width 0.381)
		(layer "F.Cu")
		(net "XP3R3V_PCIE")
	)
	(segment
		(start 52.649882 -6.929882)
		(end 53.467 -7.747)
		(width 0.381)
		(layer "F.Cu")
		(net "XP3R3V_PCIE")
	)
	(segment
		(start 134.493 -15.367)
		(end 133.477 -16.383)
		(width 0.381)
		(layer "F.Cu")
		(net "XP3R3V_PCIE")
	)
	(segment
		(start 131.064 -15.621)
		(end 92.202 -15.621)
		(width 0.381)
		(layer "F.Cu")
		(net "XP3R3V_PCIE")
	)
	(segment
		(start 133.477 -16.383)
		(end 131.826 -16.383)
		(width 0.381)
		(layer "F.Cu")
		(net "XP3R3V_PCIE")
	)
	(segment
		(start 90.551 -17.272)
		(end 87.63 -17.272)
		(width 0.381)
		(layer "F.Cu")
		(net "XP3R3V_PCIE")
	)
	(segment
		(start 92.202 -15.621)
		(end 90.551 -17.272)
		(width 0.381)
		(layer "F.Cu")
		(net "XP3R3V_PCIE")
	)
	(segment
		(start 131.826 -16.383)
		(end 131.064 -15.621)
		(width 0.381)
		(layer "F.Cu")
		(net "XP3R3V_PCIE")
	)
	(via
		(at 56.769 -14.7955)
		(size 0.508)
		(drill 0.254)
		(layers "F.Cu" "B.Cu")
		(net "XP3R3V_PCIE")
	)
	(via
		(at 86.487 -16.129)
		(size 0.508)
		(drill 0.254)
		(layers "F.Cu" "B.Cu")
		(net "XP3R3V_PCIE")
	)
	(via
		(at 134.493 -15.367)
		(size 0.508)
		(drill 0.254)
		(layers "F.Cu" "B.Cu")
		(net "XP3R3V_PCIE")
	)
	(via
		(at 53.467 -7.747)
		(size 0.4572)
		(drill 0.2032)
		(layers "F.Cu" "B.Cu")
		(net "XP3R3V_PCIE")
	)
	(via
		(at 150.114 -102.616)
		(size 0.508)
		(drill 0.254)
		(layers "F.Cu" "B.Cu")
		(net "XP3R3V_PCIE")
	)
	(segment
		(start 150.114 -103.8606)
		(end 150.114 -102.616)
		(width 0.381)
		(layer "B.Cu")
		(net "XP3R3V_PCIE")
	)
	(segment
		(start 53.467 -7.6454)
		(end 53.64988 -7.46252)
		(width 0.381)
		(layer "B.Cu")
		(net "XP3R3V_PCIE")
	)
	(segment
		(start 53.467 -7.747)
		(end 53.467 -7.6454)
		(width 0.381)
		(layer "B.Cu")
		(net "XP3R3V_PCIE")
	)
	(segment
		(start 54.3814 -7.7216)
		(end 54.649878 -7.453122)
		(width 0.381)
		(layer "B.Cu")
		(net "XP3R3V_PCIE")
	)
	(segment
		(start 54.649878 -7.453122)
		(end 54.649878 -3.500374)
		(width 0.381)
		(layer "B.Cu")
		(net "XP3R3V_PCIE")
	)
	(segment
		(start 53.64988 -7.46252)
		(end 53.64988 -3.500374)
		(width 0.381)
		(layer "B.Cu")
		(net "XP3R3V_PCIE")
	)
	(segment
		(start 160.0835 -61.912246)
		(end 162.260026 -64.088772)
		(width 0.381)
		(layer "In7.Cu")
		(net "XP3R3V_PCIE")
	)
	(segment
		(start 144.04594 -99.06)
		(end 144.933416 -99.06)
		(width 0.381)
		(layer "In7.Cu")
		(net "XP3R3V_PCIE")
	)
	(segment
		(start 143.383 -94.996)
		(end 142.6845 -95.6945)
		(width 0.381)
		(layer "In7.Cu")
		(net "XP3R3V_PCIE")
	)
	(segment
		(start 161.844228 -78.059026)
		(end 149.398228 -78.059026)
		(width 0.381)
		(layer "In7.Cu")
		(net "XP3R3V_PCIE")
	)
	(segment
		(start 144.220692 -15.074138)
		(end 145.402554 -16.256)
		(width 0.381)
		(layer "In7.Cu")
		(net "XP3R3V_PCIE")
	)
	(segment
		(start 149.398228 -78.059026)
		(end 145.669 -81.788254)
		(width 0.381)
		(layer "In7.Cu")
		(net "XP3R3V_PCIE")
	)
	(segment
		(start 139.73556 -16.8275)
		(end 141.488922 -15.074138)
		(width 0.381)
		(layer "In7.Cu")
		(net "XP3R3V_PCIE")
	)
	(segment
		(start 157.099254 -17.653)
		(end 163.449 -24.002746)
		(width 0.381)
		(layer "In7.Cu")
		(net "XP3R3V_PCIE")
	)
	(segment
		(start 145.669 -81.788254)
		(end 145.669 -89.281)
		(width 0.381)
		(layer "In7.Cu")
		(net "XP3R3V_PCIE")
	)
	(segment
		(start 86.487 -16.129)
		(end 86.487 -15.49654)
		(width 0.381)
		(layer "In7.Cu")
		(net "XP3R3V_PCIE")
	)
	(segment
		(start 160.0835 -49.212754)
		(end 160.0835 -61.912246)
		(width 0.381)
		(layer "In7.Cu")
		(net "XP3R3V_PCIE")
	)
	(segment
		(start 145.669 -89.281)
		(end 145.0213 -89.9287)
		(width 0.381)
		(layer "In7.Cu")
		(net "XP3R3V_PCIE")
	)
	(segment
		(start 142.6845 -96.9645)
		(end 143.4465 -97.7265)
		(width 0.381)
		(layer "In7.Cu")
		(net "XP3R3V_PCIE")
	)
	(segment
		(start 62.1284 -13.4874)
		(end 58.0771 -13.4874)
		(width 0.381)
		(layer "In7.Cu")
		(net "XP3R3V_PCIE")
	)
	(segment
		(start 63.5508 -12.065)
		(end 62.1284 -13.4874)
		(width 0.381)
		(layer "In7.Cu")
		(net "XP3R3V_PCIE")
	)
	(segment
		(start 78.6638 -13.2842)
		(end 73.6092 -13.2842)
		(width 0.381)
		(layer "In7.Cu")
		(net "XP3R3V_PCIE")
	)
	(segment
		(start 145.6055 -16.256)
		(end 147.0025 -17.653)
		(width 0.381)
		(layer "In7.Cu")
		(net "XP3R3V_PCIE")
	)
	(segment
		(start 145.0213 -89.9287)
		(end 143.993108 -89.9287)
		(width 0.381)
		(layer "In7.Cu")
		(net "XP3R3V_PCIE")
	)
	(segment
		(start 150.114 -102.235)
		(end 150.114 -102.616)
		(width 0.381)
		(layer "In7.Cu")
		(net "XP3R3V_PCIE")
	)
	(segment
		(start 135.509 -16.383)
		(end 138.182096 -16.383)
		(width 0.381)
		(layer "In7.Cu")
		(net "XP3R3V_PCIE")
	)
	(segment
		(start 163.449 -45.847254)
		(end 160.0835 -49.212754)
		(width 0.381)
		(layer "In7.Cu")
		(net "XP3R3V_PCIE")
	)
	(segment
		(start 85.598 -14.60754)
		(end 79.98714 -14.60754)
		(width 0.381)
		(layer "In7.Cu")
		(net "XP3R3V_PCIE")
	)
	(segment
		(start 58.0771 -13.4874)
		(end 56.769 -14.7955)
		(width 0.381)
		(layer "In7.Cu")
		(net "XP3R3V_PCIE")
	)
	(segment
		(start 134.493 -15.367)
		(end 135.509 -16.383)
		(width 0.381)
		(layer "In7.Cu")
		(net "XP3R3V_PCIE")
	)
	(segment
		(start 163.449 -24.002746)
		(end 163.449 -45.847254)
		(width 0.381)
		(layer "In7.Cu")
		(net "XP3R3V_PCIE")
	)
	(segment
		(start 143.383 -90.538808)
		(end 143.383 -94.996)
		(width 0.381)
		(layer "In7.Cu")
		(net "XP3R3V_PCIE")
	)
	(segment
		(start 147.0025 -17.653)
		(end 157.099254 -17.653)
		(width 0.381)
		(layer "In7.Cu")
		(net "XP3R3V_PCIE")
	)
	(segment
		(start 79.98714 -14.60754)
		(end 78.6638 -13.2842)
		(width 0.381)
		(layer "In7.Cu")
		(net "XP3R3V_PCIE")
	)
	(segment
		(start 72.39 -12.065)
		(end 63.5508 -12.065)
		(width 0.381)
		(layer "In7.Cu")
		(net "XP3R3V_PCIE")
	)
	(segment
		(start 146.88439 -101.010974)
		(end 148.889974 -101.010974)
		(width 0.381)
		(layer "In7.Cu")
		(net "XP3R3V_PCIE")
	)
	(segment
		(start 145.402554 -16.256)
		(end 145.6055 -16.256)
		(width 0.381)
		(layer "In7.Cu")
		(net "XP3R3V_PCIE")
	)
	(segment
		(start 73.6092 -13.2842)
		(end 72.39 -12.065)
		(width 0.381)
		(layer "In7.Cu")
		(net "XP3R3V_PCIE")
	)
	(segment
		(start 142.6845 -95.6945)
		(end 142.6845 -96.9645)
		(width 0.381)
		(layer "In7.Cu")
		(net "XP3R3V_PCIE")
	)
	(segment
		(start 148.889974 -101.010974)
		(end 150.114 -102.235)
		(width 0.381)
		(layer "In7.Cu")
		(net "XP3R3V_PCIE")
	)
	(segment
		(start 143.4465 -98.46056)
		(end 144.04594 -99.06)
		(width 0.381)
		(layer "In7.Cu")
		(net "XP3R3V_PCIE")
	)
	(segment
		(start 143.993108 -89.9287)
		(end 143.383 -90.538808)
		(width 0.381)
		(layer "In7.Cu")
		(net "XP3R3V_PCIE")
	)
	(segment
		(start 144.933416 -99.06)
		(end 146.88439 -101.010974)
		(width 0.381)
		(layer "In7.Cu")
		(net "XP3R3V_PCIE")
	)
	(segment
		(start 162.260026 -77.643228)
		(end 161.844228 -78.059026)
		(width 0.381)
		(layer "In7.Cu")
		(net "XP3R3V_PCIE")
	)
	(segment
		(start 86.487 -15.49654)
		(end 85.598 -14.60754)
		(width 0.381)
		(layer "In7.Cu")
		(net "XP3R3V_PCIE")
	)
	(segment
		(start 141.488922 -15.074138)
		(end 144.220692 -15.074138)
		(width 0.381)
		(layer "In7.Cu")
		(net "XP3R3V_PCIE")
	)
	(segment
		(start 138.626596 -16.8275)
		(end 139.73556 -16.8275)
		(width 0.381)
		(layer "In7.Cu")
		(net "XP3R3V_PCIE")
	)
	(segment
		(start 138.182096 -16.383)
		(end 138.626596 -16.8275)
		(width 0.381)
		(layer "In7.Cu")
		(net "XP3R3V_PCIE")
	)
	(segment
		(start 162.260026 -64.088772)
		(end 162.260026 -77.643228)
		(width 0.381)
		(layer "In7.Cu")
		(net "XP3R3V_PCIE")
	)
	(segment
		(start 143.4465 -97.7265)
		(end 143.4465 -98.46056)
		(width 0.381)
		(layer "In7.Cu")
		(net "XP3R3V_PCIE")
	)
	(segment
		(start 54.229 -13.716)
		(end 54.229 -13.208)
		(width 0.381)
		(layer "F.Cu")
		(net "XP3R3V_AUX_PCIE")
	)
	(segment
		(start 54.61 -12.827)
		(end 54.61 -9.09574)
		(width 0.381)
		(layer "F.Cu")
		(net "XP3R3V_AUX_PCIE")
	)
	(segment
		(start 55.0672 -7.366)
		(end 54.649878 -6.948678)
		(width 0.381)
		(layer "F.Cu")
		(net "XP3R3V_AUX_PCIE")
	)
	(segment
		(start 88.011 -16.383)
		(end 86.8045 -15.1765)
		(width 0.381)
		(layer "F.Cu")
		(net "XP3R3V_AUX_PCIE")
	)
	(segment
		(start 54.61 -15.0876)
		(end 54.61 -14.351)
		(width 0.381)
		(layer "F.Cu")
		(net "XP3R3V_AUX_PCIE")
	)
	(segment
		(start 54.61 -9.09574)
		(end 55.0672 -8.63854)
		(width 0.381)
		(layer "F.Cu")
		(net "XP3R3V_AUX_PCIE")
	)
	(segment
		(start 54.649878 -6.948678)
		(end 54.649878 -3.500374)
		(width 0.381)
		(layer "F.Cu")
		(net "XP3R3V_AUX_PCIE")
	)
	(segment
		(start 91.948 -14.732)
		(end 90.297 -16.383)
		(width 0.381)
		(layer "F.Cu")
		(net "XP3R3V_AUX_PCIE")
	)
	(segment
		(start 85.67674 -15.1765)
		(end 85.344 -15.50924)
		(width 0.381)
		(layer "F.Cu")
		(net "XP3R3V_AUX_PCIE")
	)
	(segment
		(start 54.229 -13.208)
		(end 54.61 -12.827)
		(width 0.381)
		(layer "F.Cu")
		(net "XP3R3V_AUX_PCIE")
	)
	(segment
		(start 131.953 -14.732)
		(end 91.948 -14.732)
		(width 0.381)
		(layer "F.Cu")
		(net "XP3R3V_AUX_PCIE")
	)
	(segment
		(start 54.229 -13.97)
		(end 54.229 -13.716)
		(width 0.381)
		(layer "F.Cu")
		(net "XP3R3V_AUX_PCIE")
	)
	(segment
		(start 132.461 -15.24)
		(end 131.953 -14.732)
		(width 0.381)
		(layer "F.Cu")
		(net "XP3R3V_AUX_PCIE")
	)
	(segment
		(start 86.8045 -15.1765)
		(end 85.67674 -15.1765)
		(width 0.381)
		(layer "F.Cu")
		(net "XP3R3V_AUX_PCIE")
	)
	(segment
		(start 54.61 -14.351)
		(end 54.229 -13.97)
		(width 0.381)
		(layer "F.Cu")
		(net "XP3R3V_AUX_PCIE")
	)
	(segment
		(start 90.297 -16.383)
		(end 88.011 -16.383)
		(width 0.381)
		(layer "F.Cu")
		(net "XP3R3V_AUX_PCIE")
	)
	(segment
		(start 54.61 -15.0876)
		(end 53.467 -15.0876)
		(width 0.381)
		(layer "F.Cu")
		(net "XP3R3V_AUX_PCIE")
	)
	(segment
		(start 55.0672 -8.63854)
		(end 55.0672 -7.366)
		(width 0.381)
		(layer "F.Cu")
		(net "XP3R3V_AUX_PCIE")
	)
	(via
		(at 132.461 -15.24)
		(size 0.508)
		(drill 0.254)
		(layers "F.Cu" "B.Cu")
		(net "XP3R3V_AUX_PCIE")
	)
	(via
		(at 85.344 -15.50924)
		(size 0.508)
		(drill 0.254)
		(layers "F.Cu" "B.Cu")
		(net "XP3R3V_AUX_PCIE")
	)
	(via
		(at 54.229 -13.716)
		(size 0.508)
		(drill 0.254)
		(layers "F.Cu" "B.Cu")
		(net "XP3R3V_AUX_PCIE")
	)
	(via
		(at 153.035 -102.616)
		(size 0.508)
		(drill 0.254)
		(layers "F.Cu" "B.Cu")
		(net "XP3R3V_AUX_PCIE")
	)
	(segment
		(start 153.035 -103.8606)
		(end 153.035 -102.616)
		(width 0.381)
		(layer "B.Cu")
		(net "XP3R3V_AUX_PCIE")
	)
	(segment
		(start 85.23224 -15.621)
		(end 79.248 -15.621)
		(width 0.381)
		(layer "In2.Cu")
		(net "XP3R3V_AUX_PCIE")
	)
	(segment
		(start 65.405 -14.859)
		(end 64.135 -13.589)
		(width 0.381)
		(layer "In2.Cu")
		(net "XP3R3V_AUX_PCIE")
	)
	(segment
		(start 54.356 -13.589)
		(end 54.229 -13.716)
		(width 0.381)
		(layer "In2.Cu")
		(net "XP3R3V_AUX_PCIE")
	)
	(segment
		(start 73.632314 -14.478)
		(end 73.251314 -14.859)
		(width 0.381)
		(layer "In2.Cu")
		(net "XP3R3V_AUX_PCIE")
	)
	(segment
		(start 78.105 -14.478)
		(end 73.632314 -14.478)
		(width 0.381)
		(layer "In2.Cu")
		(net "XP3R3V_AUX_PCIE")
	)
	(segment
		(start 64.135 -13.589)
		(end 54.356 -13.589)
		(width 0.381)
		(layer "In2.Cu")
		(net "XP3R3V_AUX_PCIE")
	)
	(segment
		(start 85.344 -15.50924)
		(end 85.23224 -15.621)
		(width 0.381)
		(layer "In2.Cu")
		(net "XP3R3V_AUX_PCIE")
	)
	(segment
		(start 73.251314 -14.859)
		(end 65.405 -14.859)
		(width 0.381)
		(layer "In2.Cu")
		(net "XP3R3V_AUX_PCIE")
	)
	(segment
		(start 79.248 -15.621)
		(end 78.105 -14.478)
		(width 0.381)
		(layer "In2.Cu")
		(net "XP3R3V_AUX_PCIE")
	)
	(segment
		(start 149.86 -78.867)
		(end 147.193 -81.534)
		(width 0.381)
		(layer "In7.Cu")
		(net "XP3R3V_AUX_PCIE")
	)
	(segment
		(start 160.782 -54.356)
		(end 160.782 -61.468)
		(width 0.381)
		(layer "In7.Cu")
		(net "XP3R3V_AUX_PCIE")
	)
	(segment
		(start 147.193 -81.534)
		(end 147.193 -89.154)
		(width 0.381)
		(layer "In7.Cu")
		(net "XP3R3V_AUX_PCIE")
	)
	(segment
		(start 165.227 -45.212)
		(end 161.6075 -48.8315)
		(width 0.381)
		(layer "In7.Cu")
		(net "XP3R3V_AUX_PCIE")
	)
	(segment
		(start 161.5821 -53.5559)
		(end 160.782 -54.356)
		(width 0.381)
		(layer "In7.Cu")
		(net "XP3R3V_AUX_PCIE")
	)
	(segment
		(start 161.6075 -50.295556)
		(end 161.379408 -50.523648)
		(width 0.381)
		(layer "In7.Cu")
		(net "XP3R3V_AUX_PCIE")
	)
	(segment
		(start 162.179 -78.867)
		(end 149.86 -78.867)
		(width 0.381)
		(layer "In7.Cu")
		(net "XP3R3V_AUX_PCIE")
	)
	(segment
		(start 163.068 -77.978)
		(end 162.179 -78.867)
		(width 0.381)
		(layer "In7.Cu")
		(net "XP3R3V_AUX_PCIE")
	)
	(segment
		(start 145.669 -98.679)
		(end 147.193 -100.203)
		(width 0.381)
		(layer "In7.Cu")
		(net "XP3R3V_AUX_PCIE")
	)
	(segment
		(start 147.193 -89.154)
		(end 145.669 -90.678)
		(width 0.381)
		(layer "In7.Cu")
		(net "XP3R3V_AUX_PCIE")
	)
	(segment
		(start 165.227 -24.638)
		(end 165.227 -45.212)
		(width 0.381)
		(layer "In7.Cu")
		(net "XP3R3V_AUX_PCIE")
	)
	(segment
		(start 161.6075 -48.8315)
		(end 161.6075 -50.295556)
		(width 0.381)
		(layer "In7.Cu")
		(net "XP3R3V_AUX_PCIE")
	)
	(segment
		(start 149.225 -100.203)
		(end 151.638 -102.616)
		(width 0.381)
		(layer "In7.Cu")
		(net "XP3R3V_AUX_PCIE")
	)
	(segment
		(start 132.461 -15.24)
		(end 133.261862 -14.439138)
		(width 0.381)
		(layer "In7.Cu")
		(net "XP3R3V_AUX_PCIE")
	)
	(segment
		(start 161.379408 -51.81854)
		(end 161.5821 -52.021232)
		(width 0.381)
		(layer "In7.Cu")
		(net "XP3R3V_AUX_PCIE")
	)
	(segment
		(start 133.261862 -14.439138)
		(end 148.464524 -14.439138)
		(width 0.381)
		(layer "In7.Cu")
		(net "XP3R3V_AUX_PCIE")
	)
	(segment
		(start 161.379408 -50.523648)
		(end 161.379408 -51.81854)
		(width 0.381)
		(layer "In7.Cu")
		(net "XP3R3V_AUX_PCIE")
	)
	(segment
		(start 147.193 -100.203)
		(end 149.225 -100.203)
		(width 0.381)
		(layer "In7.Cu")
		(net "XP3R3V_AUX_PCIE")
	)
	(segment
		(start 145.669 -90.678)
		(end 145.669 -98.679)
		(width 0.381)
		(layer "In7.Cu")
		(net "XP3R3V_AUX_PCIE")
	)
	(segment
		(start 149.265386 -15.24)
		(end 155.829 -15.24)
		(width 0.381)
		(layer "In7.Cu")
		(net "XP3R3V_AUX_PCIE")
	)
	(segment
		(start 151.638 -102.616)
		(end 153.035 -102.616)
		(width 0.381)
		(layer "In7.Cu")
		(net "XP3R3V_AUX_PCIE")
	)
	(segment
		(start 160.782 -61.468)
		(end 163.068 -63.754)
		(width 0.381)
		(layer "In7.Cu")
		(net "XP3R3V_AUX_PCIE")
	)
	(segment
		(start 161.5821 -52.021232)
		(end 161.5821 -53.5559)
		(width 0.381)
		(layer "In7.Cu")
		(net "XP3R3V_AUX_PCIE")
	)
	(segment
		(start 148.464524 -14.439138)
		(end 149.265386 -15.24)
		(width 0.381)
		(layer "In7.Cu")
		(net "XP3R3V_AUX_PCIE")
	)
	(segment
		(start 155.829 -15.24)
		(end 165.227 -24.638)
		(width 0.381)
		(layer "In7.Cu")
		(net "XP3R3V_AUX_PCIE")
	)
	(segment
		(start 163.068 -63.754)
		(end 163.068 -77.978)
		(width 0.381)
		(layer "In7.Cu")
		(net "XP3R3V_AUX_PCIE")
	)
	(segment
		(start 114.177064 -72.800464)
		(end 114.9096 -73.533)
		(width 0.254)
		(layer "F.Cu")
		(net "XP3R3V")
	)
	(segment
		(start 60.452 -88.4555)
		(end 60.452 -87.63)
		(width 0.381)
		(layer "F.Cu")
		(net "XP3R3V")
	)
	(segment
		(start 109.982 -70.231)
		(end 109.601 -70.231)
		(width 0.381)
		(layer "F.Cu")
		(net "XP3R3V")
	)
	(segment
		(start 109.601 -70.231)
		(end 108.966 -69.596)
		(width 0.381)
		(layer "F.Cu")
		(net "XP3R3V")
	)
	(segment
		(start 100.965 -68.072)
		(end 101.6 -67.437)
		(width 0.381)
		(layer "F.Cu")
		(net "XP3R3V")
	)
	(segment
		(start 92.0242 -95.2627)
		(end 89.5223 -92.7608)
		(width 0.381)
		(layer "F.Cu")
		(net "XP3R3V")
	)
	(segment
		(start 19.304 -60.4774)
		(end 19.87804 -61.05144)
		(width 0.381)
		(layer "F.Cu")
		(net "XP3R3V")
	)
	(segment
		(start 19.87804 -61.05144)
		(end 19.87804 -61.6585)
		(width 0.381)
		(layer "F.Cu")
		(net "XP3R3V")
	)
	(segment
		(start 18.161 -61.0108)
		(end 18.6944 -60.4774)
		(width 0.381)
		(layer "F.Cu")
		(net "XP3R3V")
	)
	(segment
		(start 110.6424 -73.0504)
		(end 110.892336 -72.800464)
		(width 0.254)
		(layer "F.Cu")
		(net "XP3R3V")
	)
	(segment
		(start 133.858 -71.3994)
		(end 132.9944 -71.3994)
		(width 0.381)
		(layer "F.Cu")
		(net "XP3R3V")
	)
	(segment
		(start 92.0242 -97.4344)
		(end 92.0242 -95.2627)
		(width 0.381)
		(layer "F.Cu")
		(net "XP3R3V")
	)
	(segment
		(start 18.6944 -60.4774)
		(end 19.304 -60.4774)
		(width 0.381)
		(layer "F.Cu")
		(net "XP3R3V")
	)
	(segment
		(start 64.7573 -92.7608)
		(end 60.452 -88.4555)
		(width 0.381)
		(layer "F.Cu")
		(net "XP3R3V")
	)
	(segment
		(start 78.105 -93.599)
		(end 77.2668 -92.7608)
		(width 0.381)
		(layer "F.Cu")
		(net "XP3R3V")
	)
	(segment
		(start 18.161 -60.9346)
		(end 17.272 -60.0456)
		(width 0.381)
		(layer "F.Cu")
		(net "XP3R3V")
	)
	(segment
		(start 77.2668 -92.7608)
		(end 64.7573 -92.7608)
		(width 0.381)
		(layer "F.Cu")
		(net "XP3R3V")
	)
	(segment
		(start 111.638334 -71.736966)
		(end 112.26165 -71.736966)
		(width 0.381)
		(layer "F.Cu")
		(net "XP3R3V")
	)
	(segment
		(start 100.7872 -68.072)
		(end 100.965 -68.072)
		(width 0.381)
		(layer "F.Cu")
		(net "XP3R3V")
	)
	(segment
		(start 65.913 -15.367)
		(end 65.913 -13.8938)
		(width 0.381)
		(layer "F.Cu")
		(net "XP3R3V")
	)
	(segment
		(start 110.892336 -72.800464)
		(end 112.26165 -72.800464)
		(width 0.254)
		(layer "F.Cu")
		(net "XP3R3V")
	)
	(segment
		(start 18.161 -61.0108)
		(end 18.161 -60.9346)
		(width 0.381)
		(layer "F.Cu")
		(net "XP3R3V")
	)
	(segment
		(start 80.01 -93.599)
		(end 78.105 -93.599)
		(width 0.381)
		(layer "F.Cu")
		(net "XP3R3V")
	)
	(segment
		(start 112.26165 -72.800464)
		(end 114.177064 -72.800464)
		(width 0.254)
		(layer "F.Cu")
		(net "XP3R3V")
	)
	(segment
		(start 111.2901 -72.0852)
		(end 111.638334 -71.736966)
		(width 0.381)
		(layer "F.Cu")
		(net "XP3R3V")
	)
	(segment
		(start 17.272 -60.0456)
		(end 17.272 -59.817)
		(width 0.381)
		(layer "F.Cu")
		(net "XP3R3V")
	)
	(segment
		(start 89.5223 -92.7608)
		(end 88.392 -92.7608)
		(width 0.381)
		(layer "F.Cu")
		(net "XP3R3V")
	)
	(via
		(at 125.0442 -61.1632)
		(size 0.508)
		(drill 0.254)
		(layers "F.Cu" "B.Cu")
		(net "XP3R3V")
	)
	(via
		(at 87.503 -91.7702)
		(size 0.508)
		(drill 0.254)
		(layers "F.Cu" "B.Cu")
		(net "XP3R3V")
	)
	(via
		(at 82.55 -92.202)
		(size 0.508)
		(drill 0.254)
		(layers "F.Cu" "B.Cu")
		(net "XP3R3V")
	)
	(via
		(at 65.913 -13.8938)
		(size 0.508)
		(drill 0.254)
		(layers "F.Cu" "B.Cu")
		(net "XP3R3V")
	)
	(via
		(at 142.883382 -25.908254)
		(size 0.508)
		(drill 0.254)
		(layers "F.Cu" "B.Cu")
		(net "XP3R3V")
	)
	(via
		(at 24.384 -61.214)
		(size 0.508)
		(drill 0.254)
		(layers "F.Cu" "B.Cu")
		(net "XP3R3V")
	)
	(via
		(at 92.837 -77.6986)
		(size 0.508)
		(drill 0.254)
		(layers "F.Cu" "B.Cu")
		(net "XP3R3V")
	)
	(via
		(at 143.746982 -25.908)
		(size 0.508)
		(drill 0.254)
		(layers "F.Cu" "B.Cu")
		(net "XP3R3V")
	)
	(via
		(at 86.487 -91.7702)
		(size 0.508)
		(drill 0.254)
		(layers "F.Cu" "B.Cu")
		(net "XP3R3V")
	)
	(via
		(at 96.6216 -20.7264)
		(size 0.4572)
		(drill 0.2032)
		(layers "F.Cu" "B.Cu")
		(net "XP3R3V")
	)
	(via
		(at 126.2634 -62.1538)
		(size 0.508)
		(drill 0.254)
		(layers "F.Cu" "B.Cu")
		(net "XP3R3V")
	)
	(via
		(at 134.29234 -57.785)
		(size 0.508)
		(drill 0.254)
		(layers "F.Cu" "B.Cu")
		(net "XP3R3V")
	)
	(via
		(at 101.6 -67.437)
		(size 0.508)
		(drill 0.254)
		(layers "F.Cu" "B.Cu")
		(net "XP3R3V")
	)
	(via
		(at 111.76 -70.739)
		(size 0.508)
		(drill 0.254)
		(layers "F.Cu" "B.Cu")
		(net "XP3R3V")
	)
	(via
		(at 110.617 -69.723)
		(size 0.508)
		(drill 0.254)
		(layers "F.Cu" "B.Cu")
		(net "XP3R3V")
	)
	(via
		(at 111.2901 -72.0852)
		(size 0.508)
		(drill 0.254)
		(layers "F.Cu" "B.Cu")
		(net "XP3R3V")
	)
	(via
		(at 127.5588 -61.1378)
		(size 0.508)
		(drill 0.254)
		(layers "F.Cu" "B.Cu")
		(net "XP3R3V")
	)
	(via
		(at 88.498172 -91.7702)
		(size 0.508)
		(drill 0.254)
		(layers "F.Cu" "B.Cu")
		(net "XP3R3V")
	)
	(via
		(at 132.9944 -71.3994)
		(size 0.508)
		(drill 0.254)
		(layers "F.Cu" "B.Cu")
		(net "XP3R3V")
	)
	(via
		(at 17.272 -59.817)
		(size 0.508)
		(drill 0.254)
		(layers "F.Cu" "B.Cu")
		(net "XP3R3V")
	)
	(via
		(at 91.7956 -77.6732)
		(size 0.508)
		(drill 0.254)
		(layers "F.Cu" "B.Cu")
		(net "XP3R3V")
	)
	(via
		(at 84.455 -91.7702)
		(size 0.508)
		(drill 0.254)
		(layers "F.Cu" "B.Cu")
		(net "XP3R3V")
	)
	(via
		(at 91.7956 -76.581)
		(size 0.508)
		(drill 0.254)
		(layers "F.Cu" "B.Cu")
		(net "XP3R3V")
	)
	(via
		(at 107.442 -18.5293)
		(size 0.508)
		(drill 0.254)
		(layers "F.Cu" "B.Cu")
		(net "XP3R3V")
	)
	(via
		(at 85.471 -91.7702)
		(size 0.508)
		(drill 0.254)
		(layers "F.Cu" "B.Cu")
		(net "XP3R3V")
	)
	(via
		(at 92.583 -105.029)
		(size 0.508)
		(drill 0.254)
		(layers "F.Cu" "B.Cu")
		(net "XP3R3V")
	)
	(via
		(at 60.452 -87.63)
		(size 0.508)
		(drill 0.254)
		(layers "F.Cu" "B.Cu")
		(net "XP3R3V")
	)
	(via
		(at 58.674 -18.161)
		(size 0.508)
		(drill 0.254)
		(layers "F.Cu" "B.Cu")
		(net "XP3R3V")
	)
	(via
		(at 113.1824 -70.6882)
		(size 0.508)
		(drill 0.254)
		(layers "F.Cu" "B.Cu")
		(net "XP3R3V")
	)
	(via
		(at 110.3884 -70.6882)
		(size 0.508)
		(drill 0.254)
		(layers "F.Cu" "B.Cu")
		(net "XP3R3V")
	)
	(via
		(at 35.814 -96.393)
		(size 0.508)
		(drill 0.254)
		(layers "F.Cu" "B.Cu")
		(net "XP3R3V")
	)
	(via
		(at 58.674 -17.272)
		(size 0.508)
		(drill 0.254)
		(layers "F.Cu" "B.Cu")
		(net "XP3R3V")
	)
	(via
		(at 126.2888 -61.1124)
		(size 0.508)
		(drill 0.254)
		(layers "F.Cu" "B.Cu")
		(net "XP3R3V")
	)
	(via
		(at 109.9947 -74.0156)
		(size 0.508)
		(drill 0.254)
		(layers "F.Cu" "B.Cu")
		(net "XP3R3V")
	)
	(via
		(at 91.7956 -78.7146)
		(size 0.508)
		(drill 0.254)
		(layers "F.Cu" "B.Cu")
		(net "XP3R3V")
	)
	(segment
		(start 95.885 -20.7264)
		(end 95.758 -20.5994)
		(width 0.381)
		(layer "B.Cu")
		(net "XP3R3V")
	)
	(segment
		(start 109.855 -68.453)
		(end 102.616 -68.453)
		(width 0.381)
		(layer "B.Cu")
		(net "XP3R3V")
	)
	(segment
		(start 90.9574 -104.902)
		(end 91.0844 -105.029)
		(width 0.381)
		(layer "B.Cu")
		(net "XP3R3V")
	)
	(segment
		(start 108.458 -19.7612)
		(end 108.4326 -19.7358)
		(width 0.381)
		(layer "B.Cu")
		(net "XP3R3V")
	)
	(segment
		(start 115.9764 -70.2564)
		(end 115.9764 -70.993)
		(width 0.381)
		(layer "B.Cu")
		(net "XP3R3V")
	)
	(segment
		(start 113.1824 -70.6882)
		(end 114.0206 -69.85)
		(width 0.381)
		(layer "B.Cu")
		(net "XP3R3V")
	)
	(segment
		(start 134.29234 -57.785)
		(end 136.8806 -57.785)
		(width 0.381)
		(layer "B.Cu")
		(net "XP3R3V")
	)
	(segment
		(start 96.6216 -20.7264)
		(end 95.885 -20.7264)
		(width 0.381)
		(layer "B.Cu")
		(net "XP3R3V")
	)
	(segment
		(start 108.4326 -19.7358)
		(end 108.4326 -18.542)
		(width 0.381)
		(layer "B.Cu")
		(net "XP3R3V")
	)
	(segment
		(start 35.814 -96.393)
		(end 35.814 -97.4344)
		(width 0.381)
		(layer "B.Cu")
		(net "XP3R3V")
	)
	(segment
		(start 114.0206 -69.85)
		(end 115.57 -69.85)
		(width 0.381)
		(layer "B.Cu")
		(net "XP3R3V")
	)
	(segment
		(start 107.4547 -18.542)
		(end 107.442 -18.5293)
		(width 0.381)
		(layer "B.Cu")
		(net "XP3R3V")
	)
	(segment
		(start 115.57 -69.85)
		(end 115.9764 -70.2564)
		(width 0.381)
		(layer "B.Cu")
		(net "XP3R3V")
	)
	(segment
		(start 95.758 -20.5994)
		(end 95.758 -21.9202)
		(width 0.381)
		(layer "B.Cu")
		(net "XP3R3V")
	)
	(segment
		(start 102.616 -68.453)
		(end 101.6 -67.437)
		(width 0.381)
		(layer "B.Cu")
		(net "XP3R3V")
	)
	(segment
		(start 91.0844 -105.029)
		(end 92.583 -105.029)
		(width 0.381)
		(layer "B.Cu")
		(net "XP3R3V")
	)
	(segment
		(start 110.617 -69.723)
		(end 110.617 -69.215)
		(width 0.381)
		(layer "B.Cu")
		(net "XP3R3V")
	)
	(segment
		(start 35.814 -97.4344)
		(end 36.195 -97.8154)
		(width 0.381)
		(layer "B.Cu")
		(net "XP3R3V")
	)
	(segment
		(start 108.4326 -18.542)
		(end 107.4547 -18.542)
		(width 0.381)
		(layer "B.Cu")
		(net "XP3R3V")
	)
	(segment
		(start 110.617 -69.215)
		(end 109.855 -68.453)
		(width 0.381)
		(layer "B.Cu")
		(net "XP3R3V")
	)
	(segment
		(start 23.43912 -60.26912)
		(end 24.384 -61.214)
		(width 0.381)
		(layer "In2.Cu")
		(net "XP3R3V")
	)
	(segment
		(start 42.164 -94.742)
		(end 42.545 -94.361)
		(width 0.381)
		(layer "In2.Cu")
		(net "XP3R3V")
	)
	(segment
		(start 42.545 -94.361)
		(end 45.72 -94.361)
		(width 0.381)
		(layer "In2.Cu")
		(net "XP3R3V")
	)
	(segment
		(start 17.272 -59.817)
		(end 17.526 -60.071)
		(width 0.381)
		(layer "In2.Cu")
		(net "XP3R3V")
	)
	(segment
		(start 46.609 -95.25)
		(end 70.993 -95.25)
		(width 0.381)
		(layer "In2.Cu")
		(net "XP3R3V")
	)
	(segment
		(start 35.814 -95.123)
		(end 36.195 -94.742)
		(width 0.381)
		(layer "In2.Cu")
		(net "XP3R3V")
	)
	(segment
		(start 88.498172 -91.7702)
		(end 92.583 -95.855028)
		(width 0.381)
		(layer "In2.Cu")
		(net "XP3R3V")
	)
	(segment
		(start 74.041 -92.202)
		(end 82.55 -92.202)
		(width 0.381)
		(layer "In2.Cu")
		(net "XP3R3V")
	)
	(segment
		(start 70.993 -95.25)
		(end 74.041 -92.202)
		(width 0.381)
		(layer "In2.Cu")
		(net "XP3R3V")
	)
	(segment
		(start 23.43912 -58.1279)
		(end 23.43912 -60.26912)
		(width 0.381)
		(layer "In2.Cu")
		(net "XP3R3V")
	)
	(segment
		(start 45.72 -94.361)
		(end 46.609 -95.25)
		(width 0.381)
		(layer "In2.Cu")
		(net "XP3R3V")
	)
	(segment
		(start 21.06168 -57.2643)
		(end 22.57552 -57.2643)
		(width 0.381)
		(layer "In2.Cu")
		(net "XP3R3V")
	)
	(segment
		(start 22.57552 -57.2643)
		(end 23.43912 -58.1279)
		(width 0.381)
		(layer "In2.Cu")
		(net "XP3R3V")
	)
	(segment
		(start 18.25498 -60.071)
		(end 21.06168 -57.2643)
		(width 0.381)
		(layer "In2.Cu")
		(net "XP3R3V")
	)
	(segment
		(start 17.526 -60.071)
		(end 18.25498 -60.071)
		(width 0.381)
		(layer "In2.Cu")
		(net "XP3R3V")
	)
	(segment
		(start 36.195 -94.742)
		(end 42.164 -94.742)
		(width 0.381)
		(layer "In2.Cu")
		(net "XP3R3V")
	)
	(segment
		(start 92.583 -95.855028)
		(end 92.583 -105.029)
		(width 0.381)
		(layer "In2.Cu")
		(net "XP3R3V")
	)
	(segment
		(start 35.814 -96.393)
		(end 35.814 -95.123)
		(width 0.381)
		(layer "In2.Cu")
		(net "XP3R3V")
	)
	(segment
		(start 58.5216 -85.6996)
		(end 57.1246 -85.6996)
		(width 0.381)
		(layer "In7.Cu")
		(net "XP3R3V")
	)
	(segment
		(start 57.1246 -85.6996)
		(end 55.626 -84.201)
		(width 0.381)
		(layer "In7.Cu")
		(net "XP3R3V")
	)
	(segment
		(start 55.626 -81.153)
		(end 45.8724 -71.3994)
		(width 0.381)
		(layer "In7.Cu")
		(net "XP3R3V")
	)
	(segment
		(start 45.8724 -71.3994)
		(end 31.623 -71.3994)
		(width 0.381)
		(layer "In7.Cu")
		(net "XP3R3V")
	)
	(segment
		(start 26.5938 -63.4238)
		(end 24.384 -61.214)
		(width 0.381)
		(layer "In7.Cu")
		(net "XP3R3V")
	)
	(segment
		(start 31.623 -71.3994)
		(end 26.5938 -66.3702)
		(width 0.381)
		(layer "In7.Cu")
		(net "XP3R3V")
	)
	(segment
		(start 26.5938 -66.3702)
		(end 26.5938 -63.4238)
		(width 0.381)
		(layer "In7.Cu")
		(net "XP3R3V")
	)
	(segment
		(start 60.452 -87.63)
		(end 58.5216 -85.6996)
		(width 0.381)
		(layer "In7.Cu")
		(net "XP3R3V")
	)
	(segment
		(start 55.626 -84.201)
		(end 55.626 -81.153)
		(width 0.381)
		(layer "In7.Cu")
		(net "XP3R3V")
	)
	(segment
		(start 46.649894 -3.500374)
		(end 46.649894 -7.3406)
		(width 0.381)
		(layer "F.Cu")
		(net "XP12R0V_PCIE")
	)
	(segment
		(start 46.649894 -7.3406)
		(end 45.9486 -7.3406)
		(width 0.381)
		(layer "F.Cu")
		(net "XP12R0V_PCIE")
	)
	(segment
		(start 45.9486 -7.3406)
		(end 45.649896 -7.041896)
		(width 0.381)
		(layer "F.Cu")
		(net "XP12R0V_PCIE")
	)
	(segment
		(start 46.649894 -7.3406)
		(end 47.649892 -7.3406)
		(width 0.381)
		(layer "F.Cu")
		(net "XP12R0V_PCIE")
	)
	(segment
		(start 45.649896 -7.041896)
		(end 45.649896 -3.500374)
		(width 0.381)
		(layer "F.Cu")
		(net "XP12R0V_PCIE")
	)
	(segment
		(start 47.649892 -7.3406)
		(end 47.649892 -3.500374)
		(width 0.381)
		(layer "F.Cu")
		(net "XP12R0V_PCIE")
	)
	(via
		(at 17.907 -97.028)
		(size 0.508)
		(drill 0.254)
		(layers "F.Cu" "B.Cu")
		(net "XP12R0V_PCIE")
	)
	(via
		(at 15.875 -94.742)
		(size 0.508)
		(drill 0.254)
		(layers "F.Cu" "B.Cu")
		(net "XP12R0V_PCIE")
	)
	(via
		(at 18.542 -92.71)
		(size 0.508)
		(drill 0.254)
		(layers "F.Cu" "B.Cu")
		(net "XP12R0V_PCIE")
	)
	(via
		(at 47.649892 -9.3726)
		(size 0.4572)
		(drill 0.2032)
		(layers "F.Cu" "B.Cu")
		(net "XP12R0V_PCIE")
	)
	(via
		(at 15.875 -92.71)
		(size 0.508)
		(drill 0.254)
		(layers "F.Cu" "B.Cu")
		(net "XP12R0V_PCIE")
	)
	(via
		(at 15.875 -93.726)
		(size 0.508)
		(drill 0.254)
		(layers "F.Cu" "B.Cu")
		(net "XP12R0V_PCIE")
	)
	(via
		(at 15.875 -97.028)
		(size 0.508)
		(drill 0.254)
		(layers "F.Cu" "B.Cu")
		(net "XP12R0V_PCIE")
	)
	(via
		(at 16.891 -97.028)
		(size 0.508)
		(drill 0.254)
		(layers "F.Cu" "B.Cu")
		(net "XP12R0V_PCIE")
	)
	(via
		(at 16.764 -92.71)
		(size 0.508)
		(drill 0.254)
		(layers "F.Cu" "B.Cu")
		(net "XP12R0V_PCIE")
	)
	(via
		(at 47.244 -8.382)
		(size 0.4572)
		(drill 0.2032)
		(layers "F.Cu" "B.Cu")
		(net "XP12R0V_PCIE")
	)
	(via
		(at 15.875 -96.012)
		(size 0.508)
		(drill 0.254)
		(layers "F.Cu" "B.Cu")
		(net "XP12R0V_PCIE")
	)
	(via
		(at 47.649892 -7.3406)
		(size 0.4572)
		(drill 0.2032)
		(layers "F.Cu" "B.Cu")
		(net "XP12R0V_PCIE")
	)
	(via
		(at 17.653 -92.71)
		(size 0.508)
		(drill 0.254)
		(layers "F.Cu" "B.Cu")
		(net "XP12R0V_PCIE")
	)
	(via
		(at 48.133 -8.382)
		(size 0.4572)
		(drill 0.2032)
		(layers "F.Cu" "B.Cu")
		(net "XP12R0V_PCIE")
	)
	(segment
		(start 46.649894 -3.500374)
		(end 46.649894 -7.3406)
		(width 0.381)
		(layer "B.Cu")
		(net "XP12R0V_PCIE")
	)
	(segment
		(start 47.649892 -3.500374)
		(end 47.649892 -7.3406)
		(width 0.381)
		(layer "B.Cu")
		(net "XP12R0V_PCIE")
	)
	(segment
		(start 89.2556 -60.198)
		(end 89.651078 -60.593478)
		(width 0.11938)
		(layer "F.Cu")
		(net "UNNAMED_9_CAPACITOR_I17_1")
	)
	(segment
		(start 89.154 -60.198)
		(end 89.2556 -60.198)
		(width 0.11938)
		(layer "F.Cu")
		(net "UNNAMED_9_CAPACITOR_I17_1")
	)
	(segment
		(start 88.981534 -60.025534)
		(end 89.154 -60.198)
		(width 0.11938)
		(layer "F.Cu")
		(net "UNNAMED_9_CAPACITOR_I17_1")
	)
	(segment
		(start 87.668608 -60.025534)
		(end 88.981534 -60.025534)
		(width 0.11938)
		(layer "F.Cu")
		(net "UNNAMED_9_CAPACITOR_I17_1")
	)
	(segment
		(start 92.220542 -60.593478)
		(end 90.678 -60.593478)
		(width 0.11938)
		(layer "F.Cu")
		(net "UNNAMED_9_CAPACITOR_I17_1")
	)
	(segment
		(start 89.651078 -60.593478)
		(end 90.678 -60.593478)
		(width 0.11938)
		(layer "F.Cu")
		(net "UNNAMED_9_CAPACITOR_I17_1")
	)
	(segment
		(start 92.372942 -60.745878)
		(end 92.220542 -60.593478)
		(width 0.11938)
		(layer "F.Cu")
		(net "UNNAMED_9_CAPACITOR_I17_1")
	)
	(via
		(at 89.154 -60.198)
		(size 0.508)
		(drill 0.254)
		(layers "F.Cu" "B.Cu")
		(net "UNNAMED_9_CAPACITOR_I17_1")
	)
	(segment
		(start 88.138 -60.3504)
		(end 89.0016 -60.3504)
		(width 0.11938)
		(layer "B.Cu")
		(net "UNNAMED_9_CAPACITOR_I17_1")
	)
	(segment
		(start 89.0016 -60.3504)
		(end 89.154 -60.198)
		(width 0.11938)
		(layer "B.Cu")
		(net "UNNAMED_9_CAPACITOR_I17_1")
	)
	(via
		(at 15.6972 -76.835)
		(size 0.762)
		(drill 0.381)
		(layers "F.Cu" "B.Cu")
		(net "R_LM75B_1_I2C_SDA")
	)
	(segment
		(start 15.9766 -76.5556)
		(end 15.6972 -76.835)
		(width 0.11938)
		(layer "B.Cu")
		(net "R_LM75B_1_I2C_SDA")
	)
	(segment
		(start 16.764 -76.5556)
		(end 15.9766 -76.5556)
		(width 0.11938)
		(layer "B.Cu")
		(net "R_LM75B_1_I2C_SDA")
	)
	(segment
		(start 15.01902 -78.03896)
		(end 15.01902 -77.51318)
		(width 0.11938)
		(layer "B.Cu")
		(net "R_LM75B_1_I2C_SDA")
	)
	(segment
		(start 15.01902 -77.51318)
		(end 15.6972 -76.835)
		(width 0.11938)
		(layer "B.Cu")
		(net "R_LM75B_1_I2C_SDA")
	)
	(segment
		(start 14.89964 -78.15834)
		(end 15.01902 -78.03896)
		(width 0.11938)
		(layer "B.Cu")
		(net "R_LM75B_1_I2C_SDA")
	)
	(segment
		(start 13.9827 -78.03896)
		(end 14.10208 -78.15834)
		(width 0.11938)
		(layer "B.Cu")
		(net "R_LM75B_1_I2C_SDA")
	)
	(segment
		(start 13.9827 -76.92136)
		(end 13.9827 -78.03896)
		(width 0.11938)
		(layer "B.Cu")
		(net "R_LM75B_1_I2C_SDA")
	)
	(segment
		(start 14.10208 -78.15834)
		(end 14.89964 -78.15834)
		(width 0.11938)
		(layer "B.Cu")
		(net "R_LM75B_1_I2C_SDA")
	)
	(via
		(at 7.366 -74.041)
		(size 0.508)
		(drill 0.254)
		(layers "F.Cu" "B.Cu")
		(net "UNNAMED_6_LM75BDPTSSOP8_I34_A2")
	)
	(segment
		(start 8.16864 -74.97064)
		(end 9.3853 -74.97064)
		(width 0.11938)
		(layer "B.Cu")
		(net "UNNAMED_6_LM75BDPTSSOP8_I34_A2")
	)
	(segment
		(start 7.366 -72.9234)
		(end 7.366 -74.041)
		(width 0.11938)
		(layer "B.Cu")
		(net "UNNAMED_6_LM75BDPTSSOP8_I34_A2")
	)
	(segment
		(start 7.366 -74.041)
		(end 7.366 -74.168)
		(width 0.11938)
		(layer "B.Cu")
		(net "UNNAMED_6_LM75BDPTSSOP8_I34_A2")
	)
	(segment
		(start 7.366 -74.168)
		(end 8.16864 -74.97064)
		(width 0.11938)
		(layer "B.Cu")
		(net "UNNAMED_6_LM75BDPTSSOP8_I34_A2")
	)
	(segment
		(start 7.366 -72.9234)
		(end 8.509 -72.9234)
		(width 0.11938)
		(layer "B.Cu")
		(net "UNNAMED_6_LM75BDPTSSOP8_I34_A2")
	)
	(via
		(at 7.112 -75.311)
		(size 0.508)
		(drill 0.254)
		(layers "F.Cu" "B.Cu")
		(net "UNNAMED_6_LM75BDPTSSOP8_I34_A1")
	)
	(segment
		(start 6.1214 -74.295)
		(end 6.223 -74.295)
		(width 0.11938)
		(layer "B.Cu")
		(net "UNNAMED_6_LM75BDPTSSOP8_I34_A1")
	)
	(segment
		(start 7.112 -75.184)
		(end 7.112 -75.311)
		(width 0.11938)
		(layer "B.Cu")
		(net "UNNAMED_6_LM75BDPTSSOP8_I34_A1")
	)
	(segment
		(start 7.239 -75.311)
		(end 7.54888 -75.62088)
		(width 0.11938)
		(layer "B.Cu")
		(net "UNNAMED_6_LM75BDPTSSOP8_I34_A1")
	)
	(segment
		(start 7.54888 -75.62088)
		(end 9.3853 -75.62088)
		(width 0.11938)
		(layer "B.Cu")
		(net "UNNAMED_6_LM75BDPTSSOP8_I34_A1")
	)
	(segment
		(start 7.112 -75.311)
		(end 7.239 -75.311)
		(width 0.11938)
		(layer "B.Cu")
		(net "UNNAMED_6_LM75BDPTSSOP8_I34_A1")
	)
	(segment
		(start 6.1214 -74.295)
		(end 6.1214 -73.025)
		(width 0.11938)
		(layer "B.Cu")
		(net "UNNAMED_6_LM75BDPTSSOP8_I34_A1")
	)
	(segment
		(start 6.223 -74.295)
		(end 7.112 -75.184)
		(width 0.11938)
		(layer "B.Cu")
		(net "UNNAMED_6_LM75BDPTSSOP8_I34_A1")
	)
	(via
		(at 7.239 -76.708)
		(size 0.508)
		(drill 0.254)
		(layers "F.Cu" "B.Cu")
		(net "UNNAMED_6_LM75BDPTSSOP8_I34_A0")
	)
	(segment
		(start 7.239 -76.708)
		(end 7.366 -76.708)
		(width 0.11938)
		(layer "B.Cu")
		(net "UNNAMED_6_LM75BDPTSSOP8_I34_A0")
	)
	(segment
		(start 7.80288 -76.27112)
		(end 9.3853 -76.27112)
		(width 0.11938)
		(layer "B.Cu")
		(net "UNNAMED_6_LM75BDPTSSOP8_I34_A0")
	)
	(segment
		(start 6.858 -76.835)
		(end 6.985 -76.708)
		(width 0.11938)
		(layer "B.Cu")
		(net "UNNAMED_6_LM75BDPTSSOP8_I34_A0")
	)
	(segment
		(start 7.366 -76.708)
		(end 7.80288 -76.27112)
		(width 0.11938)
		(layer "B.Cu")
		(net "UNNAMED_6_LM75BDPTSSOP8_I34_A0")
	)
	(segment
		(start 6.1214 -76.835)
		(end 6.1214 -75.565)
		(width 0.11938)
		(layer "B.Cu")
		(net "UNNAMED_6_LM75BDPTSSOP8_I34_A0")
	)
	(segment
		(start 6.985 -76.708)
		(end 7.239 -76.708)
		(width 0.11938)
		(layer "B.Cu")
		(net "UNNAMED_6_LM75BDPTSSOP8_I34_A0")
	)
	(segment
		(start 6.1214 -76.835)
		(end 6.858 -76.835)
		(width 0.11938)
		(layer "B.Cu")
		(net "UNNAMED_6_LM75BDPTSSOP8_I34_A0")
	)
	(segment
		(start 75.6158 -85.1154)
		(end 75.6158 -84.3026)
		(width 0.11938)
		(layer "F.Cu")
		(net "UNNAMED_5_PCA9546APWTSSOP16_I_2")
	)
	(segment
		(start 75.6158 -84.3026)
		(end 76.04252 -83.87588)
		(width 0.11938)
		(layer "F.Cu")
		(net "UNNAMED_5_PCA9546APWTSSOP16_I_2")
	)
	(segment
		(start 76.04252 -83.87588)
		(end 77.2795 -83.87588)
		(width 0.11938)
		(layer "F.Cu")
		(net "UNNAMED_5_PCA9546APWTSSOP16_I_2")
	)
	(via
		(at 75.6158 -85.1154)
		(size 0.4572)
		(drill 0.2032)
		(layers "F.Cu" "B.Cu")
		(net "UNNAMED_5_PCA9546APWTSSOP16_I_2")
	)
	(segment
		(start 76.8604 -85.09)
		(end 76.8604 -83.947)
		(width 0.11938)
		(layer "B.Cu")
		(net "UNNAMED_5_PCA9546APWTSSOP16_I_2")
	)
	(segment
		(start 76.8604 -85.09)
		(end 75.6412 -85.09)
		(width 0.11938)
		(layer "B.Cu")
		(net "UNNAMED_5_PCA9546APWTSSOP16_I_2")
	)
	(segment
		(start 75.6412 -85.09)
		(end 75.6158 -85.1154)
		(width 0.11938)
		(layer "B.Cu")
		(net "UNNAMED_5_PCA9546APWTSSOP16_I_2")
	)
	(segment
		(start 85.47735 -82.677)
		(end 85.376258 -82.575908)
		(width 0.11938)
		(layer "F.Cu")
		(net "UNNAMED_5_PCA9546APWTSSOP16_I_1")
	)
	(segment
		(start 85.376258 -82.575908)
		(end 83.3501 -82.575908)
		(width 0.11938)
		(layer "F.Cu")
		(net "UNNAMED_5_PCA9546APWTSSOP16_I_1")
	)
	(via
		(at 85.47735 -82.677)
		(size 0.4572)
		(drill 0.2032)
		(layers "F.Cu" "B.Cu")
		(net "UNNAMED_5_PCA9546APWTSSOP16_I_1")
	)
	(segment
		(start 85.47735 -82.677)
		(end 84.7852 -82.677)
		(width 0.11938)
		(layer "B.Cu")
		(net "UNNAMED_5_PCA9546APWTSSOP16_I_1")
	)
	(segment
		(start 84.7852 -82.677)
		(end 83.7692 -83.693)
		(width 0.11938)
		(layer "B.Cu")
		(net "UNNAMED_5_PCA9546APWTSSOP16_I_1")
	)
	(segment
		(start 83.7692 -84.836)
		(end 83.7692 -83.693)
		(width 0.11938)
		(layer "B.Cu")
		(net "UNNAMED_5_PCA9546APWTSSOP16_I_1")
	)
	(segment
		(start 84.958428 -81.925922)
		(end 83.3501 -81.925922)
		(width 0.11938)
		(layer "F.Cu")
		(net "UNNAMED_5_PCA9546APWTSSOP16_I33")
	)
	(segment
		(start 85.47735 -81.407)
		(end 84.958428 -81.925922)
		(width 0.11938)
		(layer "F.Cu")
		(net "UNNAMED_5_PCA9546APWTSSOP16_I33")
	)
	(via
		(at 85.47735 -81.407)
		(size 0.4572)
		(drill 0.2032)
		(layers "F.Cu" "B.Cu")
		(net "UNNAMED_5_PCA9546APWTSSOP16_I33")
	)
	(segment
		(start 83.7692 -81.407)
		(end 85.47735 -81.407)
		(width 0.11938)
		(layer "B.Cu")
		(net "UNNAMED_5_PCA9546APWTSSOP16_I33")
	)
	(segment
		(start 83.7692 -81.407)
		(end 83.7692 -82.55)
		(width 0.11938)
		(layer "B.Cu")
		(net "UNNAMED_5_PCA9546APWTSSOP16_I33")
	)
	(segment
		(start 77.47 -6.985)
		(end 77.649832 -6.805168)
		(width 0.11938)
		(layer "F.Cu")
		(net "UNNAMED_3_CONN64PGF_I61_PRSNT22")
	)
	(segment
		(start 77.649832 -6.805168)
		(end 77.649832 -3.995674)
		(width 0.11938)
		(layer "F.Cu")
		(net "UNNAMED_3_CONN64PGF_I61_PRSNT22")
	)
	(segment
		(start 78.0542 -14.1732)
		(end 77.47 -13.589)
		(width 0.11938)
		(layer "F.Cu")
		(net "UNNAMED_3_CONN64PGF_I61_PRSNT22")
	)
	(segment
		(start 77.47 -13.589)
		(end 77.47 -6.985)
		(width 0.11938)
		(layer "F.Cu")
		(net "UNNAMED_3_CONN64PGF_I61_PRSNT22")
	)
	(segment
		(start 78.0542 -15.5702)
		(end 78.0542 -14.1732)
		(width 0.11938)
		(layer "F.Cu")
		(net "UNNAMED_3_CONN64PGF_I61_PRSNT22")
	)
	(via
		(at 78.0542 -15.5702)
		(size 0.4572)
		(drill 0.2032)
		(layers "F.Cu" "B.Cu")
		(net "UNNAMED_3_CONN64PGF_I61_PRSNT22")
	)
	(via
		(at 45.87748 -19.78406)
		(size 0.4572)
		(drill 0.2032)
		(layers "F.Cu" "B.Cu")
		(net "UNNAMED_3_CONN64PGF_I61_PRSNT22")
	)
	(segment
		(start 47.36084 -18.3007)
		(end 45.87748 -19.78406)
		(width 0.11938)
		(layer "B.Cu")
		(net "UNNAMED_3_CONN64PGF_I61_PRSNT22")
	)
	(segment
		(start 47.36084 -16.36268)
		(end 47.36084 -18.3007)
		(width 0.11938)
		(layer "B.Cu")
		(net "UNNAMED_3_CONN64PGF_I61_PRSNT22")
	)
	(segment
		(start 62.852554 -14.224)
		(end 54.594506 -14.224)
		(width 0.127)
		(layer "In2.Cu")
		(net "UNNAMED_3_CONN64PGF_I61_PRSNT22")
	)
	(segment
		(start 53.391054 -14.541246)
		(end 52.0573 -15.875)
		(width 0.127)
		(layer "In2.Cu")
		(net "UNNAMED_3_CONN64PGF_I61_PRSNT22")
	)
	(segment
		(start 54.594506 -14.224)
		(end 54.27726 -14.541246)
		(width 0.127)
		(layer "In2.Cu")
		(net "UNNAMED_3_CONN64PGF_I61_PRSNT22")
	)
	(segment
		(start 54.27726 -14.541246)
		(end 53.391054 -14.541246)
		(width 0.127)
		(layer "In2.Cu")
		(net "UNNAMED_3_CONN64PGF_I61_PRSNT22")
	)
	(segment
		(start 45.87748 -18.978626)
		(end 45.87748 -19.78406)
		(width 0.127)
		(layer "In2.Cu")
		(net "UNNAMED_3_CONN64PGF_I61_PRSNT22")
	)
	(segment
		(start 64.198754 -15.5702)
		(end 62.852554 -14.224)
		(width 0.127)
		(layer "In2.Cu")
		(net "UNNAMED_3_CONN64PGF_I61_PRSNT22")
	)
	(segment
		(start 78.0542 -15.5702)
		(end 64.198754 -15.5702)
		(width 0.127)
		(layer "In2.Cu")
		(net "UNNAMED_3_CONN64PGF_I61_PRSNT22")
	)
	(segment
		(start 52.0573 -15.875)
		(end 48.981106 -15.875)
		(width 0.127)
		(layer "In2.Cu")
		(net "UNNAMED_3_CONN64PGF_I61_PRSNT22")
	)
	(segment
		(start 48.981106 -15.875)
		(end 45.87748 -18.978626)
		(width 0.127)
		(layer "In2.Cu")
		(net "UNNAMED_3_CONN64PGF_I61_PRSNT22")
	)
	(segment
		(start 63.64986 -7.610602)
		(end 64.649858 -8.6106)
		(width 0.11938)
		(layer "F.Cu")
		(net "UNNAMED_3_CONN64PGF_I61_PRSNT21")
	)
	(segment
		(start 63.64986 -3.500374)
		(end 63.64986 -7.610602)
		(width 0.11938)
		(layer "F.Cu")
		(net "UNNAMED_3_CONN64PGF_I61_PRSNT21")
	)
	(segment
		(start 64.1858 -11.176)
		(end 64.1858 -14.432788)
		(width 0.11938)
		(layer "F.Cu")
		(net "UNNAMED_3_CONN64PGF_I61_PRSNT21")
	)
	(segment
		(start 64.1858 -14.432788)
		(end 63.784988 -14.8336)
		(width 0.11938)
		(layer "F.Cu")
		(net "UNNAMED_3_CONN64PGF_I61_PRSNT21")
	)
	(via
		(at 64.1858 -11.176)
		(size 0.4572)
		(drill 0.2032)
		(layers "F.Cu" "B.Cu")
		(net "UNNAMED_3_CONN64PGF_I61_PRSNT21")
	)
	(via
		(at 64.649858 -8.6106)
		(size 0.4572)
		(drill 0.2032)
		(layers "F.Cu" "B.Cu")
		(net "UNNAMED_3_CONN64PGF_I61_PRSNT21")
	)
	(segment
		(start 64.1858 -9.074658)
		(end 64.649858 -8.6106)
		(width 0.127)
		(layer "In7.Cu")
		(net "UNNAMED_3_CONN64PGF_I61_PRSNT21")
	)
	(segment
		(start 64.1858 -11.176)
		(end 64.1858 -9.074658)
		(width 0.127)
		(layer "In7.Cu")
		(net "UNNAMED_3_CONN64PGF_I61_PRSNT21")
	)
	(segment
		(start 147.049998 -108.599732)
		(end 145.793714 -108.599732)
		(width 0.11938)
		(layer "F.Cu")
		(net "UNNAMED_14_OPTICAL_I137_A")
	)
	(via
		(at 145.793714 -108.599732)
		(size 0.508)
		(drill 0.254)
		(layers "F.Cu" "B.Cu")
		(net "UNNAMED_14_OPTICAL_I137_A")
	)
	(segment
		(start 145.793714 -108.599732)
		(end 146.164046 -108.2294)
		(width 0.11938)
		(layer "B.Cu")
		(net "UNNAMED_14_OPTICAL_I137_A")
	)
	(segment
		(start 146.164046 -108.2294)
		(end 147.066 -108.2294)
		(width 0.11938)
		(layer "B.Cu")
		(net "UNNAMED_14_OPTICAL_I137_A")
	)
	(segment
		(start 138.050016 -108.599732)
		(end 136.793732 -108.599732)
		(width 0.11938)
		(layer "F.Cu")
		(net "UNNAMED_14_OPTICAL_I12_A")
	)
	(via
		(at 136.793732 -108.599732)
		(size 0.508)
		(drill 0.254)
		(layers "F.Cu" "B.Cu")
		(net "UNNAMED_14_OPTICAL_I12_A")
	)
	(segment
		(start 136.793732 -108.599732)
		(end 137.164064 -108.2294)
		(width 0.11938)
		(layer "B.Cu")
		(net "UNNAMED_14_OPTICAL_I12_A")
	)
	(segment
		(start 137.164064 -108.2294)
		(end 138.049 -108.2294)
		(width 0.11938)
		(layer "B.Cu")
		(net "UNNAMED_14_OPTICAL_I12_A")
	)
	(segment
		(start 141.05001 -108.599732)
		(end 139.793726 -108.599732)
		(width 0.11938)
		(layer "F.Cu")
		(net "UNNAMED_14_OPTICAL_I11_A")
	)
	(via
		(at 139.793726 -108.599732)
		(size 0.508)
		(drill 0.254)
		(layers "F.Cu" "B.Cu")
		(net "UNNAMED_14_OPTICAL_I11_A")
	)
	(segment
		(start 140.164058 -108.2294)
		(end 141.097 -108.2294)
		(width 0.11938)
		(layer "B.Cu")
		(net "UNNAMED_14_OPTICAL_I11_A")
	)
	(segment
		(start 139.793726 -108.599732)
		(end 140.164058 -108.2294)
		(width 0.11938)
		(layer "B.Cu")
		(net "UNNAMED_14_OPTICAL_I11_A")
	)
	(segment
		(start 144.050004 -108.599732)
		(end 142.79372 -108.599732)
		(width 0.11938)
		(layer "F.Cu")
		(net "UNNAMED_14_OPTICAL_I136_A")
	)
	(via
		(at 142.79372 -108.599732)
		(size 0.508)
		(drill 0.254)
		(layers "F.Cu" "B.Cu")
		(net "UNNAMED_14_OPTICAL_I136_A")
	)
	(segment
		(start 142.79372 -108.599732)
		(end 143.164052 -108.2294)
		(width 0.11938)
		(layer "B.Cu")
		(net "UNNAMED_14_OPTICAL_I136_A")
	)
	(segment
		(start 143.164052 -108.2294)
		(end 144.018 -108.2294)
		(width 0.11938)
		(layer "B.Cu")
		(net "UNNAMED_14_OPTICAL_I136_A")
	)
	(segment
		(start 94.361 -88.9)
		(end 93.091 -87.63)
		(width 0.11938)
		(layer "F.Cu")
		(net "SHT3X_I2C_SDA")
	)
	(segment
		(start 96.3295 -91.6305)
		(end 94.361 -89.662)
		(width 0.11938)
		(layer "F.Cu")
		(net "SHT3X_I2C_SDA")
	)
	(segment
		(start 85.049106 -85.176106)
		(end 83.3501 -85.176106)
		(width 0.11938)
		(layer "F.Cu")
		(net "SHT3X_I2C_SDA")
	)
	(segment
		(start 97.0915 -91.6305)
		(end 96.3295 -91.6305)
		(width 0.11938)
		(layer "F.Cu")
		(net "SHT3X_I2C_SDA")
	)
	(segment
		(start 98.171 -92.71)
		(end 97.0915 -91.6305)
		(width 0.11938)
		(layer "F.Cu")
		(net "SHT3X_I2C_SDA")
	)
	(segment
		(start 87.503 -87.63)
		(end 85.049106 -85.176106)
		(width 0.11938)
		(layer "F.Cu")
		(net "SHT3X_I2C_SDA")
	)
	(segment
		(start 94.361 -89.662)
		(end 94.361 -88.9)
		(width 0.11938)
		(layer "F.Cu")
		(net "SHT3X_I2C_SDA")
	)
	(segment
		(start 149.225 -48.26)
		(end 150.123398 -48.26)
		(width 0.11938)
		(layer "F.Cu")
		(net "SHT3X_I2C_SDA")
	)
	(segment
		(start 93.091 -87.63)
		(end 87.503 -87.63)
		(width 0.11938)
		(layer "F.Cu")
		(net "SHT3X_I2C_SDA")
	)
	(segment
		(start 150.123398 -48.26)
		(end 150.343108 -48.47971)
		(width 0.11938)
		(layer "F.Cu")
		(net "SHT3X_I2C_SDA")
	)
	(via
		(at 98.171 -92.71)
		(size 0.508)
		(drill 0.254)
		(layers "F.Cu" "B.Cu")
		(net "SHT3X_I2C_SDA")
	)
	(via
		(at 149.225 -48.26)
		(size 0.508)
		(drill 0.254)
		(layers "F.Cu" "B.Cu")
		(net "SHT3X_I2C_SDA")
	)
	(segment
		(start 149.34438 -49.54651)
		(end 150.343108 -49.54651)
		(width 0.11938)
		(layer "B.Cu")
		(net "SHT3X_I2C_SDA")
	)
	(segment
		(start 149.225 -49.42713)
		(end 149.34438 -49.54651)
		(width 0.11938)
		(layer "B.Cu")
		(net "SHT3X_I2C_SDA")
	)
	(segment
		(start 149.225 -48.26)
		(end 149.225 -49.42713)
		(width 0.11938)
		(layer "B.Cu")
		(net "SHT3X_I2C_SDA")
	)
	(segment
		(start 119.38 -91.694)
		(end 119.028464 -91.694)
		(width 0.127)
		(layer "In7.Cu")
		(net "SHT3X_I2C_SDA")
	)
	(segment
		(start 141.986 -72.1995)
		(end 141.986 -74.676254)
		(width 0.127)
		(layer "In7.Cu")
		(net "SHT3X_I2C_SDA")
	)
	(segment
		(start 115.218464 -91.694)
		(end 115.091464 -91.821)
		(width 0.127)
		(layer "In7.Cu")
		(net "SHT3X_I2C_SDA")
	)
	(segment
		(start 115.091464 -91.821)
		(end 115.091464 -92.35948)
		(width 0.127)
		(layer "In7.Cu")
		(net "SHT3X_I2C_SDA")
	)
	(segment
		(start 146.8755 -54.33568)
		(end 147.066 -54.52618)
		(width 0.127)
		(layer "In7.Cu")
		(net "SHT3X_I2C_SDA")
	)
	(segment
		(start 118.774464 -92.48648)
		(end 118.393464 -92.48648)
		(width 0.127)
		(layer "In7.Cu")
		(net "SHT3X_I2C_SDA")
	)
	(segment
		(start 105.41 -93.726)
		(end 105.029 -93.345)
		(width 0.127)
		(layer "In7.Cu")
		(net "SHT3X_I2C_SDA")
	)
	(segment
		(start 129.729992 -88.5825)
		(end 129.729992 -89.218008)
		(width 0.127)
		(layer "In7.Cu")
		(net "SHT3X_I2C_SDA")
	)
	(segment
		(start 119.028464 -91.694)
		(end 118.901464 -91.821)
		(width 0.127)
		(layer "In7.Cu")
		(net "SHT3X_I2C_SDA")
	)
	(segment
		(start 107.061 -93.726)
		(end 105.41 -93.726)
		(width 0.127)
		(layer "In7.Cu")
		(net "SHT3X_I2C_SDA")
	)
	(segment
		(start 147.066 -54.52618)
		(end 147.066 -56.812434)
		(width 0.127)
		(layer "In7.Cu")
		(net "SHT3X_I2C_SDA")
	)
	(segment
		(start 114.456464 -92.35948)
		(end 114.456464 -91.821)
		(width 0.127)
		(layer "In7.Cu")
		(net "SHT3X_I2C_SDA")
	)
	(segment
		(start 128.397 -90.551)
		(end 128.396746 -90.551)
		(width 0.127)
		(layer "In7.Cu")
		(net "SHT3X_I2C_SDA")
	)
	(segment
		(start 99.314 -92.71)
		(end 98.171 -92.71)
		(width 0.127)
		(layer "In7.Cu")
		(net "SHT3X_I2C_SDA")
	)
	(segment
		(start 118.266464 -92.35948)
		(end 118.266464 -91.821)
		(width 0.127)
		(layer "In7.Cu")
		(net "SHT3X_I2C_SDA")
	)
	(segment
		(start 114.583464 -92.48648)
		(end 114.456464 -92.35948)
		(width 0.127)
		(layer "In7.Cu")
		(net "SHT3X_I2C_SDA")
	)
	(segment
		(start 114.964464 -92.48648)
		(end 114.583464 -92.48648)
		(width 0.127)
		(layer "In7.Cu")
		(net "SHT3X_I2C_SDA")
	)
	(segment
		(start 118.139464 -91.694)
		(end 117.758464 -91.694)
		(width 0.127)
		(layer "In7.Cu")
		(net "SHT3X_I2C_SDA")
	)
	(segment
		(start 146.4945 -66.027808)
		(end 146.4945 -67.691)
		(width 0.127)
		(layer "In7.Cu")
		(net "SHT3X_I2C_SDA")
	)
	(segment
		(start 118.901464 -92.35948)
		(end 118.774464 -92.48648)
		(width 0.127)
		(layer "In7.Cu")
		(net "SHT3X_I2C_SDA")
	)
	(segment
		(start 128.396746 -90.551)
		(end 128.333246 -90.6145)
		(width 0.127)
		(layer "In7.Cu")
		(net "SHT3X_I2C_SDA")
	)
	(segment
		(start 146.4945 -67.691)
		(end 141.986 -72.1995)
		(width 0.127)
		(layer "In7.Cu")
		(net "SHT3X_I2C_SDA")
	)
	(segment
		(start 126.618746 -90.551)
		(end 120.523 -90.551)
		(width 0.127)
		(layer "In7.Cu")
		(net "SHT3X_I2C_SDA")
	)
	(segment
		(start 148.0185 -57.764934)
		(end 148.0185 -57.767982)
		(width 0.127)
		(layer "In7.Cu")
		(net "SHT3X_I2C_SDA")
	)
	(segment
		(start 148.276056 -58.025538)
		(end 148.276056 -64.246252)
		(width 0.127)
		(layer "In7.Cu")
		(net "SHT3X_I2C_SDA")
	)
	(segment
		(start 147.574254 -48.006)
		(end 146.8755 -48.704754)
		(width 0.127)
		(layer "In7.Cu")
		(net "SHT3X_I2C_SDA")
	)
	(segment
		(start 115.599464 -91.694)
		(end 115.218464 -91.694)
		(width 0.127)
		(layer "In7.Cu")
		(net "SHT3X_I2C_SDA")
	)
	(segment
		(start 117.758464 -91.694)
		(end 117.631464 -91.821)
		(width 0.127)
		(layer "In7.Cu")
		(net "SHT3X_I2C_SDA")
	)
	(segment
		(start 110.4265 -95.1865)
		(end 108.5215 -95.1865)
		(width 0.127)
		(layer "In7.Cu")
		(net "SHT3X_I2C_SDA")
	)
	(segment
		(start 148.0185 -57.767982)
		(end 148.276056 -58.025538)
		(width 0.127)
		(layer "In7.Cu")
		(net "SHT3X_I2C_SDA")
	)
	(segment
		(start 113.919 -91.694)
		(end 110.4265 -95.1865)
		(width 0.127)
		(layer "In7.Cu")
		(net "SHT3X_I2C_SDA")
	)
	(segment
		(start 115.091464 -92.35948)
		(end 114.964464 -92.48648)
		(width 0.127)
		(layer "In7.Cu")
		(net "SHT3X_I2C_SDA")
	)
	(segment
		(start 146.8755 -48.704754)
		(end 146.8755 -54.33568)
		(width 0.127)
		(layer "In7.Cu")
		(net "SHT3X_I2C_SDA")
	)
	(segment
		(start 126.682246 -90.6145)
		(end 126.618746 -90.551)
		(width 0.127)
		(layer "In7.Cu")
		(net "SHT3X_I2C_SDA")
	)
	(segment
		(start 128.333246 -90.6145)
		(end 126.682246 -90.6145)
		(width 0.127)
		(layer "In7.Cu")
		(net "SHT3X_I2C_SDA")
	)
	(segment
		(start 108.5215 -95.1865)
		(end 107.061 -93.726)
		(width 0.127)
		(layer "In7.Cu")
		(net "SHT3X_I2C_SDA")
	)
	(segment
		(start 116.869464 -91.694)
		(end 116.488464 -91.694)
		(width 0.127)
		(layer "In7.Cu")
		(net "SHT3X_I2C_SDA")
	)
	(segment
		(start 116.361464 -92.35948)
		(end 116.234464 -92.48648)
		(width 0.127)
		(layer "In7.Cu")
		(net "SHT3X_I2C_SDA")
	)
	(segment
		(start 120.523 -90.551)
		(end 119.38 -91.694)
		(width 0.127)
		(layer "In7.Cu")
		(net "SHT3X_I2C_SDA")
	)
	(segment
		(start 116.996464 -92.35948)
		(end 116.996464 -91.821)
		(width 0.127)
		(layer "In7.Cu")
		(net "SHT3X_I2C_SDA")
	)
	(segment
		(start 118.393464 -92.48648)
		(end 118.266464 -92.35948)
		(width 0.127)
		(layer "In7.Cu")
		(net "SHT3X_I2C_SDA")
	)
	(segment
		(start 115.726464 -92.35948)
		(end 115.726464 -91.821)
		(width 0.127)
		(layer "In7.Cu")
		(net "SHT3X_I2C_SDA")
	)
	(segment
		(start 114.329464 -91.694)
		(end 113.919 -91.694)
		(width 0.127)
		(layer "In7.Cu")
		(net "SHT3X_I2C_SDA")
	)
	(segment
		(start 133.17982 -78.359)
		(end 131.5212 -80.01762)
		(width 0.127)
		(layer "In7.Cu")
		(net "SHT3X_I2C_SDA")
	)
	(segment
		(start 148.276056 -64.246252)
		(end 146.4945 -66.027808)
		(width 0.127)
		(layer "In7.Cu")
		(net "SHT3X_I2C_SDA")
	)
	(segment
		(start 116.488464 -91.694)
		(end 116.361464 -91.821)
		(width 0.127)
		(layer "In7.Cu")
		(net "SHT3X_I2C_SDA")
	)
	(segment
		(start 147.066 -56.812434)
		(end 148.0185 -57.764934)
		(width 0.127)
		(layer "In7.Cu")
		(net "SHT3X_I2C_SDA")
	)
	(segment
		(start 115.853464 -92.48648)
		(end 115.726464 -92.35948)
		(width 0.127)
		(layer "In7.Cu")
		(net "SHT3X_I2C_SDA")
	)
	(segment
		(start 114.456464 -91.821)
		(end 114.329464 -91.694)
		(width 0.127)
		(layer "In7.Cu")
		(net "SHT3X_I2C_SDA")
	)
	(segment
		(start 116.361464 -91.821)
		(end 116.361464 -92.35948)
		(width 0.127)
		(layer "In7.Cu")
		(net "SHT3X_I2C_SDA")
	)
	(segment
		(start 99.949 -93.345)
		(end 99.314 -92.71)
		(width 0.127)
		(layer "In7.Cu")
		(net "SHT3X_I2C_SDA")
	)
	(segment
		(start 117.631464 -92.35948)
		(end 117.504464 -92.48648)
		(width 0.127)
		(layer "In7.Cu")
		(net "SHT3X_I2C_SDA")
	)
	(segment
		(start 148.971 -48.006)
		(end 147.574254 -48.006)
		(width 0.127)
		(layer "In7.Cu")
		(net "SHT3X_I2C_SDA")
	)
	(segment
		(start 129.729992 -89.218008)
		(end 128.397 -90.551)
		(width 0.127)
		(layer "In7.Cu")
		(net "SHT3X_I2C_SDA")
	)
	(segment
		(start 118.901464 -91.821)
		(end 118.901464 -92.35948)
		(width 0.127)
		(layer "In7.Cu")
		(net "SHT3X_I2C_SDA")
	)
	(segment
		(start 117.504464 -92.48648)
		(end 117.123464 -92.48648)
		(width 0.127)
		(layer "In7.Cu")
		(net "SHT3X_I2C_SDA")
	)
	(segment
		(start 138.303254 -78.359)
		(end 133.17982 -78.359)
		(width 0.127)
		(layer "In7.Cu")
		(net "SHT3X_I2C_SDA")
	)
	(segment
		(start 131.5212 -80.01762)
		(end 131.5212 -86.791292)
		(width 0.127)
		(layer "In7.Cu")
		(net "SHT3X_I2C_SDA")
	)
	(segment
		(start 117.631464 -91.821)
		(end 117.631464 -92.35948)
		(width 0.127)
		(layer "In7.Cu")
		(net "SHT3X_I2C_SDA")
	)
	(segment
		(start 149.225 -48.26)
		(end 148.971 -48.006)
		(width 0.127)
		(layer "In7.Cu")
		(net "SHT3X_I2C_SDA")
	)
	(segment
		(start 141.986 -74.676254)
		(end 138.303254 -78.359)
		(width 0.127)
		(layer "In7.Cu")
		(net "SHT3X_I2C_SDA")
	)
	(segment
		(start 118.266464 -91.821)
		(end 118.139464 -91.694)
		(width 0.127)
		(layer "In7.Cu")
		(net "SHT3X_I2C_SDA")
	)
	(segment
		(start 131.5212 -86.791292)
		(end 129.729992 -88.5825)
		(width 0.127)
		(layer "In7.Cu")
		(net "SHT3X_I2C_SDA")
	)
	(segment
		(start 117.123464 -92.48648)
		(end 116.996464 -92.35948)
		(width 0.127)
		(layer "In7.Cu")
		(net "SHT3X_I2C_SDA")
	)
	(segment
		(start 116.996464 -91.821)
		(end 116.869464 -91.694)
		(width 0.127)
		(layer "In7.Cu")
		(net "SHT3X_I2C_SDA")
	)
	(segment
		(start 116.234464 -92.48648)
		(end 115.853464 -92.48648)
		(width 0.127)
		(layer "In7.Cu")
		(net "SHT3X_I2C_SDA")
	)
	(segment
		(start 105.029 -93.345)
		(end 99.949 -93.345)
		(width 0.127)
		(layer "In7.Cu")
		(net "SHT3X_I2C_SDA")
	)
	(segment
		(start 115.726464 -91.821)
		(end 115.599464 -91.694)
		(width 0.127)
		(layer "In7.Cu")
		(net "SHT3X_I2C_SDA")
	)
	(segment
		(start 93.853 -89.154254)
		(end 92.777564 -88.078818)
		(width 0.11938)
		(layer "F.Cu")
		(net "SHT3X_I2C_SCL")
	)
	(segment
		(start 85.064346 -85.826092)
		(end 83.3501 -85.826092)
		(width 0.11938)
		(layer "F.Cu")
		(net "SHT3X_I2C_SCL")
	)
	(segment
		(start 92.777564 -88.078818)
		(end 87.317072 -88.078818)
		(width 0.11938)
		(layer "F.Cu")
		(net "SHT3X_I2C_SCL")
	)
	(segment
		(start 96.774 -92.709746)
		(end 93.853 -89.788746)
		(width 0.11938)
		(layer "F.Cu")
		(net "SHT3X_I2C_SCL")
	)
	(segment
		(start 93.853 -89.788746)
		(end 93.853 -89.154254)
		(width 0.11938)
		(layer "F.Cu")
		(net "SHT3X_I2C_SCL")
	)
	(segment
		(start 154.153108 -48.47971)
		(end 154.153108 -47.244)
		(width 0.11938)
		(layer "F.Cu")
		(net "SHT3X_I2C_SCL")
	)
	(segment
		(start 87.317072 -88.078818)
		(end 85.064346 -85.826092)
		(width 0.11938)
		(layer "F.Cu")
		(net "SHT3X_I2C_SCL")
	)
	(segment
		(start 96.774 -92.71)
		(end 96.774 -92.709746)
		(width 0.11938)
		(layer "F.Cu")
		(net "SHT3X_I2C_SCL")
	)
	(via
		(at 96.774 -92.71)
		(size 0.508)
		(drill 0.254)
		(layers "F.Cu" "B.Cu")
		(net "SHT3X_I2C_SCL")
	)
	(via
		(at 154.153108 -47.244)
		(size 0.508)
		(drill 0.254)
		(layers "F.Cu" "B.Cu")
		(net "SHT3X_I2C_SCL")
	)
	(segment
		(start 154.153108 -48.47971)
		(end 154.153108 -47.244)
		(width 0.11938)
		(layer "B.Cu")
		(net "SHT3X_I2C_SCL")
	)
	(segment
		(start 145.923 -67.437)
		(end 141.097 -72.263)
		(width 0.127)
		(layer "In7.Cu")
		(net "SHT3X_I2C_SCL")
	)
	(segment
		(start 147.363688 -47.498)
		(end 146.300444 -48.561244)
		(width 0.127)
		(layer "In7.Cu")
		(net "SHT3X_I2C_SCL")
	)
	(segment
		(start 120.178068 -90.043)
		(end 119.207534 -91.013534)
		(width 0.127)
		(layer "In7.Cu")
		(net "SHT3X_I2C_SCL")
	)
	(segment
		(start 147.6121 -58.0771)
		(end 147.6121 -64.0969)
		(width 0.127)
		(layer "In7.Cu")
		(net "SHT3X_I2C_SCL")
	)
	(segment
		(start 109.093 -94.234)
		(end 107.188 -92.329)
		(width 0.127)
		(layer "In7.Cu")
		(net "SHT3X_I2C_SCL")
	)
	(segment
		(start 131.0132 -79.807054)
		(end 131.0132 -86.580726)
		(width 0.127)
		(layer "In7.Cu")
		(net "SHT3X_I2C_SCL")
	)
	(segment
		(start 107.188 -92.329)
		(end 105.156 -92.329)
		(width 0.127)
		(layer "In7.Cu")
		(net "SHT3X_I2C_SCL")
	)
	(segment
		(start 150.06828 -47.498)
		(end 147.363688 -47.498)
		(width 0.127)
		(layer "In7.Cu")
		(net "SHT3X_I2C_SCL")
	)
	(segment
		(start 138.049 -77.851)
		(end 132.969254 -77.851)
		(width 0.127)
		(layer "In7.Cu")
		(net "SHT3X_I2C_SCL")
	)
	(segment
		(start 104.648 -92.837)
		(end 100.203 -92.837)
		(width 0.127)
		(layer "In7.Cu")
		(net "SHT3X_I2C_SCL")
	)
	(segment
		(start 145.796 -56.261)
		(end 147.6121 -58.0771)
		(width 0.127)
		(layer "In7.Cu")
		(net "SHT3X_I2C_SCL")
	)
	(segment
		(start 113.837466 -91.013534)
		(end 110.617 -94.234)
		(width 0.127)
		(layer "In7.Cu")
		(net "SHT3X_I2C_SCL")
	)
	(segment
		(start 110.617 -94.234)
		(end 109.093 -94.234)
		(width 0.127)
		(layer "In7.Cu")
		(net "SHT3X_I2C_SCL")
	)
	(segment
		(start 129.519426 -88.0745)
		(end 128.584198 -88.0745)
		(width 0.127)
		(layer "In7.Cu")
		(net "SHT3X_I2C_SCL")
	)
	(segment
		(start 146.300444 -54.479444)
		(end 145.796 -54.983888)
		(width 0.127)
		(layer "In7.Cu")
		(net "SHT3X_I2C_SCL")
	)
	(segment
		(start 145.796 -54.983888)
		(end 145.796 -56.261)
		(width 0.127)
		(layer "In7.Cu")
		(net "SHT3X_I2C_SCL")
	)
	(segment
		(start 132.969254 -77.851)
		(end 131.0132 -79.807054)
		(width 0.127)
		(layer "In7.Cu")
		(net "SHT3X_I2C_SCL")
	)
	(segment
		(start 131.0132 -86.580726)
		(end 129.519426 -88.0745)
		(width 0.127)
		(layer "In7.Cu")
		(net "SHT3X_I2C_SCL")
	)
	(segment
		(start 105.156 -92.329)
		(end 104.648 -92.837)
		(width 0.127)
		(layer "In7.Cu")
		(net "SHT3X_I2C_SCL")
	)
	(segment
		(start 119.207534 -91.013534)
		(end 113.837466 -91.013534)
		(width 0.127)
		(layer "In7.Cu")
		(net "SHT3X_I2C_SCL")
	)
	(segment
		(start 152.400254 -46.863)
		(end 150.70328 -46.863)
		(width 0.127)
		(layer "In7.Cu")
		(net "SHT3X_I2C_SCL")
	)
	(segment
		(start 99.314 -91.948)
		(end 97.536 -91.948)
		(width 0.127)
		(layer "In7.Cu")
		(net "SHT3X_I2C_SCL")
	)
	(segment
		(start 126.615698 -90.043)
		(end 120.178068 -90.043)
		(width 0.127)
		(layer "In7.Cu")
		(net "SHT3X_I2C_SCL")
	)
	(segment
		(start 145.923 -65.786)
		(end 145.923 -67.437)
		(width 0.127)
		(layer "In7.Cu")
		(net "SHT3X_I2C_SCL")
	)
	(segment
		(start 146.300444 -48.561244)
		(end 146.300444 -54.479444)
		(width 0.127)
		(layer "In7.Cu")
		(net "SHT3X_I2C_SCL")
	)
	(segment
		(start 154.153108 -47.244)
		(end 152.781254 -47.244)
		(width 0.127)
		(layer "In7.Cu")
		(net "SHT3X_I2C_SCL")
	)
	(segment
		(start 152.781254 -47.244)
		(end 152.400254 -46.863)
		(width 0.127)
		(layer "In7.Cu")
		(net "SHT3X_I2C_SCL")
	)
	(segment
		(start 150.70328 -46.863)
		(end 150.06828 -47.498)
		(width 0.127)
		(layer "In7.Cu")
		(net "SHT3X_I2C_SCL")
	)
	(segment
		(start 141.097 -74.803)
		(end 138.049 -77.851)
		(width 0.127)
		(layer "In7.Cu")
		(net "SHT3X_I2C_SCL")
	)
	(segment
		(start 100.203 -92.837)
		(end 99.314 -91.948)
		(width 0.127)
		(layer "In7.Cu")
		(net "SHT3X_I2C_SCL")
	)
	(segment
		(start 128.584198 -88.0745)
		(end 126.615698 -90.043)
		(width 0.127)
		(layer "In7.Cu")
		(net "SHT3X_I2C_SCL")
	)
	(segment
		(start 147.6121 -64.0969)
		(end 145.923 -65.786)
		(width 0.127)
		(layer "In7.Cu")
		(net "SHT3X_I2C_SCL")
	)
	(segment
		(start 97.536 -91.948)
		(end 96.774 -92.71)
		(width 0.127)
		(layer "In7.Cu")
		(net "SHT3X_I2C_SCL")
	)
	(segment
		(start 141.097 -72.263)
		(end 141.097 -74.803)
		(width 0.127)
		(layer "In7.Cu")
		(net "SHT3X_I2C_SCL")
	)
	(segment
		(start 151.613108 -49.54651)
		(end 151.613108 -50.749708)
		(width 0.11938)
		(layer "F.Cu")
		(net "SHT3X_ADDR")
	)
	(segment
		(start 151.613108 -50.749708)
		(end 151.638 -50.7746)
		(width 0.11938)
		(layer "F.Cu")
		(net "SHT3X_ADDR")
	)
	(segment
		(start 151.896064 -51.032664)
		(end 151.638 -50.7746)
		(width 0.11938)
		(layer "F.Cu")
		(net "SHT3X_ADDR")
	)
	(segment
		(start 151.896064 -51.922172)
		(end 151.896064 -51.032664)
		(width 0.11938)
		(layer "F.Cu")
		(net "SHT3X_ADDR")
	)
	(via
		(at 151.638 -50.7746)
		(size 0.4572)
		(drill 0.2032)
		(layers "F.Cu" "B.Cu")
		(net "SHT3X_ADDR")
	)
	(segment
		(start 151.638 -50.7746)
		(end 151.613108 -50.749708)
		(width 0.11938)
		(layer "B.Cu")
		(net "SHT3X_ADDR")
	)
	(segment
		(start 151.613108 -50.749708)
		(end 151.613108 -49.54651)
		(width 0.11938)
		(layer "B.Cu")
		(net "SHT3X_ADDR")
	)
	(segment
		(start 96.4692 -26.924)
		(end 96.5962 -27.051)
		(width 0.381)
		(layer "F.Cu")
		(net "SG")
	)
	(segment
		(start 99.846892 -51.823112)
		(end 99.34702 -52.322984)
		(width 0.381)
		(layer "F.Cu")
		(net "SG")
	)
	(segment
		(start 138.796522 -100.7618)
		(end 137.922 -100.7618)
		(width 0.381)
		(layer "F.Cu")
		(net "SG")
	)
	(segment
		(start 106.847132 -50.823114)
		(end 106.34726 -51.322986)
		(width 0.381)
		(layer "F.Cu")
		(net "SG")
	)
	(segment
		(start 114.681 -25.146)
		(end 114.681 -27.1018)
		(width 0.381)
		(layer "F.Cu")
		(net "SG")
	)
	(segment
		(start 101.473 -30.48)
		(end 101.346 -30.48)
		(width 0.381)
		(layer "F.Cu")
		(net "SG")
	)
	(segment
		(start 113.6269 -27.4828)
		(end 113.2459 -27.8638)
		(width 0.381)
		(layer "F.Cu")
		(net "SG")
	)
	(segment
		(start 12.612878 -68.707)
		(end 12.358878 -68.961)
		(width 0.254)
		(layer "F.Cu")
		(net "SG")
	)
	(segment
		(start 107.84713 -41.823132)
		(end 107.347258 -41.32326)
		(width 0.381)
		(layer "F.Cu")
		(net "SG")
	)
	(segment
		(start 103.847138 -43.823128)
		(end 103.347266 -43.323256)
		(width 0.381)
		(layer "F.Cu")
		(net "SG")
	)
	(segment
		(start 101.847142 -40.823134)
		(end 101.34727 -40.323262)
		(width 0.381)
		(layer "F.Cu")
		(net "SG")
	)
	(segment
		(start 25.273 -90.87993)
		(end 25.27427 -90.8812)
		(width 0.254)
		(layer "F.Cu")
		(net "SG")
	)
	(segment
		(start 104.847136 -37.82314)
		(end 104.347264 -37.323268)
		(width 0.381)
		(layer "F.Cu")
		(net "SG")
	)
	(segment
		(start 120.346978 -42.323258)
		(end 119.847106 -41.823386)
		(width 0.381)
		(layer "F.Cu")
		(net "SG")
	)
	(segment
		(start 141.097 -60.579)
		(end 141.097 -60.0964)
		(width 0.254)
		(layer "F.Cu")
		(net "SG")
	)
	(segment
		(start 25.146 -88.9)
		(end 25.273 -89.027)
		(width 0.254)
		(layer "F.Cu")
		(net "SG")
	)
	(segment
		(start 114.3 -27.4828)
		(end 113.6269 -27.4828)
		(width 0.381)
		(layer "F.Cu")
		(net "SG")
	)
	(segment
		(start 117.84711 -37.82314)
		(end 118.346982 -37.323268)
		(width 0.381)
		(layer "F.Cu")
		(net "SG")
	)
	(segment
		(start 103.847138 -49.823116)
		(end 103.347266 -50.322988)
		(width 0.381)
		(layer "F.Cu")
		(net "SG")
	)
	(segment
		(start 65.913 -17.8054)
		(end 65.913 -16.637)
		(width 0.381)
		(layer "F.Cu")
		(net "SG")
	)
	(segment
		(start 93.091 -20.716494)
		(end 93.091 -21.717)
		(width 0.381)
		(layer "F.Cu")
		(net "SG")
	)
	(segment
		(start 18.946622 -53.1114)
		(end 18.946622 -51.360578)
		(width 0.381)
		(layer "F.Cu")
		(net "SG")
	)
	(segment
		(start 30.87878 -15.58544)
		(end 30.87878 -15.180056)
		(width 0.381)
		(layer "F.Cu")
		(net "SG")
	)
	(segment
		(start 105.7783 -101.9175)
		(end 106.299 -101.3968)
		(width 0.3048)
		(layer "F.Cu")
		(net "SG")
	)
	(segment
		(start 30.27426 -90.8812)
		(end 30.27426 -92.37726)
		(width 0.254)
		(layer "F.Cu")
		(net "SG")
	)
	(segment
		(start 34.417 -97.282)
		(end 34.417 -95.885)
		(width 0.381)
		(layer "F.Cu")
		(net "SG")
	)
	(segment
		(start 32.766 -92.71)
		(end 32.766 -92.202)
		(width 0.254)
		(layer "F.Cu")
		(net "SG")
	)
	(segment
		(start 30.850078 -96.266)
		(end 30.099 -96.266)
		(width 0.254)
		(layer "F.Cu")
		(net "SG")
	)
	(segment
		(start 146.3548 -93.1418)
		(end 147.3454 -93.1418)
		(width 0.381)
		(layer "F.Cu")
		(net "SG")
	)
	(segment
		(start 24.280622 -84.670138)
		(end 24.136096 -84.814664)
		(width 0.254)
		(layer "F.Cu")
		(net "SG")
	)
	(segment
		(start 152.146 -23.876)
		(end 153.83764 -25.56764)
		(width 0.381)
		(layer "F.Cu")
		(net "SG")
	)
	(segment
		(start 34.417 -100.584)
		(end 34.147506 -100.853494)
		(width 0.381)
		(layer "F.Cu")
		(net "SG")
	)
	(segment
		(start 110.847124 -42.82313)
		(end 111.346996 -42.323258)
		(width 0.381)
		(layer "F.Cu")
		(net "SG")
	)
	(segment
		(start 17.653 -25.4)
		(end 18.161 -24.892)
		(width 0.3048)
		(layer "F.Cu")
		(net "SG")
	)
	(segment
		(start 118.847108 -34.822892)
		(end 119.34698 -34.32302)
		(width 0.381)
		(layer "F.Cu")
		(net "SG")
	)
	(segment
		(start 59.649868 -6.847332)
		(end 59.649868 -3.500374)
		(width 0.381)
		(layer "F.Cu")
		(net "SG")
	)
	(segment
		(start 67.133216 -7.3406)
		(end 67.649852 -6.823964)
		(width 0.381)
		(layer "F.Cu")
		(net "SG")
	)
	(segment
		(start 101.092 -88.40216)
		(end 101.092 -89.408)
		(width 0.381)
		(layer "F.Cu")
		(net "SG")
	)
	(segment
		(start 115.847114 -33.822894)
		(end 116.292376 -33.377632)
		(width 0.381)
		(layer "F.Cu")
		(net "SG")
	)
	(segment
		(start 115.847114 -43.823128)
		(end 115.347242 -43.323256)
		(width 0.381)
		(layer "F.Cu")
		(net "SG")
	)
	(segment
		(start 93.218 -61.275722)
		(end 93.218 -58.928)
		(width 0.381)
		(layer "F.Cu")
		(net "SG")
	)
	(segment
		(start 75.819 -46.99)
		(end 75.31227 -47.49673)
		(width 0.254)
		(layer "F.Cu")
		(net "SG")
	)
	(segment
		(start 85.974936 -64.8462)
		(end 87.249 -64.8462)
		(width 0.381)
		(layer "F.Cu")
		(net "SG")
	)
	(segment
		(start 111.6584 -100.711)
		(end 111.6584 -101.981)
		(width 0.381)
		(layer "F.Cu")
		(net "SG")
	)
	(segment
		(start 76.12888 -17.07388)
		(end 76.12888 -16.96212)
		(width 0.381)
		(layer "F.Cu")
		(net "SG")
	)
	(segment
		(start 69.17182 -13.937234)
		(end 69.17182 -14.308074)
		(width 0.3048)
		(layer "F.Cu")
		(net "SG")
	)
	(segment
		(start 32.776922 -96.266)
		(end 33.528 -96.266)
		(width 0.254)
		(layer "F.Cu")
		(net "SG")
	)
	(segment
		(start 101.847142 -36.823142)
		(end 101.34727 -36.32327)
		(width 0.381)
		(layer "F.Cu")
		(net "SG")
	)
	(segment
		(start 113.847118 -49.823116)
		(end 114.34699 -50.322988)
		(width 0.381)
		(layer "F.Cu")
		(net "SG")
	)
	(segment
		(start 35.591242 -99.467416)
		(end 35.591242 -99.409758)
		(width 0.3048)
		(layer "F.Cu")
		(net "SG")
	)
	(segment
		(start 23.0378 -65.544192)
		(end 22.281642 -65.544192)
		(width 0.381)
		(layer "F.Cu")
		(net "SG")
	)
	(segment
		(start 107.188 -19.685)
		(end 106.426 -19.685)
		(width 0.381)
		(layer "F.Cu")
		(net "SG")
	)
	(segment
		(start 34.417 -95.885)
		(end 33.909 -95.377)
		(width 0.381)
		(layer "F.Cu")
		(net "SG")
	)
	(segment
		(start 33.909 -95.377)
		(end 33.528 -95.377)
		(width 0.381)
		(layer "F.Cu")
		(net "SG")
	)
	(segment
		(start 22.606 -17.018)
		(end 23.1394 -17.5514)
		(width 0.381)
		(layer "F.Cu")
		(net "SG")
	)
	(segment
		(start 90.9828 -70.1294)
		(end 90.1319 -70.1294)
		(width 0.3048)
		(layer "F.Cu")
		(net "SG")
	)
	(segment
		(start 36.449 -100.2284)
		(end 35.8394 -100.2284)
		(width 0.3048)
		(layer "F.Cu")
		(net "SG")
	)
	(segment
		(start 91.518994 -104.064054)
		(end 91.01074 -103.5558)
		(width 0.381)
		(layer "F.Cu")
		(net "SG")
	)
	(segment
		(start 35.705542 -82.314542)
		(end 34.3408 -82.314542)
		(width 0.254)
		(layer "F.Cu")
		(net "SG")
	)
	(segment
		(start 48.64989 -3.500374)
		(end 48.64989 -7.3406)
		(width 0.381)
		(layer "F.Cu")
		(net "SG")
	)
	(segment
		(start 101.847142 -35.82289)
		(end 101.34727 -35.323018)
		(width 0.381)
		(layer "F.Cu")
		(net "SG")
	)
	(segment
		(start 100.84689 -48.823118)
		(end 100.347018 -49.32299)
		(width 0.381)
		(layer "F.Cu")
		(net "SG")
	)
	(segment
		(start 30.87878 -15.180056)
		(end 30.353 -14.654276)
		(width 0.381)
		(layer "F.Cu")
		(net "SG")
	)
	(segment
		(start 53.25364 -82.9437)
		(end 53.25364 -84.201)
		(width 0.381)
		(layer "F.Cu")
		(net "SG")
	)
	(segment
		(start 78.64983 -3.500374)
		(end 78.64983 -6.848602)
		(width 0.381)
		(layer "F.Cu")
		(net "SG")
	)
	(segment
		(start 92.3544 -44.8564)
		(end 92.285058 -44.8564)
		(width 0.381)
		(layer "F.Cu")
		(net "SG")
	)
	(segment
		(start 64.649858 -3.500374)
		(end 64.649858 -7.3406)
		(width 0.381)
		(layer "F.Cu")
		(net "SG")
	)
	(segment
		(start 59.1058 -7.3914)
		(end 59.649868 -6.847332)
		(width 0.381)
		(layer "F.Cu")
		(net "SG")
	)
	(segment
		(start 109.847126 -51.823112)
		(end 110.346998 -52.322984)
		(width 0.381)
		(layer "F.Cu")
		(net "SG")
	)
	(segment
		(start 119.634 -88.3666)
		(end 119.634 -88.138)
		(width 0.381)
		(layer "F.Cu")
		(net "SG")
	)
	(segment
		(start 27.774138 -92.290138)
		(end 27.774138 -90.8812)
		(width 0.254)
		(layer "F.Cu")
		(net "SG")
	)
	(segment
		(start 29.718 -100.838)
		(end 29.337 -100.457)
		(width 0.381)
		(layer "F.Cu")
		(net "SG")
	)
	(segment
		(start 146.3548 -97.9678)
		(end 146.3548 -96.6978)
		(width 0.381)
		(layer "F.Cu")
		(net "SG")
	)
	(segment
		(start 5.2197 -23.8887)
		(end 5.2197 -24.2951)
		(width 0.381)
		(layer "F.Cu")
		(net "SG")
	)
	(segment
		(start 38.354 -81.4324)
		(end 38.354 -82.3468)
		(width 0.381)
		(layer "F.Cu")
		(net "SG")
	)
	(segment
		(start 147.049998 -103.60025)
		(end 144.050004 -103.60025)
		(width 0.381)
		(layer "F.Cu")
		(net "SG")
	)
	(segment
		(start 51.649884 -7.024116)
		(end 51.2953 -7.3787)
		(width 0.381)
		(layer "F.Cu")
		(net "SG")
	)
	(segment
		(start 127.0254 -36.322)
		(end 128.0033 -36.322)
		(width 0.381)
		(layer "F.Cu")
		(net "SG")
	)
	(segment
		(start 93.091 -21.717)
		(end 94.869 -23.495)
		(width 0.381)
		(layer "F.Cu")
		(net "SG")
	)
	(segment
		(start 108.220002 -26.305002)
		(end 107.442 -25.527)
		(width 0.381)
		(layer "F.Cu")
		(net "SG")
	)
	(segment
		(start 125.1204 -42.545)
		(end 125.984 -42.545)
		(width 0.381)
		(layer "F.Cu")
		(net "SG")
	)
	(segment
		(start 93.218 -58.801254)
		(end 93.218 -58.928)
		(width 0.381)
		(layer "F.Cu")
		(net "SG")
	)
	(segment
		(start 115.6716 -82.9818)
		(end 115.6716 -81.788)
		(width 0.381)
		(layer "F.Cu")
		(net "SG")
	)
	(segment
		(start 112.776 -62.5094)
		(end 112.776 -63.5)
		(width 0.381)
		(layer "F.Cu")
		(net "SG")
	)
	(segment
		(start 139.333478 -99.3648)
		(end 139.333478 -98.4758)
		(width 0.2032)
		(layer "F.Cu")
		(net "SG")
	)
	(segment
		(start 113.5888 -89.7001)
		(end 113.5888 -88.265)
		(width 0.381)
		(layer "F.Cu")
		(net "SG")
	)
	(segment
		(start 125.2982 -32.1056)
		(end 125.2982 -30.861)
		(width 0.381)
		(layer "F.Cu")
		(net "SG")
	)
	(segment
		(start 146.3548 -96.6978)
		(end 147.3962 -96.6978)
		(width 0.381)
		(layer "F.Cu")
		(net "SG")
	)
	(segment
		(start 145.578322 -94.2848)
		(end 146.3802 -94.2848)
		(width 0.2032)
		(layer "F.Cu")
		(net "SG")
	)
	(segment
		(start 98.846894 -37.82314)
		(end 98.347022 -37.323268)
		(width 0.381)
		(layer "F.Cu")
		(net "SG")
	)
	(segment
		(start 98.846894 -41.823132)
		(end 98.347022 -41.32326)
		(width 0.381)
		(layer "F.Cu")
		(net "SG")
	)
	(segment
		(start 104.1654 -24.638)
		(end 103.9368 -24.8666)
		(width 0.3048)
		(layer "F.Cu")
		(net "SG")
	)
	(segment
		(start 71.649844 -6.823964)
		(end 71.649844 -3.500374)
		(width 0.381)
		(layer "F.Cu")
		(net "SG")
	)
	(segment
		(start 146.6088 -16.7132)
		(end 147.447 -16.7132)
		(width 0.3048)
		(layer "F.Cu")
		(net "SG")
	)
	(segment
		(start 82.408268 -86.476078)
		(end 83.3501 -86.476078)
		(width 0.3048)
		(layer "F.Cu")
		(net "SG")
	)
	(segment
		(start 108.847128 -54.823106)
		(end 108.347256 -55.322978)
		(width 0.381)
		(layer "F.Cu")
		(net "SG")
	)
	(segment
		(start 91.44 -61.595)
		(end 91.567 -61.722)
		(width 0.381)
		(layer "F.Cu")
		(net "SG")
	)
	(segment
		(start 107.84713 -47.82312)
		(end 107.347258 -48.322992)
		(width 0.381)
		(layer "F.Cu")
		(net "SG")
	)
	(segment
		(start 114.3 -28.956)
		(end 113.792 -29.464)
		(width 0.381)
		(layer "F.Cu")
		(net "SG")
	)
	(segment
		(start 94.869 -23.495)
		(end 94.869 -23.876)
		(width 0.381)
		(layer "F.Cu")
		(net "SG")
	)
	(segment
		(start 97.155 -26.2636)
		(end 96.4946 -26.924)
		(width 0.381)
		(layer "F.Cu")
		(net "SG")
	)
	(segment
		(start 15.93977 -84.072476)
		(end 16.0274 -83.984846)
		(width 0.381)
		(layer "F.Cu")
		(net "SG")
	)
	(segment
		(start 134.1882 -105.422446)
		(end 133.394704 -104.62895)
		(width 0.381)
		(layer "F.Cu")
		(net "SG")
	)
	(segment
		(start 113.411 -73.533)
		(end 113.156746 -73.533)
		(width 0.3048)
		(layer "F.Cu")
		(net "SG")
	)
	(segment
		(start 75.31227 -47.49673)
		(end 74.354436 -47.49673)
		(width 0.254)
		(layer "F.Cu")
		(net "SG")
	)
	(segment
		(start 111.8362 -19.558)
		(end 112.1156 -19.8374)
		(width 0.381)
		(layer "F.Cu")
		(net "SG")
	)
	(segment
		(start 99.06 -25.527)
		(end 98.99142 -25.45842)
		(width 0.381)
		(layer "F.Cu")
		(net "SG")
	)
	(segment
		(start 102.84714 -41.823132)
		(end 102.347268 -41.32326)
		(width 0.381)
		(layer "F.Cu")
		(net "SG")
	)
	(segment
		(start 73.166478 -7.3406)
		(end 72.649842 -6.823964)
		(width 0.381)
		(layer "F.Cu")
		(net "SG")
	)
	(segment
		(start 108.847128 -42.82313)
		(end 108.347256 -42.323258)
		(width 0.381)
		(layer "F.Cu")
		(net "SG")
	)
	(segment
		(start 153.049986 -103.60025)
		(end 150.049992 -103.60025)
		(width 0.381)
		(layer "F.Cu")
		(net "SG")
	)
	(segment
		(start 12.612878 -68.072)
		(end 12.612878 -68.707)
		(width 0.254)
		(layer "F.Cu")
		(net "SG")
	)
	(segment
		(start 102.84714 -52.82311)
		(end 102.347268 -53.322982)
		(width 0.381)
		(layer "F.Cu")
		(net "SG")
	)
	(segment
		(start 51.649884 -3.500374)
		(end 51.649884 -7.024116)
		(width 0.381)
		(layer "F.Cu")
		(net "SG")
	)
	(segment
		(start 100.84689 -44.823126)
		(end 100.347018 -45.322998)
		(width 0.381)
		(layer "F.Cu")
		(net "SG")
	)
	(segment
		(start 95.26397 -25.45842)
		(end 95.716852 -25.45842)
		(width 0.381)
		(layer "F.Cu")
		(net "SG")
	)
	(segment
		(start 33.528 -94.869)
		(end 32.766 -94.107)
		(width 0.381)
		(layer "F.Cu")
		(net "SG")
	)
	(segment
		(start 109.847126 -42.82313)
		(end 110.346998 -42.323258)
		(width 0.381)
		(layer "F.Cu")
		(net "SG")
	)
	(segment
		(start 154.2034 -57.658)
		(end 155.067 -57.658)
		(width 0.4572)
		(layer "F.Cu")
		(net "SG")
	)
	(segment
		(start 33.528 -95.377)
		(end 33.528 -94.869)
		(width 0.381)
		(layer "F.Cu")
		(net "SG")
	)
	(segment
		(start 122.690382 -18.806922)
		(end 124.0917 -18.806922)
		(width 0.381)
		(layer "F.Cu")
		(net "SG")
	)
	(segment
		(start 30.27426 -92.37726)
		(end 30.48 -92.583)
		(width 0.254)
		(layer "F.Cu")
		(net "SG")
	)
	(segment
		(start 105.847134 -39.823136)
		(end 105.347262 -39.323264)
		(width 0.381)
		(layer "F.Cu")
		(net "SG")
	)
	(segment
		(start 99.846892 -35.82289)
		(end 99.34702 -35.323018)
		(width 0.381)
		(layer "F.Cu")
		(net "SG")
	)
	(segment
		(start 99.846892 -44.823126)
		(end 99.34702 -45.322998)
		(width 0.381)
		(layer "F.Cu")
		(net "SG")
	)
	(segment
		(start 96.52 -85.979)
		(end 95.7326 -85.979)
		(width 0.3048)
		(layer "F.Cu")
		(net "SG")
	)
	(segment
		(start 35.8394 -100.2284)
		(end 35.5854 -100.4824)
		(width 0.3048)
		(layer "F.Cu")
		(net "SG")
	)
	(segment
		(start 96.5962 -27.0764)
		(end 97.0534 -27.5336)
		(width 0.381)
		(layer "F.Cu")
		(net "SG")
	)
	(segment
		(start 106.299 -101.3968)
		(end 107.67314 -101.3968)
		(width 0.3048)
		(layer "F.Cu")
		(net "SG")
	)
	(segment
		(start 104.29875 -29.24175)
		(end 104.29875 -29.917898)
		(width 0.381)
		(layer "F.Cu")
		(net "SG")
	)
	(segment
		(start 11.557 -41.7576)
		(end 11.557 -40.894)
		(width 0.381)
		(layer "F.Cu")
		(net "SG")
	)
	(segment
		(start 126.0094 -69.2912)
		(end 125.2474 -69.2912)
		(width 0.3048)
		(layer "F.Cu")
		(net "SG")
	)
	(segment
		(start 143.036798 -95.919798)
		(end 142.054834 -95.919798)
		(width 0.2032)
		(layer "F.Cu")
		(net "SG")
	)
	(segment
		(start 156.120592 -34.814002)
		(end 157.717998 -34.814002)
		(width 0.381)
		(layer "F.Cu")
		(net "SG")
	)
	(segment
		(start 25.273 -89.027)
		(end 25.273 -90.87993)
		(width 0.254)
		(layer "F.Cu")
		(net "SG")
	)
	(segment
		(start 110.847124 -38.823138)
		(end 111.346996 -38.323266)
		(width 0.381)
		(layer "F.Cu")
		(net "SG")
	)
	(segment
		(start 91.1352 -104.6734)
		(end 91.44 -104.3686)
		(width 0.3048)
		(layer "F.Cu")
		(net "SG")
	)
	(segment
		(start 98.846894 -35.82289)
		(end 98.347022 -35.323018)
		(width 0.381)
		(layer "F.Cu")
		(net "SG")
	)
	(segment
		(start 107.84713 -43.823128)
		(end 107.347258 -43.323256)
		(width 0.381)
		(layer "F.Cu")
		(net "SG")
	)
	(segment
		(start 116.332 -83.058)
		(end 116.586 -82.804)
		(width 0.381)
		(layer "F.Cu")
		(net "SG")
	)
	(segment
		(start 139.954 -60.070746)
		(end 140.2842 -60.400946)
		(width 0.3048)
		(layer "F.Cu")
		(net "SG")
	)
	(segment
		(start 86.741 -59.309)
		(end 86.741 -59.279536)
		(width 0.254)
		(layer "F.Cu")
		(net "SG")
	)
	(segment
		(start 118.847108 -44.823126)
		(end 119.34698 -45.322998)
		(width 0.381)
		(layer "F.Cu")
		(net "SG")
	)
	(segment
		(start 71.133208 -7.3406)
		(end 71.649844 -6.823964)
		(width 0.381)
		(layer "F.Cu")
		(net "SG")
	)
	(segment
		(start 153.83764 -25.56764)
		(end 154.5463 -25.56764)
		(width 0.381)
		(layer "F.Cu")
		(net "SG")
	)
	(segment
		(start 89.2048 -49.9364)
		(end 89.05113 -49.78273)
		(width 0.2032)
		(layer "F.Cu")
		(net "SG")
	)
	(segment
		(start 109.847126 -43.823128)
		(end 110.346998 -43.323256)
		(width 0.381)
		(layer "F.Cu")
		(net "SG")
	)
	(segment
		(start 104.2162 -101.3968)
		(end 102.84206 -101.3968)
		(width 0.3048)
		(layer "F.Cu")
		(net "SG")
	)
	(segment
		(start 30.48 -94.488)
		(end 30.353 -94.615)
		(width 0.381)
		(layer "F.Cu")
		(net "SG")
	)
	(segment
		(start 75.649836 -6.823964)
		(end 75.649836 -3.500374)
		(width 0.381)
		(layer "F.Cu")
		(net "SG")
	)
	(segment
		(start 113.36274 -19.812)
		(end 112.141 -19.812)
		(width 0.381)
		(layer "F.Cu")
		(net "SG")
	)
	(segment
		(start 79.4004 -54.9656)
		(end 80.2386 -54.9656)
		(width 0.381)
		(layer "F.Cu")
		(net "SG")
	)
	(segment
		(start 115.9764 -72.263)
		(end 116.84 -72.263)
		(width 0.381)
		(layer "F.Cu")
		(net "SG")
	)
	(segment
		(start 86.856062 -61.088016)
		(end 86.856062 -60.452)
		(width 0.254)
		(layer "F.Cu")
		(net "SG")
	)
	(segment
		(start 113.90122 -20.35048)
		(end 113.36274 -19.812)
		(width 0.381)
		(layer "F.Cu")
		(net "SG")
	)
	(segment
		(start 162.8267 -54.900068)
		(end 161.544 -54.900068)
		(width 0.381)
		(layer "F.Cu")
		(net "SG")
	)
	(segment
		(start 105.7783 -100.8761)
		(end 105.2576 -100.3554)
		(width 0.3048)
		(layer "F.Cu")
		(net "SG")
	)
	(segment
		(start 114.681 -27.1018)
		(end 114.3 -27.4828)
		(width 0.381)
		(layer "F.Cu")
		(net "SG")
	)
	(segment
		(start 134.376922 -69.215)
		(end 135.255 -69.215)
		(width 0.254)
		(layer "F.Cu")
		(net "SG")
	)
	(segment
		(start 87.249 -65.7606)
		(end 87.249 -64.8462)
		(width 0.381)
		(layer "F.Cu")
		(net "SG")
	)
	(segment
		(start 30.776926 -100.810568)
		(end 29.745432 -100.810568)
		(width 0.381)
		(layer "F.Cu")
		(net "SG")
	)
	(segment
		(start 104.684322 -77.887322)
		(end 105.9053 -77.887322)
		(width 0.381)
		(layer "F.Cu")
		(net "SG")
	)
	(segment
		(start 108.847128 -40.823134)
		(end 108.347256 -40.323262)
		(width 0.381)
		(layer "F.Cu")
		(net "SG")
	)
	(segment
		(start 36.10102 -82.71002)
		(end 35.705542 -82.314542)
		(width 0.254)
		(layer "F.Cu")
		(net "SG")
	)
	(segment
		(start 91.44 -104.188514)
		(end 91.518994 -104.10952)
		(width 0.3048)
		(layer "F.Cu")
		(net "SG")
	)
	(segment
		(start 124.63272 -32.1056)
		(end 125.2982 -32.1056)
		(width 0.381)
		(layer "F.Cu")
		(net "SG")
	)
	(segment
		(start 95.7326 -24.638)
		(end 95.7326 -25.442672)
		(width 0.381)
		(layer "F.Cu")
		(net "SG")
	)
	(segment
		(start 18.1356 -57.2008)
		(end 18.1356 -56.3118)
		(width 0.381)
		(layer "F.Cu")
		(net "SG")
	)
	(segment
		(start 78.64983 -6.848602)
		(end 78.157832 -7.3406)
		(width 0.381)
		(layer "F.Cu")
		(net "SG")
	)
	(segment
		(start 83.947 -73.279)
		(end 83.947 -74.041)
		(width 0.381)
		(layer "F.Cu")
		(net "SG")
	)
	(segment
		(start 105.029 -19.019012)
		(end 105.029 -18.4404)
		(width 0.381)
		(layer "F.Cu")
		(net "SG")
	)
	(segment
		(start 18.161 -24.892)
		(end 18.405348 -24.892)
		(width 0.3048)
		(layer "F.Cu")
		(net "SG")
	)
	(segment
		(start 159.255206 -58.796936)
		(end 159.255206 -60.449206)
		(width 0.381)
		(layer "F.Cu")
		(net "SG")
	)
	(segment
		(start 22.5806 -17.018)
		(end 22.606 -17.018)
		(width 0.381)
		(layer "F.Cu")
		(net "SG")
	)
	(segment
		(start 116.847112 -50.823114)
		(end 117.346984 -51.322986)
		(width 0.381)
		(layer "F.Cu")
		(net "SG")
	)
	(segment
		(start 107.84713 -37.82314)
		(end 107.347258 -37.323268)
		(width 0.381)
		(layer "F.Cu")
		(net "SG")
	)
	(segment
		(start 110.847124 -41.823132)
		(end 111.346996 -41.32326)
		(width 0.381)
		(layer "F.Cu")
		(net "SG")
	)
	(segment
		(start 94.869 -19.177)
		(end 94.869 -19.812)
		(width 0.381)
		(layer "F.Cu")
		(net "SG")
	)
	(segment
		(start 89.027 -58.293)
		(end 92.709746 -58.293)
		(width 0.381)
		(layer "F.Cu")
		(net "SG")
	)
	(segment
		(start 146.3548 -91.8718)
		(end 147.3708 -91.8718)
		(width 0.381)
		(layer "F.Cu")
		(net "SG")
	)
	(segment
		(start 73.533 -80.772)
		(end 73.279 -80.518)
		(width 0.381)
		(layer "F.Cu")
		(net "SG")
	)
	(segment
		(start 134.8105 -65.7987)
		(end 134.8105 -65.77965)
		(width 0.381)
		(layer "F.Cu")
		(net "SG")
	)
	(segment
		(start 73.533 -81.4324)
		(end 73.533 -80.772)
		(width 0.381)
		(layer "F.Cu")
		(net "SG")
	)
	(segment
		(start 30.353 -95.504)
		(end 30.099 -95.758)
		(width 0.381)
		(layer "F.Cu")
		(net "SG")
	)
	(segment
		(start 94.615 -58.928)
		(end 94.107 -59.436)
		(width 0.381)
		(layer "F.Cu")
		(net "SG")
	)
	(segment
		(start 4.318 -51.943)
		(end 5.2197 -52.8447)
		(width 0.381)
		(layer "F.Cu")
		(net "SG")
	)
	(segment
		(start 163.0934 -28.829)
		(end 164.338 -28.829)
		(width 0.381)
		(layer "F.Cu")
		(net "SG")
	)
	(segment
		(start 38.31844 -17.1196)
		(end 38.59276 -16.84528)
		(width 0.381)
		(layer "F.Cu")
		(net "SG")
	)
	(segment
		(start 12.964922 -39.878)
		(end 13.6906 -39.878)
		(width 0.254)
		(layer "F.Cu")
		(net "SG")
	)
	(segment
		(start 75.1332 -7.3406)
		(end 75.649836 -6.823964)
		(width 0.381)
		(layer "F.Cu")
		(net "SG")
	)
	(segment
		(start 156.04998 -103.60025)
		(end 153.049986 -103.60025)
		(width 0.381)
		(layer "F.Cu")
		(net "SG")
	)
	(segment
		(start 32.977074 -97.829116)
		(end 33.869884 -97.829116)
		(width 0.381)
		(layer "F.Cu")
		(net "SG")
	)
	(segment
		(start 92.51442 -58.928)
		(end 92.372942 -59.069478)
		(width 0.3048)
		(layer "F.Cu")
		(net "SG")
	)
	(segment
		(start 13.150088 -19.790156)
		(end 13.150088 -18.6944)
		(width 0.254)
		(layer "F.Cu")
		(net "SG")
	)
	(segment
		(start 155.575 -56.515)
		(end 155.9814 -56.9214)
		(width 0.4572)
		(layer "F.Cu")
		(net "SG")
	)
	(segment
		(start 110.363 -19.558)
		(end 111.8362 -19.558)
		(width 0.381)
		(layer "F.Cu")
		(net "SG")
	)
	(segment
		(start 15.7226 -70.866)
		(end 15.7226 -71.0946)
		(width 0.381)
		(layer "F.Cu")
		(net "SG")
	)
	(segment
		(start 14.605 -55.499)
		(end 13.716 -55.499)
		(width 0.3048)
		(layer "F.Cu")
		(net "SG")
	)
	(segment
		(start 105.791 -23.876)
		(end 107.442 -25.527)
		(width 0.381)
		(layer "F.Cu")
		(net "SG")
	)
	(segment
		(start 104.1654 -29.1084)
		(end 104.29875 -29.24175)
		(width 0.381)
		(layer "F.Cu")
		(net "SG")
	)
	(segment
		(start 21.632926 -67.089274)
		(end 20.827746 -67.089274)
		(width 0.254)
		(layer "F.Cu")
		(net "SG")
	)
	(segment
		(start 115.9764 -74.803)
		(end 115.9764 -73.533)
		(width 0.381)
		(layer "F.Cu")
		(net "SG")
	)
	(segment
		(start 146.3548 -95.4278)
		(end 146.3548 -96.6978)
		(width 0.381)
		(layer "F.Cu")
		(net "SG")
	)
	(segment
		(start 157.717998 -34.814002)
		(end 157.988 -34.544)
		(width 0.381)
		(layer "F.Cu")
		(net "SG")
	)
	(segment
		(start 135.382 -22.098)
		(end 134.3914 -22.098)
		(width 0.381)
		(layer "F.Cu")
		(net "SG")
	)
	(segment
		(start 102.84714 -43.823128)
		(end 102.347268 -43.323256)
		(width 0.381)
		(layer "F.Cu")
		(net "SG")
	)
	(segment
		(start 141.05001 -103.60025)
		(end 144.050004 -103.60025)
		(width 0.381)
		(layer "F.Cu")
		(net "SG")
	)
	(segment
		(start 149.848062 -58.014108)
		(end 149.376892 -58.014108)
		(width 0.381)
		(layer "F.Cu")
		(net "SG")
	)
	(segment
		(start 152.2603 -34.814002)
		(end 150.638002 -34.814002)
		(width 0.381)
		(layer "F.Cu")
		(net "SG")
	)
	(segment
		(start 91.518994 -104.10952)
		(end 91.518994 -104.064054)
		(width 0.381)
		(layer "F.Cu")
		(net "SG")
	)
	(segment
		(start 80.2386 -64.1096)
		(end 79.1464 -64.1096)
		(width 0.4572)
		(layer "F.Cu")
		(net "SG")
	)
	(segment
		(start 112.84712 -42.82313)
		(end 113.346992 -42.323258)
		(width 0.381)
		(layer "F.Cu")
		(net "SG")
	)
	(segment
		(start 93.218 -61.275722)
		(end 93.218 -61.529722)
		(width 0.381)
		(layer "F.Cu")
		(net "SG")
	)
	(segment
		(start 21.082 -64.1096)
		(end 21.0566 -64.135)
		(width 0.381)
		(layer "F.Cu")
		(net "SG")
	)
	(segment
		(start 16.0274 -83.984846)
		(end 16.0274 -83.566)
		(width 0.381)
		(layer "F.Cu")
		(net "SG")
	)
	(segment
		(start 134.3914 -22.098)
		(end 134.3914 -23.368)
		(width 0.381)
		(layer "F.Cu")
		(net "SG")
	)
	(segment
		(start 38.59276 -16.84528)
		(end 39.3192 -16.84528)
		(width 0.381)
		(layer "F.Cu")
		(net "SG")
	)
	(segment
		(start 114.847116 -46.823122)
		(end 115.346988 -47.322994)
		(width 0.381)
		(layer "F.Cu")
		(net "SG")
	)
	(segment
		(start 110.363 -19.558)
		(end 110.236 -19.685)
		(width 0.381)
		(layer "F.Cu")
		(net "SG")
	)
	(segment
		(start 94.107 -59.436)
		(end 94.107 -60.5536)
		(width 0.381)
		(layer "F.Cu")
		(net "SG")
	)
	(segment
		(start 21.0566 -64.135)
		(end 20.649184 -64.135)
		(width 0.381)
		(layer "F.Cu")
		(net "SG")
	)
	(segment
		(start 125.2474 -69.2912)
		(end 125.095 -69.1388)
		(width 0.3048)
		(layer "F.Cu")
		(net "SG")
	)
	(segment
		(start 125.1204 -43.688)
		(end 125.1204 -42.545)
		(width 0.381)
		(layer "F.Cu")
		(net "SG")
	)
	(segment
		(start 30.353 -94.615)
		(end 30.353 -95.504)
		(width 0.381)
		(layer "F.Cu")
		(net "SG")
	)
	(segment
		(start 140.2842 -60.6298)
		(end 140.6652 -61.0108)
		(width 0.3048)
		(layer "F.Cu")
		(net "SG")
	)
	(segment
		(start 104.847136 -38.823138)
		(end 104.347264 -38.323266)
		(width 0.381)
		(layer "F.Cu")
		(net "SG")
	)
	(segment
		(start 21.82876 -57.64276)
		(end 21.82876 -57.0611)
		(width 0.381)
		(layer "F.Cu")
		(net "SG")
	)
	(segment
		(start 96.012 -69.469)
		(end 96.266 -69.215)
		(width 0.3048)
		(layer "F.Cu")
		(net "SG")
	)
	(segment
		(start 96.266 -69.215)
		(end 96.9264 -69.215)
		(width 0.3048)
		(layer "F.Cu")
		(net "SG")
	)
	(segment
		(start 105.847134 -41.823132)
		(end 105.347262 -41.32326)
		(width 0.381)
		(layer "F.Cu")
		(net "SG")
	)
	(segment
		(start 116.847112 -40.823134)
		(end 117.346984 -40.323262)
		(width 0.381)
		(layer "F.Cu")
		(net "SG")
	)
	(segment
		(start 105.847134 -43.823128)
		(end 105.347262 -43.323256)
		(width 0.381)
		(layer "F.Cu")
		(net "SG")
	)
	(segment
		(start 77.089 -17.6276)
		(end 76.6826 -17.6276)
		(width 0.381)
		(layer "F.Cu")
		(net "SG")
	)
	(segment
		(start 35.9156 -99.0854)
		(end 36.844478 -99.0854)
		(width 0.3048)
		(layer "F.Cu")
		(net "SG")
	)
	(segment
		(start 104.29875 -29.917898)
		(end 103.759254 -30.457394)
		(width 0.381)
		(layer "F.Cu")
		(net "SG")
	)
	(segment
		(start 91.2368 -102.4128)
		(end 90.5256 -102.4128)
		(width 0.3048)
		(layer "F.Cu")
		(net "SG")
	)
	(segment
		(start 108.847128 -34.822892)
		(end 108.347256 -34.32302)
		(width 0.381)
		(layer "F.Cu")
		(net "SG")
	)
	(segment
		(start 72.649842 -6.823964)
		(end 72.649842 -3.500374)
		(width 0.381)
		(layer "F.Cu")
		(net "SG")
	)
	(segment
		(start 97.2566 -27.5336)
		(end 97.536 -27.813)
		(width 0.381)
		(layer "F.Cu")
		(net "SG")
	)
	(segment
		(start 91.44 -104.3686)
		(end 91.44 -104.188514)
		(width 0.3048)
		(layer "F.Cu")
		(net "SG")
	)
	(segment
		(start 21.209 -64.1096)
		(end 21.082 -64.1096)
		(width 0.381)
		(layer "F.Cu")
		(net "SG")
	)
	(segment
		(start 101.847142 -44.823126)
		(end 101.34727 -45.322998)
		(width 0.381)
		(layer "F.Cu")
		(net "SG")
	)
	(segment
		(start 69.17182 -14.308074)
		(end 69.58076 -14.717014)
		(width 0.3048)
		(layer "F.Cu")
		(net "SG")
	)
	(segment
		(start 69.166486 -7.3406)
		(end 68.64985 -6.823964)
		(width 0.381)
		(layer "F.Cu")
		(net "SG")
	)
	(segment
		(start 29.745432 -100.810568)
		(end 29.718 -100.838)
		(width 0.381)
		(layer "F.Cu")
		(net "SG")
	)
	(segment
		(start 11.557 -30.988)
		(end 11.557 -32.004)
		(width 0.381)
		(layer "F.Cu")
		(net "SG")
	)
	(segment
		(start 102.84714 -36.823142)
		(end 102.347268 -36.32327)
		(width 0.381)
		(layer "F.Cu")
		(net "SG")
	)
	(segment
		(start 109.7788 -25.1968)
		(end 110.109 -25.527)
		(width 0.381)
		(layer "F.Cu")
		(net "SG")
	)
	(segment
		(start 67.649852 -6.823964)
		(end 67.649852 -3.500374)
		(width 0.381)
		(layer "F.Cu")
		(net "SG")
	)
	(segment
		(start 99.8982 -78.5368)
		(end 99.8982 -79.375)
		(width 0.3048)
		(layer "F.Cu")
		(net "SG")
	)
	(segment
		(start 91.764104 -44.335446)
		(end 91.5416 -44.335446)
		(width 0.381)
		(layer "F.Cu")
		(net "SG")
	)
	(segment
		(start 92.898722 -61.849)
		(end 91.694 -61.849)
		(width 0.381)
		(layer "F.Cu")
		(net "SG")
	)
	(segment
		(start 97.42932 -26.2636)
		(end 97.155 -26.2636)
		(width 0.381)
		(layer "F.Cu")
		(net "SG")
	)
	(segment
		(start 158.078424 -76.581)
		(end 160.909 -76.581)
		(width 0.381)
		(layer "F.Cu")
		(net "SG")
	)
	(segment
		(start 32.274256 -91.710256)
		(end 32.274256 -90.8812)
		(width 0.254)
		(layer "F.Cu")
		(net "SG")
	)
	(segment
		(start 83.439 -65.7606)
		(end 83.439 -64.8462)
		(width 0.381)
		(layer "F.Cu")
		(net "SG")
	)
	(segment
		(start 25.774142 -78.111858)
		(end 25.774142 -79.248)
		(width 0.254)
		(layer "F.Cu")
		(net "SG")
	)
	(segment
		(start 138.165078 -16.129)
		(end 138.165078 -15.377922)
		(width 0.254)
		(layer "F.Cu")
		(net "SG")
	)
	(segment
		(start 92.709746 -58.293)
		(end 93.218 -58.801254)
		(width 0.381)
		(layer "F.Cu")
		(net "SG")
	)
	(segment
		(start 15.113 -91.3384)
		(end 16.129 -91.3384)
		(width 0.381)
		(layer "F.Cu")
		(net "SG")
	)
	(segment
		(start 90.9828 -73.6092)
		(end 90.1192 -73.6092)
		(width 0.3048)
		(layer "F.Cu")
		(net "SG")
	)
	(segment
		(start 96.9264 -68.072)
		(end 96.9264 -69.215)
		(width 0.381)
		(layer "F.Cu")
		(net "SG")
	)
	(segment
		(start 103.9368 -25.527)
		(end 104.648 -25.527)
		(width 0.381)
		(layer "F.Cu")
		(net "SG")
	)
	(segment
		(start 143.1798 -89.5096)
		(end 143.1798 -90.6526)
		(width 0.381)
		(layer "F.Cu")
		(net "SG")
	)
	(segment
		(start 111.847122 -41.823132)
		(end 112.346994 -41.32326)
		(width 0.381)
		(layer "F.Cu")
		(net "SG")
	)
	(segment
		(start 138.050016 -103.60025)
		(end 136.779 -103.60025)
		(width 0.381)
		(layer "F.Cu")
		(net "SG")
	)
	(segment
		(start 15.875 -27.5336)
		(end 15.875 -26.924)
		(width 0.381)
		(layer "F.Cu")
		(net "SG")
	)
	(segment
		(start 113.284 -25.0698)
		(end 112.8268 -25.527)
		(width 0.381)
		(layer "F.Cu")
		(net "SG")
	)
	(segment
		(start 154.2034 -56.515)
		(end 155.575 -56.515)
		(width 0.4572)
		(layer "F.Cu")
		(net "SG")
	)
	(segment
		(start 27.94 -92.456)
		(end 27.774138 -92.290138)
		(width 0.254)
		(layer "F.Cu")
		(net "SG")
	)
	(segment
		(start 113.847118 -43.823128)
		(end 114.34699 -43.323256)
		(width 0.381)
		(layer "F.Cu")
		(net "SG")
	)
	(segment
		(start 75.819 -46.863)
		(end 75.819 -46.99)
		(width 0.254)
		(layer "F.Cu")
		(net "SG")
	)
	(segment
		(start 27.274266 -90.8812)
		(end 27.274266 -92.232734)
		(width 0.254)
		(layer "F.Cu")
		(net "SG")
	)
	(segment
		(start 90.17 -61.595)
		(end 91.44 -61.595)
		(width 0.381)
		(layer "F.Cu")
		(net "SG")
	)
	(segment
		(start 30.099 -95.758)
		(end 30.099 -96.266)
		(width 0.381)
		(layer "F.Cu")
		(net "SG")
	)
	(segment
		(start 18.405348 -24.892)
		(end 18.710148 -24.5872)
		(width 0.3048)
		(layer "F.Cu")
		(net "SG")
	)
	(segment
		(start 124.60732 -32.0802)
		(end 124.63272 -32.1056)
		(width 0.381)
		(layer "F.Cu")
		(net "SG")
	)
	(segment
		(start 115.6716 -81.788)
		(end 116.713 -81.788)
		(width 0.381)
		(layer "F.Cu")
		(net "SG")
	)
	(segment
		(start 121.578624 -93.27007)
		(end 120.72747 -93.27007)
		(width 0.381)
		(layer "F.Cu")
		(net "SG")
	)
	(segment
		(start 35.591242 -99.409758)
		(end 35.9156 -99.0854)
		(width 0.3048)
		(layer "F.Cu")
		(net "SG")
	)
	(segment
		(start 105.00487 -19.105118)
		(end 103.632 -19.105118)
		(width 0.381)
		(layer "F.Cu")
		(net "SG")
	)
	(segment
		(start 34.147506 -100.853494)
		(end 32.258 -100.853494)
		(width 0.381)
		(layer "F.Cu")
		(net "SG")
	)
	(segment
		(start 80.2386 -59.5376)
		(end 79.248 -59.5376)
		(width 0.381)
		(layer "F.Cu")
		(net "SG")
	)
	(segment
		(start 21.896578 -51.614578)
		(end 21.896578 -53.1114)
		(width 0.381)
		(layer "F.Cu")
		(net "SG")
	)
	(segment
		(start 104.1654 -25.7556)
		(end 104.1654 -29.1084)
		(width 0.381)
		(layer "F.Cu")
		(net "SG")
	)
	(segment
		(start 106.847132 -40.823134)
		(end 106.34726 -40.323262)
		(width 0.381)
		(layer "F.Cu")
		(net "SG")
	)
	(segment
		(start 119.847106 -41.823386)
		(end 119.847106 -41.823132)
		(width 0.381)
		(layer "F.Cu")
		(net "SG")
	)
	(segment
		(start 115.9764 -73.533)
		(end 116.84 -73.533)
		(width 0.381)
		(layer "F.Cu")
		(net "SG")
	)
	(segment
		(start 29.591 -97.028)
		(end 30.099 -96.52)
		(width 0.381)
		(layer "F.Cu")
		(net "SG")
	)
	(segment
		(start 112.84712 -44.823126)
		(end 113.346992 -45.322998)
		(width 0.381)
		(layer "F.Cu")
		(net "SG")
	)
	(segment
		(start 11.938 -25.4)
		(end 12.790678 -25.4)
		(width 0.254)
		(layer "F.Cu")
		(net "SG")
	)
	(segment
		(start 76.6826 -17.6276)
		(end 76.12888 -17.07388)
		(width 0.381)
		(layer "F.Cu")
		(net "SG")
	)
	(segment
		(start 100.965 -79.4766)
		(end 101.1428 -79.2988)
		(width 0.3048)
		(layer "F.Cu")
		(net "SG")
	)
	(segment
		(start 113.156746 -73.533)
		(end 112.924082 -73.300336)
		(width 0.3048)
		(layer "F.Cu")
		(net "SG")
	)
	(segment
		(start 108.847128 -41.823132)
		(end 108.347256 -41.32326)
		(width 0.381)
		(layer "F.Cu")
		(net "SG")
	)
	(segment
		(start 4.445 -23.114)
		(end 5.2197 -23.8887)
		(width 0.381)
		(layer "F.Cu")
		(net "SG")
	)
	(segment
		(start 15.3924 -41.84523)
		(end 15.3924 -40.9448)
		(width 0.381)
		(layer "F.Cu")
		(net "SG")
	)
	(segment
		(start 98.846894 -39.823136)
		(end 98.347022 -39.323264)
		(width 0.381)
		(layer "F.Cu")
		(net "SG")
	)
	(segment
		(start 111.847122 -43.823128)
		(end 112.346994 -43.323256)
		(width 0.381)
		(layer "F.Cu")
		(net "SG")
	)
	(segment
		(start 122.174 -17.9578)
		(end 122.174 -18.29054)
		(width 0.381)
		(layer "F.Cu")
		(net "SG")
	)
	(segment
		(start 142.2654 -99.441)
		(end 142.2654 -98.8441)
		(width 0.381)
		(layer "F.Cu")
		(net "SG")
	)
	(segment
		(start 104.7369 -101.9175)
		(end 105.2576 -102.4382)
		(width 0.3048)
		(layer "F.Cu")
		(net "SG")
	)
	(segment
		(start 100.645722 -70.4596)
		(end 101.2952 -70.4596)
		(width 0.3048)
		(layer "F.Cu")
		(net "SG")
	)
	(segment
		(start 115.847114 -53.823108)
		(end 116.346986 -54.32298)
		(width 0.381)
		(layer "F.Cu")
		(net "SG")
	)
	(segment
		(start 102.84714 -39.823136)
		(end 102.347268 -39.323264)
		(width 0.381)
		(layer "F.Cu")
		(net "SG")
	)
	(segment
		(start 30.776926 -100.810568)
		(end 32.215074 -100.810568)
		(width 0.381)
		(layer "F.Cu")
		(net "SG")
	)
	(segment
		(start 100.84689 -35.82289)
		(end 100.347018 -35.323018)
		(width 0.381)
		(layer "F.Cu")
		(net "SG")
	)
	(segment
		(start 98.846894 -34.822892)
		(end 98.347022 -34.32302)
		(width 0.381)
		(layer "F.Cu")
		(net "SG")
	)
	(segment
		(start 141.05001 -103.60025)
		(end 138.050016 -103.60025)
		(width 0.381)
		(layer "F.Cu")
		(net "SG")
	)
	(segment
		(start 95.631 -18.415)
		(end 94.869 -19.177)
		(width 0.381)
		(layer "F.Cu")
		(net "SG")
	)
	(segment
		(start 109.0676 -27.305)
		(end 109.8423 -28.0797)
		(width 0.381)
		(layer "F.Cu")
		(net "SG")
	)
	(segment
		(start 125.795278 -70.5358)
		(end 124.9172 -70.5358)
		(width 0.3048)
		(layer "F.Cu")
		(net "SG")
	)
	(segment
		(start 11.4808 -60.1472)
		(end 10.668 -60.1472)
		(width 0.381)
		(layer "F.Cu")
		(net "SG")
	)
	(segment
		(start 86.995 -59.025536)
		(end 87.668608 -59.025536)
		(width 0.254)
		(layer "F.Cu")
		(net "SG")
	)
	(segment
		(start 82.230976 -70.231)
		(end 79.883 -70.231)
		(width 0.381)
		(layer "F.Cu")
		(net "SG")
	)
	(segment
		(start 30.776926 -99.528884)
		(end 30.776926 -100.810568)
		(width 0.381)
		(layer "F.Cu")
		(net "SG")
	)
	(segment
		(start 97.536 -26.15692)
		(end 97.42932 -26.2636)
		(width 0.381)
		(layer "F.Cu")
		(net "SG")
	)
	(segment
		(start 80.2386 -64.1096)
		(end 80.2386 -62.9666)
		(width 0.4572)
		(layer "F.Cu")
		(net "SG")
	)
	(segment
		(start 152.146 -23.495)
		(end 152.146 -23.876)
		(width 0.381)
		(layer "F.Cu")
		(net "SG")
	)
	(segment
		(start 29.337 -98.806)
		(end 29.591 -98.552)
		(width 0.381)
		(layer "F.Cu")
		(net "SG")
	)
	(segment
		(start 13.150088 -48.790098)
		(end 13.150088 -47.748698)
		(width 0.254)
		(layer "F.Cu")
		(net "SG")
	)
	(segment
		(start 106.847132 -42.82313)
		(end 106.34726 -42.323258)
		(width 0.381)
		(layer "F.Cu")
		(net "SG")
	)
	(segment
		(start 32.766 -92.71)
		(end 32.766 -94.107)
		(width 0.381)
		(layer "F.Cu")
		(net "SG")
	)
	(segment
		(start 91.44 -102.2096)
		(end 91.2368 -102.4128)
		(width 0.3048)
		(layer "F.Cu")
		(net "SG")
	)
	(segment
		(start 115.5954 -83.058)
		(end 115.6716 -82.9818)
		(width 0.381)
		(layer "F.Cu")
		(net "SG")
	)
	(segment
		(start 104.7369 -100.8761)
		(end 104.2162 -101.3968)
		(width 0.3048)
		(layer "F.Cu")
		(net "SG")
	)
	(segment
		(start 26.289 -77.597)
		(end 25.774142 -78.111858)
		(width 0.254)
		(layer "F.Cu")
		(net "SG")
	)
	(segment
		(start 30.48 -94.361)
		(end 30.48 -94.488)
		(width 0.381)
		(layer "F.Cu")
		(net "SG")
	)
	(segment
		(start 33.869884 -97.829116)
		(end 34.417 -97.282)
		(width 0.381)
		(layer "F.Cu")
		(net "SG")
	)
	(segment
		(start 103.9368 -24.8666)
		(end 103.9368 -25.527)
		(width 0.3048)
		(layer "F.Cu")
		(net "SG")
	)
	(segment
		(start 95.7326 -25.442672)
		(end 95.716852 -25.45842)
		(width 0.381)
		(layer "F.Cu")
		(net "SG")
	)
	(segment
		(start 113.90122 -22.74316)
		(end 114.3 -23.14194)
		(width 0.381)
		(layer "F.Cu")
		(net "SG")
	)
	(segment
		(start 105.059988 -22.448012)
		(end 105.059988 -19.05)
		(width 0.381)
		(layer "F.Cu")
		(net "SG")
	)
	(segment
		(start 56.3372 -73.533)
		(end 56.3372 -74.4474)
		(width 0.381)
		(layer "F.Cu")
		(net "SG")
	)
	(segment
		(start 143.383 -96.266)
		(end 143.036798 -95.919798)
		(width 0.2032)
		(layer "F.Cu")
		(net "SG")
	)
	(segment
		(start 104.648 -25.527)
		(end 105.029 -25.146)
		(width 0.381)
		(layer "F.Cu")
		(net "SG")
	)
	(segment
		(start 142.2654 -98.8441)
		(end 142.2908 -98.8187)
		(width 0.381)
		(layer "F.Cu")
		(net "SG")
	)
	(segment
		(start 106.045 -88.45296)
		(end 106.045 -89.408)
		(width 0.381)
		(layer "F.Cu")
		(net "SG")
	)
	(segment
		(start 117.84711 -47.82312)
		(end 118.346982 -48.322992)
		(width 0.381)
		(layer "F.Cu")
		(net "SG")
	)
	(segment
		(start 113.90122 -22.74316)
		(end 113.90122 -20.35048)
		(width 0.381)
		(layer "F.Cu")
		(net "SG")
	)
	(segment
		(start 86.741 -59.279536)
		(end 86.995 -59.025536)
		(width 0.254)
		(layer "F.Cu")
		(net "SG")
	)
	(segment
		(start 105.2576 -100.3554)
		(end 105.2576 -98.98126)
		(width 0.3048)
		(layer "F.Cu")
		(net "SG")
	)
	(segment
		(start 134.8105 -65.77965)
		(end 134.7089 -65.67805)
		(width 0.381)
		(layer "F.Cu")
		(net "SG")
	)
	(segment
		(start 139.838176 -76.7334)
		(end 137.859262 -76.7334)
		(width 0.381)
		(layer "F.Cu")
		(net "SG")
	)
	(segment
		(start 16.5354 -71.9074)
		(end 17.018 -71.9074)
		(width 0.381)
		(layer "F.Cu")
		(net "SG")
	)
	(segment
		(start 24.136096 -84.814664)
		(end 22.7076 -84.814664)
		(width 0.254)
		(layer "F.Cu")
		(net "SG")
	)
	(segment
		(start 101.847142 -45.823124)
		(end 101.34727 -46.322996)
		(width 0.381)
		(layer "F.Cu")
		(net "SG")
	)
	(segment
		(start 86.856062 -60.452)
		(end 86.602062 -60.198)
		(width 0.254)
		(layer "F.Cu")
		(net "SG")
	)
	(segment
		(start 112.924082 -73.300336)
		(end 112.26165 -73.300336)
		(width 0.3048)
		(layer "F.Cu")
		(net "SG")
	)
	(segment
		(start 43.550078 -73.66)
		(end 42.926 -73.66)
		(width 0.254)
		(layer "F.Cu")
		(net "SG")
	)
	(segment
		(start 113.792 -29.464)
		(end 112.940846 -29.464)
		(width 0.381)
		(layer "F.Cu")
		(net "SG")
	)
	(segment
		(start 98.846894 -43.823128)
		(end 98.347022 -43.323256)
		(width 0.381)
		(layer "F.Cu")
		(net "SG")
	)
	(segment
		(start 53.467 -16.1544)
		(end 54.61 -16.1544)
		(width 0.381)
		(layer "F.Cu")
		(net "SG")
	)
	(segment
		(start 103.759254 -30.457394)
		(end 103.400606 -30.457394)
		(width 0.381)
		(layer "F.Cu")
		(net "SG")
	)
	(segment
		(start 103.400606 -30.457394)
		(end 103.378 -30.48)
		(width 0.381)
		(layer "F.Cu")
		(net "SG")
	)
	(segment
		(start 31.77413 -79.248)
		(end 31.77413 -77.74813)
		(width 0.254)
		(layer "F.Cu")
		(net "SG")
	)
	(segment
		(start 146.3548 -90.6018)
		(end 147.3962 -90.6018)
		(width 0.381)
		(layer "F.Cu")
		(net "SG")
	)
	(segment
		(start 112.940846 -29.464)
		(end 112.7887 -29.616146)
		(width 0.381)
		(layer "F.Cu")
		(net "SG")
	)
	(segment
		(start 70.354444 -45.496734)
		(end 71.6788 -45.496734)
		(width 0.254)
		(layer "F.Cu")
		(net "SG")
	)
	(segment
		(start 140.2842 -60.400946)
		(end 140.2842 -60.6298)
		(width 0.3048)
		(layer "F.Cu")
		(net "SG")
	)
	(segment
		(start 122.174 -18.29054)
		(end 122.690382 -18.806922)
		(width 0.381)
		(layer "F.Cu")
		(net "SG")
	)
	(segment
		(start 96.393 -18.415)
		(end 95.631 -18.415)
		(width 0.381)
		(layer "F.Cu")
		(net "SG")
	)
	(segment
		(start 120.72747 -93.27007)
		(end 119.7356 -92.2782)
		(width 0.381)
		(layer "F.Cu")
		(net "SG")
	)
	(segment
		(start 12.358878 -68.961)
		(end 12.319 -68.961)
		(width 0.254)
		(layer "F.Cu")
		(net "SG")
	)
	(segment
		(start 47.83328 -18.796)
		(end 48.80864 -19.77136)
		(width 0.381)
		(layer "F.Cu")
		(net "SG")
	)
	(segment
		(start 22.0472 -57.8612)
		(end 21.82876 -57.64276)
		(width 0.381)
		(layer "F.Cu")
		(net "SG")
	)
	(segment
		(start 32.215074 -100.810568)
		(end 32.258 -100.853494)
		(width 0.381)
		(layer "F.Cu")
		(net "SG")
	)
	(segment
		(start 104.847136 -44.823126)
		(end 104.347264 -45.322998)
		(width 0.381)
		(layer "F.Cu")
		(net "SG")
	)
	(segment
		(start 98.846894 -44.823126)
		(end 98.347022 -45.322998)
		(width 0.381)
		(layer "F.Cu")
		(net "SG")
	)
	(segment
		(start 140.1318 -65.1002)
		(end 139.838176 -65.393824)
		(width 0.381)
		(layer "F.Cu")
		(net "SG")
	)
	(segment
		(start 15.93977 -84.090002)
		(end 15.93977 -84.072476)
		(width 0.381)
		(layer "F.Cu")
		(net "SG")
	)
	(segment
		(start 119.847106 -51.823112)
		(end 120.346978 -52.322984)
		(width 0.381)
		(layer "F.Cu")
		(net "SG")
	)
	(segment
		(start 106.426 -19.685)
		(end 105.791 -20.32)
		(width 0.381)
		(layer "F.Cu")
		(net "SG")
	)
	(segment
		(start 101.2952 -70.4596)
		(end 101.5492 -70.7136)
		(width 0.3048)
		(layer "F.Cu")
		(net "SG")
	)
	(segment
		(start 62.133226 -7.3406)
		(end 62.649862 -6.823964)
		(width 0.381)
		(layer "F.Cu")
		(net "SG")
	)
	(segment
		(start 23.1394 -17.5514)
		(end 24.3205 -17.5514)
		(width 0.381)
		(layer "F.Cu")
		(net "SG")
	)
	(segment
		(start 118.847108 -54.823106)
		(end 119.34698 -55.322978)
		(width 0.381)
		(layer "F.Cu")
		(net "SG")
	)
	(segment
		(start 150.049992 -103.60025)
		(end 147.049998 -103.60025)
		(width 0.381)
		(layer "F.Cu")
		(net "SG")
	)
	(segment
		(start 21.7424 -66.9798)
		(end 21.632926 -67.089274)
		(width 0.254)
		(layer "F.Cu")
		(net "SG")
	)
	(segment
		(start 150.638002 -34.814002)
		(end 150.368 -34.544)
		(width 0.381)
		(layer "F.Cu")
		(net "SG")
	)
	(segment
		(start 82.230976 -72.771)
		(end 83.439 -72.771)
		(width 0.381)
		(layer "F.Cu")
		(net "SG")
	)
	(segment
		(start 155.9814 -57.8612)
		(end 155.9814 -56.9214)
		(width 0.4572)
		(layer "F.Cu")
		(net "SG")
	)
	(segment
		(start 93.218 -58.928)
		(end 92.51442 -58.928)
		(width 0.3048)
		(layer "F.Cu")
		(net "SG")
	)
	(segment
		(start 92.372942 -61.275722)
		(end 93.218 -61.275722)
		(width 0.3048)
		(layer "F.Cu")
		(net "SG")
	)
	(segment
		(start 91.01074 -103.5558)
		(end 90.5256 -103.5558)
		(width 0.381)
		(layer "F.Cu")
		(net "SG")
	)
	(segment
		(start 20.827746 -67.5894)
		(end 20.128992 -67.5894)
		(width 0.254)
		(layer "F.Cu")
		(net "SG")
	)
	(segment
		(start 81.762346 -87.122)
		(end 82.408268 -86.476078)
		(width 0.3048)
		(layer "F.Cu")
		(net "SG")
	)
	(segment
		(start 112.84712 -40.823134)
		(end 113.346992 -40.323262)
		(width 0.381)
		(layer "F.Cu")
		(net "SG")
	)
	(segment
		(start 15.875 -26.924)
		(end 15.5956 -26.6446)
		(width 0.381)
		(layer "F.Cu")
		(net "SG")
	)
	(segment
		(start 135.3312 -66.3194)
		(end 134.8105 -65.7987)
		(width 0.381)
		(layer "F.Cu")
		(net "SG")
	)
	(segment
		(start 112.1156 -20.920964)
		(end 112.1156 -19.8374)
		(width 0.381)
		(layer "F.Cu")
		(net "SG")
	)
	(segment
		(start 134.7089 -65.67805)
		(end 134.7089 -65.39992)
		(width 0.381)
		(layer "F.Cu")
		(net "SG")
	)
	(segment
		(start 100.6856 -25.527)
		(end 99.06 -25.527)
		(width 0.381)
		(layer "F.Cu")
		(net "SG")
	)
	(segment
		(start 115.5954 -83.058)
		(end 116.332 -83.058)
		(width 0.381)
		(layer "F.Cu")
		(net "SG")
	)
	(segment
		(start 96.7486 -18.0594)
		(end 96.393 -18.415)
		(width 0.381)
		(layer "F.Cu")
		(net "SG")
	)
	(segment
		(start 97.282 -86.741)
		(end 96.52 -85.979)
		(width 0.3048)
		(layer "F.Cu")
		(net "SG")
	)
	(segment
		(start 103.9368 -25.527)
		(end 104.1654 -25.7556)
		(width 0.381)
		(layer "F.Cu")
		(net "SG")
	)
	(segment
		(start 29.337 -100.457)
		(end 29.337 -98.806)
		(width 0.381)
		(layer "F.Cu")
		(net "SG")
	)
	(segment
		(start 13.716 -55.499)
		(end 13.2334 -55.0164)
		(width 0.3048)
		(layer "F.Cu")
		(net "SG")
	)
	(segment
		(start 114.3 -23.14194)
		(end 114.3 -24.765)
		(width 0.381)
		(layer "F.Cu")
		(net "SG")
	)
	(segment
		(start 13.2334 -55.0164)
		(end 13.117322 -55.0164)
		(width 0.3048)
		(layer "F.Cu")
		(net "SG")
	)
	(segment
		(start 137.859262 -76.7334)
		(end 137.501884 -77.090778)
		(width 0.381)
		(layer "F.Cu")
		(net "SG")
	)
	(segment
		(start 114.3 -27.4828)
		(end 114.3 -28.956)
		(width 0.381)
		(layer "F.Cu")
		(net "SG")
	)
	(segment
		(start 97.0534 -27.5336)
		(end 97.2566 -27.5336)
		(width 0.381)
		(layer "F.Cu")
		(net "SG")
	)
	(segment
		(start 26.543 -77.597)
		(end 26.289 -77.597)
		(width 0.254)
		(layer "F.Cu")
		(net "SG")
	)
	(segment
		(start 113.847118 -39.823136)
		(end 114.34699 -39.323264)
		(width 0.381)
		(layer "F.Cu")
		(net "SG")
	)
	(segment
		(start 79.248 -55.118)
		(end 79.4004 -54.9656)
		(width 0.381)
		(layer "F.Cu")
		(net "SG")
	)
	(segment
		(start 104.847136 -42.82313)
		(end 104.347264 -42.323258)
		(width 0.381)
		(layer "F.Cu")
		(net "SG")
	)
	(segment
		(start 100.6856 -24.638)
		(end 100.6856 -25.527)
		(width 0.3048)
		(layer "F.Cu")
		(net "SG")
	)
	(segment
		(start 103.847138 -37.82314)
		(end 103.347266 -37.323268)
		(width 0.381)
		(layer "F.Cu")
		(net "SG")
	)
	(segment
		(start 18.161 -62.0776)
		(end 18.161 -62.9412)
		(width 0.381)
		(layer "F.Cu")
		(net "SG")
	)
	(segment
		(start 146.3548 -89.3318)
		(end 146.3548 -90.6018)
		(width 0.381)
		(layer "F.Cu")
		(net "SG")
	)
	(segment
		(start 34.417 -100.584)
		(end 34.417 -99.187)
		(width 0.381)
		(layer "F.Cu")
		(net "SG")
	)
	(segment
		(start 105.847134 -53.823108)
		(end 105.347262 -54.32298)
		(width 0.381)
		(layer "F.Cu")
		(net "SG")
	)
	(segment
		(start 26.274268 -90.8812)
		(end 26.274268 -92.343732)
		(width 0.254)
		(layer "F.Cu")
		(net "SG")
	)
	(segment
		(start 139.954 -59.700922)
		(end 139.954 -60.070746)
		(width 0.3048)
		(layer "F.Cu")
		(net "SG")
	)
	(segment
		(start 109.8423 -28.0797)
		(end 109.8423 -28.5242)
		(width 0.381)
		(layer "F.Cu")
		(net "SG")
	)
	(segment
		(start 104.267 -77.47)
		(end 104.684322 -77.887322)
		(width 0.381)
		(layer "F.Cu")
		(net "SG")
	)
	(segment
		(start 11.2522 -17.5006)
		(end 12.0904 -17.5006)
		(width 0.381)
		(layer "F.Cu")
		(net "SG")
	)
	(segment
		(start 111.847122 -35.82289)
		(end 112.346994 -35.323018)
		(width 0.381)
		(layer "F.Cu")
		(net "SG")
	)
	(segment
		(start 105.059988 -19.05)
		(end 105.029 -19.019012)
		(width 0.381)
		(layer "F.Cu")
		(net "SG")
	)
	(segment
		(start 113.847118 -41.823132)
		(end 114.34699 -41.32326)
		(width 0.381)
		(layer "F.Cu")
		(net "SG")
	)
	(segment
		(start 112.141 -19.812)
		(end 112.1156 -19.8374)
		(width 0.381)
		(layer "F.Cu")
		(net "SG")
	)
	(segment
		(start 34.417 -99.187)
		(end 34.417 -97.282)
		(width 0.381)
		(layer "F.Cu")
		(net "SG")
	)
	(segment
		(start 93.995494 -19.812)
		(end 93.091 -20.716494)
		(width 0.381)
		(layer "F.Cu")
		(net "SG")
	)
	(segment
		(start 105.029 -22.479)
		(end 105.059988 -22.448012)
		(width 0.381)
		(layer "F.Cu")
		(net "SG")
	)
	(segment
		(start 100.6856 -29.8196)
		(end 100.6856 -25.527)
		(width 0.381)
		(layer "F.Cu")
		(net "SG")
	)
	(segment
		(start 111.6584 -99.441)
		(end 111.6584 -100.711)
		(width 0.381)
		(layer "F.Cu")
		(net "SG")
	)
	(segment
		(start 146.3548 -95.4278)
		(end 147.3962 -95.4278)
		(width 0.381)
		(layer "F.Cu")
		(net "SG")
	)
	(segment
		(start 80.2386 -64.1096)
		(end 80.2386 -65.2526)
		(width 0.4572)
		(layer "F.Cu")
		(net "SG")
	)
	(segment
		(start 96.4946 -26.924)
		(end 96.4692 -26.924)
		(width 0.381)
		(layer "F.Cu")
		(net "SG")
	)
	(segment
		(start 13.150088 -34.29)
		(end 13.150088 -33.147)
		(width 0.254)
		(layer "F.Cu")
		(net "SG")
	)
	(segment
		(start 112.4204 -95.123)
		(end 113.284 -95.123)
		(width 0.381)
		(layer "F.Cu")
		(net "SG")
	)
	(segment
		(start 21.7805 -51.4985)
		(end 21.896578 -51.614578)
		(width 0.381)
		(layer "F.Cu")
		(net "SG")
	)
	(segment
		(start 101.346 -30.48)
		(end 100.6856 -29.8196)
		(width 0.381)
		(layer "F.Cu")
		(net "SG")
	)
	(segment
		(start 105.2576 -102.4382)
		(end 105.2576 -103.81234)
		(width 0.3048)
		(layer "F.Cu")
		(net "SG")
	)
	(segment
		(start 105.059988 -19.05)
		(end 105.00487 -19.105118)
		(width 0.381)
		(layer "F.Cu")
		(net "SG")
	)
	(segment
		(start 110.847124 -40.823134)
		(end 111.346996 -40.323262)
		(width 0.381)
		(layer "F.Cu")
		(net "SG")
	)
	(segment
		(start 104.648 -18.0594)
		(end 96.7486 -18.0594)
		(width 0.381)
		(layer "F.Cu")
		(net "SG")
	)
	(segment
		(start 110.847124 -48.823118)
		(end 111.346996 -49.32299)
		(width 0.3048)
		(layer "F.Cu")
		(net "SG")
	)
	(segment
		(start 110.236 -19.685)
		(end 107.188 -19.685)
		(width 0.381)
		(layer "F.Cu")
		(net "SG")
	)
	(segment
		(start 22.268434 -65.5574)
		(end 22.1996 -65.5574)
		(width 0.381)
		(layer "F.Cu")
		(net "SG")
	)
	(segment
		(start 27.274266 -92.232734)
		(end 27.051 -92.456)
		(width 0.254)
		(layer "F.Cu")
		(net "SG")
	)
	(segment
		(start 111.847122 -45.823124)
		(end 112.346994 -46.322996)
		(width 0.381)
		(layer "F.Cu")
		(net "SG")
	)
	(segment
		(start 120.269 -89.0016)
		(end 119.634 -88.3666)
		(width 0.381)
		(layer "F.Cu")
		(net "SG")
	)
	(segment
		(start 5.2197 -52.8447)
		(end 5.2197 -53.2511)
		(width 0.381)
		(layer "F.Cu")
		(net "SG")
	)
	(segment
		(start 109.847126 -41.823132)
		(end 110.346998 -41.32326)
		(width 0.381)
		(layer "F.Cu")
		(net "SG")
	)
	(segment
		(start 26.274268 -92.343732)
		(end 26.162 -92.456)
		(width 0.254)
		(layer "F.Cu")
		(net "SG")
	)
	(segment
		(start 105.847134 -33.822894)
		(end 105.347262 -33.323022)
		(width 0.381)
		(layer "F.Cu")
		(net "SG")
	)
	(segment
		(start 92.285058 -44.8564)
		(end 91.764104 -44.335446)
		(width 0.381)
		(layer "F.Cu")
		(net "SG")
	)
	(segment
		(start 89.05113 -49.78273)
		(end 89.05113 -49.253394)
		(width 0.2032)
		(layer "F.Cu")
		(net "SG")
	)
	(segment
		(start 109.847126 -39.823136)
		(end 110.346998 -39.323264)
		(width 0.381)
		(layer "F.Cu")
		(net "SG")
	)
	(segment
		(start 142.2908 -98.8187)
		(end 142.2908 -98.171)
		(width 0.381)
		(layer "F.Cu")
		(net "SG")
	)
	(segment
		(start 102.84714 -37.82314)
		(end 102.347268 -37.323268)
		(width 0.381)
		(layer "F.Cu")
		(net "SG")
	)
	(segment
		(start 68.967604 -46.996604)
		(end 68.834 -46.863)
		(width 0.254)
		(layer "F.Cu")
		(net "SG")
	)
	(segment
		(start 30.099 -96.52)
		(end 30.099 -96.266)
		(width 0.381)
		(layer "F.Cu")
		(net "SG")
	)
	(segment
		(start 114.3 -24.765)
		(end 114.681 -25.146)
		(width 0.381)
		(layer "F.Cu")
		(net "SG")
	)
	(segment
		(start 101.1428 -79.2988)
		(end 101.1428 -78.750922)
		(width 0.3048)
		(layer "F.Cu")
		(net "SG")
	)
	(segment
		(start 108.220002 -28.337002)
		(end 108.220002 -26.305002)
		(width 0.381)
		(layer "F.Cu")
		(net "SG")
	)
	(segment
		(start 104.847136 -40.823134)
		(end 104.347264 -40.323262)
		(width 0.381)
		(layer "F.Cu")
		(net "SG")
	)
	(segment
		(start 96.5962 -27.051)
		(end 96.5962 -27.0764)
		(width 0.381)
		(layer "F.Cu")
		(net "SG")
	)
	(segment
		(start 16.256 -56.6166)
		(end 17.145 -56.6166)
		(width 0.381)
		(layer "F.Cu")
		(net "SG")
	)
	(segment
		(start 32.766 -92.202)
		(end 32.274256 -91.710256)
		(width 0.254)
		(layer "F.Cu")
		(net "SG")
	)
	(segment
		(start 91.694 -61.849)
		(end 91.567 -61.722)
		(width 0.381)
		(layer "F.Cu")
		(net "SG")
	)
	(segment
		(start 114.847116 -36.823142)
		(end 115.346988 -36.32327)
		(width 0.381)
		(layer "F.Cu")
		(net "SG")
	)
	(segment
		(start 139.838176 -65.393824)
		(end 139.838176 -66.5734)
		(width 0.381)
		(layer "F.Cu")
		(net "SG")
	)
	(segment
		(start 104.847136 -46.823122)
		(end 104.347264 -47.322994)
		(width 0.381)
		(layer "F.Cu")
		(net "SG")
	)
	(segment
		(start 93.853 -66.7131)
		(end 93.853 -67.945)
		(width 0.381)
		(layer "F.Cu")
		(net "SG")
	)
	(segment
		(start 62.649862 -6.823964)
		(end 62.649862 -3.500374)
		(width 0.381)
		(layer "F.Cu")
		(net "SG")
	)
	(segment
		(start 93.218 -61.529722)
		(end 92.898722 -61.849)
		(width 0.381)
		(layer "F.Cu")
		(net "SG")
	)
	(segment
		(start 98.99142 -25.45842)
		(end 95.716852 -25.45842)
		(width 0.381)
		(layer "F.Cu")
		(net "SG")
	)
	(segment
		(start 111.6584 -101.981)
		(end 112.522 -101.981)
		(width 0.381)
		(layer "F.Cu")
		(net "SG")
	)
	(segment
		(start 100.84689 -42.82313)
		(end 100.347018 -42.323258)
		(width 0.381)
		(layer "F.Cu")
		(net "SG")
	)
	(segment
		(start 22.281642 -65.544192)
		(end 22.268434 -65.5574)
		(width 0.381)
		(layer "F.Cu")
		(net "SG")
	)
	(segment
		(start 20.649184 -64.135)
		(end 20.357592 -64.426592)
		(width 0.381)
		(layer "F.Cu")
		(net "SG")
	)
	(segment
		(start 94.869 -25.06345)
		(end 95.26397 -25.45842)
		(width 0.381)
		(layer "F.Cu")
		(net "SG")
	)
	(segment
		(start 112.4204 -95.123)
		(end 112.4204 -96.266)
		(width 0.381)
		(layer "F.Cu")
		(net "SG")
	)
	(segment
		(start 105.791 -20.32)
		(end 105.791 -23.876)
		(width 0.381)
		(layer "F.Cu")
		(net "SG")
	)
	(segment
		(start 68.64985 -6.823964)
		(end 68.64985 -3.500374)
		(width 0.381)
		(layer "F.Cu")
		(net "SG")
	)
	(segment
		(start 90.104722 -104.6734)
		(end 91.1352 -104.6734)
		(width 0.3048)
		(layer "F.Cu")
		(net "SG")
	)
	(segment
		(start 106.847132 -44.823126)
		(end 106.34726 -45.322998)
		(width 0.381)
		(layer "F.Cu")
		(net "SG")
	)
	(segment
		(start 22.0472 -58.42)
		(end 22.0472 -57.8612)
		(width 0.381)
		(layer "F.Cu")
		(net "SG")
	)
	(segment
		(start 107.84713 -39.823136)
		(end 107.347258 -39.323264)
		(width 0.381)
		(layer "F.Cu")
		(net "SG")
	)
	(segment
		(start 94.869 -23.876)
		(end 94.869 -25.06345)
		(width 0.381)
		(layer "F.Cu")
		(net "SG")
	)
	(segment
		(start 104.847136 -39.823136)
		(end 104.347264 -39.323264)
		(width 0.381)
		(layer "F.Cu")
		(net "SG")
	)
	(segment
		(start 111.847122 -39.823136)
		(end 112.346994 -39.323264)
		(width 0.381)
		(layer "F.Cu")
		(net "SG")
	)
	(segment
		(start 149.376892 -58.014108)
		(end 148.971 -58.42)
		(width 0.381)
		(layer "F.Cu")
		(net "SG")
	)
	(segment
		(start 18.710148 -24.5872)
		(end 18.710148 -24.0665)
		(width 0.3048)
		(layer "F.Cu")
		(net "SG")
	)
	(segment
		(start 15.7226 -71.0946)
		(end 16.5354 -71.9074)
		(width 0.381)
		(layer "F.Cu")
		(net "SG")
	)
	(segment
		(start 100.6856 -24.638)
		(end 99.3394 -24.638)
		(width 0.3048)
		(layer "F.Cu")
		(net "SG")
	)
	(segment
		(start 54.61 -16.1544)
		(end 54.61 -17.526)
		(width 0.381)
		(layer "F.Cu")
		(net "SG")
	)
	(segment
		(start 113.2459 -27.8638)
		(end 113.2459 -28.5242)
		(width 0.381)
		(layer "F.Cu")
		(net "SG")
	)
	(segment
		(start 112.84712 -52.82311)
		(end 113.346992 -53.322982)
		(width 0.381)
		(layer "F.Cu")
		(net "SG")
	)
	(segment
		(start 140.6652 -61.0108)
		(end 141.097 -60.579)
		(width 0.254)
		(layer "F.Cu")
		(net "SG")
	)
	(segment
		(start 113.284 -24.7142)
		(end 113.284 -25.0698)
		(width 0.381)
		(layer "F.Cu")
		(net "SG")
	)
	(segment
		(start 98.846894 -54.823106)
		(end 98.347022 -55.322978)
		(width 0.381)
		(layer "F.Cu")
		(net "SG")
	)
	(segment
		(start 22.1996 -65.5574)
		(end 22.1488 -65.6082)
		(width 0.381)
		(layer "F.Cu")
		(net "SG")
	)
	(segment
		(start 15.618206 -84.411566)
		(end 15.93977 -84.090002)
		(width 0.381)
		(layer "F.Cu")
		(net "SG")
	)
	(segment
		(start 69.58076 -14.717014)
		(end 69.9516 -14.717014)
		(width 0.3048)
		(layer "F.Cu")
		(net "SG")
	)
	(segment
		(start 146.822922 -15.4686)
		(end 147.483322 -15.4686)
		(width 0.3048)
		(layer "F.Cu")
		(net "SG")
	)
	(segment
		(start 100.84689 -38.823138)
		(end 100.347018 -38.323266)
		(width 0.381)
		(layer "F.Cu")
		(net "SG")
	)
	(segment
		(start 109.7788 -24.7142)
		(end 109.7788 -25.1968)
		(width 0.381)
		(layer "F.Cu")
		(net "SG")
	)
	(segment
		(start 102.5017 -91.069922)
		(end 104.14 -91.069922)
		(width 0.381)
		(layer "F.Cu")
		(net "SG")
	)
	(segment
		(start 104.847136 -41.823132)
		(end 104.347264 -41.32326)
		(width 0.381)
		(layer "F.Cu")
		(net "SG")
	)
	(segment
		(start 105.029 -18.4404)
		(end 104.648 -18.0594)
		(width 0.381)
		(layer "F.Cu")
		(net "SG")
	)
	(segment
		(start 29.591 -98.552)
		(end 29.591 -97.028)
		(width 0.381)
		(layer "F.Cu")
		(net "SG")
	)
	(segment
		(start 147.3962 -97.9678)
		(end 146.3548 -97.9678)
		(width 0.381)
		(layer "F.Cu")
		(net "SG")
	)
	(segment
		(start 103.505 -77.47)
		(end 104.267 -77.47)
		(width 0.381)
		(layer "F.Cu")
		(net "SG")
	)
	(segment
		(start 18.288 -86.1949)
		(end 18.288 -85.09)
		(width 0.381)
		(layer "F.Cu")
		(net "SG")
	)
	(segment
		(start 83.439 -72.771)
		(end 83.947 -73.279)
		(width 0.381)
		(layer "F.Cu")
		(net "SG")
	)
	(segment
		(start 13.150088 -63.290196)
		(end 13.150088 -62.248796)
		(width 0.254)
		(layer "F.Cu")
		(net "SG")
	)
	(segment
		(start 109.474 -29.591)
		(end 108.220002 -28.337002)
		(width 0.381)
		(layer "F.Cu")
		(net "SG")
	)
	(segment
		(start 124.3076 -32.0802)
		(end 124.60732 -32.0802)
		(width 0.381)
		(layer "F.Cu")
		(net "SG")
	)
	(segment
		(start 94.869 -19.812)
		(end 93.995494 -19.812)
		(width 0.381)
		(layer "F.Cu")
		(net "SG")
	)
	(segment
		(start 70.354444 -46.996604)
		(end 68.967604 -46.996604)
		(width 0.254)
		(layer "F.Cu")
		(net "SG")
	)
	(segment
		(start 105.029 -25.146)
		(end 105.029 -22.479)
		(width 0.381)
		(layer "F.Cu")
		(net "SG")
	)
	(via
		(at 166.633906 -31.80207)
		(size 0.4572)
		(drill 0.2032)
		(layers "F.Cu" "B.Cu")
		(net "SG")
	)
	(via
		(at 127.104902 -110.133892)
		(size 0.4572)
		(drill 0.2032)
		(layers "F.Cu" "B.Cu")
		(net "SG")
	)
	(via
		(at 78.477618 -51.816)
		(size 0.508)
		(drill 0.254)
		(layers "F.Cu" "B.Cu")
		(net "SG")
	)
	(via
		(at 112.116108 -13.766038)
		(size 0.4572)
		(drill 0.2032)
		(layers "F.Cu" "B.Cu")
		(net "SG")
	)
	(via
		(at 72.263 -45.9994)
		(size 0.4572)
		(drill 0.2032)
		(layers "F.Cu" "B.Cu")
		(net "SG")
	)
	(via
		(at 145.644108 -13.766038)
		(size 0.4572)
		(drill 0.2032)
		(layers "F.Cu" "B.Cu")
		(net "SG")
	)
	(via
		(at 40.173402 -5.516118)
		(size 0.4572)
		(drill 0.2032)
		(layers "F.Cu" "B.Cu")
		(net "SG")
	)
	(via
		(at 110.109 -25.527)
		(size 0.508)
		(drill 0.254)
		(layers "F.Cu" "B.Cu")
		(net "SG")
	)
	(via
		(at 104.347264 -37.323268)
		(size 0.4572)
		(drill 0.2032)
		(layers "F.Cu" "B.Cu")
		(net "SG")
	)
	(via
		(at 34.365946 -8.257286)
		(size 0.4572)
		(drill 0.2032)
		(layers "F.Cu" "B.Cu")
		(net "SG")
	)
	(via
		(at 41.539922 -13.248386)
		(size 0.4572)
		(drill 0.2032)
		(layers "F.Cu" "B.Cu")
		(net "SG")
	)
	(via
		(at 12.296902 -110.133892)
		(size 0.4572)
		(drill 0.2032)
		(layers "F.Cu" "B.Cu")
		(net "SG")
	)
	(via
		(at 104.347264 -41.32326)
		(size 0.4572)
		(drill 0.2032)
		(layers "F.Cu" "B.Cu")
		(net "SG")
	)
	(via
		(at 166.633906 -107.672886)
		(size 0.4572)
		(drill 0.2032)
		(layers "F.Cu" "B.Cu")
		(net "SG")
	)
	(via
		(at 70.358 -50.4698)
		(size 0.4572)
		(drill 0.2032)
		(layers "F.Cu" "B.Cu")
		(net "SG")
	)
	(via
		(at 115.4684 -27.559)
		(size 0.508)
		(drill 0.254)
		(layers "F.Cu" "B.Cu")
		(net "SG")
	)
	(via
		(at 136.3726 -51.181)
		(size 0.508)
		(drill 0.254)
		(layers "F.Cu" "B.Cu")
		(net "SG")
	)
	(via
		(at 11.399012 -5.516118)
		(size 0.4572)
		(drill 0.2032)
		(layers "F.Cu" "B.Cu")
		(net "SG")
	)
	(via
		(at 119.34698 -55.322978)
		(size 0.4572)
		(drill 0.2032)
		(layers "F.Cu" "B.Cu")
		(net "SG")
	)
	(via
		(at 114.34699 -39.323264)
		(size 0.4572)
		(drill 0.2032)
		(layers "F.Cu" "B.Cu")
		(net "SG")
	)
	(via
		(at 112.880902 -110.133892)
		(size 0.4572)
		(drill 0.2032)
		(layers "F.Cu" "B.Cu")
		(net "SG")
	)
	(via
		(at 138.176 -40.386)
		(size 0.508)
		(drill 0.254)
		(layers "F.Cu" "B.Cu")
		(net "SG")
	)
	(via
		(at 45.806614 -11.99515)
		(size 0.4572)
		(drill 0.2032)
		(layers "F.Cu" "B.Cu")
		(net "SG")
	)
	(via
		(at 128.143 -95.504)
		(size 0.508)
		(drill 0.254)
		(layers "F.Cu" "B.Cu")
		(net "SG")
	)
	(via
		(at 15.344902 -110.133892)
		(size 0.4572)
		(drill 0.2032)
		(layers "F.Cu" "B.Cu")
		(net "SG")
	)
	(via
		(at 1.016 -108.107226)
		(size 0.4572)
		(drill 0.2032)
		(layers "F.Cu" "B.Cu")
		(net "SG")
	)
	(via
		(at 142.2908 -98.171)
		(size 0.508)
		(drill 0.254)
		(layers "F.Cu" "B.Cu")
		(net "SG")
	)
	(via
		(at 17.64284 -13.766038)
		(size 0.4572)
		(drill 0.2032)
		(layers "F.Cu" "B.Cu")
		(net "SG")
	)
	(via
		(at 113.346992 -45.322998)
		(size 0.4572)
		(drill 0.2032)
		(layers "F.Cu" "B.Cu")
		(net "SG")
	)
	(via
		(at 80.368902 -110.133892)
		(size 0.4572)
		(drill 0.2032)
		(layers "F.Cu" "B.Cu")
		(net "SG")
	)
	(via
		(at 6.200902 -110.133892)
		(size 0.4572)
		(drill 0.2032)
		(layers "F.Cu" "B.Cu")
		(net "SG")
	)
	(via
		(at 65.128902 -110.133892)
		(size 0.4572)
		(drill 0.2032)
		(layers "F.Cu" "B.Cu")
		(net "SG")
	)
	(via
		(at 94.869 -23.876)
		(size 0.4572)
		(drill 0.2032)
		(layers "F.Cu" "B.Cu")
		(net "SG")
	)
	(via
		(at 69.91604 -56.642)
		(size 0.508)
		(drill 0.254)
		(layers "F.Cu" "B.Cu")
		(net "SG")
	)
	(via
		(at 12.319 -68.961)
		(size 0.508)
		(drill 0.254)
		(layers "F.Cu" "B.Cu")
		(net "SG")
	)
	(via
		(at 144.4498 -51.8922)
		(size 0.508)
		(drill 0.254)
		(layers "F.Cu" "B.Cu")
		(net "SG")
	)
	(via
		(at 106.045 -89.408)
		(size 0.508)
		(drill 0.254)
		(layers "F.Cu" "B.Cu")
		(net "SG")
	)
	(via
		(at 119.228108 -13.766038)
		(size 0.4572)
		(drill 0.2032)
		(layers "F.Cu" "B.Cu")
		(net "SG")
	)
	(via
		(at 22.0472 -58.42)
		(size 0.4572)
		(drill 0.2032)
		(layers "F.Cu" "B.Cu")
		(net "SG")
	)
	(via
		(at 78.336902 -110.133892)
		(size 0.4572)
		(drill 0.2032)
		(layers "F.Cu" "B.Cu")
		(net "SG")
	)
	(via
		(at 1.016 -94.899226)
		(size 0.4572)
		(drill 0.2032)
		(layers "F.Cu" "B.Cu")
		(net "SG")
	)
	(via
		(at 133.8834 -86.5124)
		(size 0.508)
		(drill 0.254)
		(layers "F.Cu" "B.Cu")
		(net "SG")
	)
	(via
		(at 4.168902 -110.133892)
		(size 0.4572)
		(drill 0.2032)
		(layers "F.Cu" "B.Cu")
		(net "SG")
	)
	(via
		(at 90.1319 -70.1294)
		(size 0.4572)
		(drill 0.2032)
		(layers "F.Cu" "B.Cu")
		(net "SG")
	)
	(via
		(at 135.7884 -38.608)
		(size 0.508)
		(drill 0.254)
		(layers "F.Cu" "B.Cu")
		(net "SG")
	)
	(via
		(at 1.016 -99.979226)
		(size 0.4572)
		(drill 0.2032)
		(layers "F.Cu" "B.Cu")
		(net "SG")
	)
	(via
		(at 121.008902 -110.133892)
		(size 0.4572)
		(drill 0.2032)
		(layers "F.Cu" "B.Cu")
		(net "SG")
	)
	(via
		(at 156.591 -49.497996)
		(size 0.508)
		(drill 0.254)
		(layers "F.Cu" "B.Cu")
		(net "SG")
	)
	(via
		(at 61.4426 -60.6552)
		(size 0.508)
		(drill 0.254)
		(layers "F.Cu" "B.Cu")
		(net "SG")
	)
	(via
		(at 119.34698 -34.32302)
		(size 0.4572)
		(drill 0.2032)
		(layers "F.Cu" "B.Cu")
		(net "SG")
	)
	(via
		(at 83.59394 -48.335946)
		(size 0.4572)
		(drill 0.2032)
		(layers "F.Cu" "B.Cu")
		(net "SG")
	)
	(via
		(at 97.892108 -13.766038)
		(size 0.4572)
		(drill 0.2032)
		(layers "F.Cu" "B.Cu")
		(net "SG")
	)
	(via
		(at 28.8798 -97.155)
		(size 0.4572)
		(drill 0.2032)
		(layers "F.Cu" "B.Cu")
		(net "SG")
	)
	(via
		(at 92.812108 -13.766038)
		(size 0.4572)
		(drill 0.2032)
		(layers "F.Cu" "B.Cu")
		(net "SG")
	)
	(via
		(at 26.035 -106.68)
		(size 0.508)
		(drill 0.254)
		(layers "F.Cu" "B.Cu")
		(net "SG")
	)
	(via
		(at 118.346982 -37.323268)
		(size 0.4572)
		(drill 0.2032)
		(layers "F.Cu" "B.Cu")
		(net "SG")
	)
	(via
		(at 120.346978 -42.323258)
		(size 0.4572)
		(drill 0.2032)
		(layers "F.Cu" "B.Cu")
		(net "SG")
	)
	(via
		(at 117.348 -63.5)
		(size 0.508)
		(drill 0.254)
		(layers "F.Cu" "B.Cu")
		(net "SG")
	)
	(via
		(at 166.633906 -14.53007)
		(size 0.4572)
		(drill 0.2032)
		(layers "F.Cu" "B.Cu")
		(net "SG")
	)
	(via
		(at 48.641 -104.902)
		(size 0.508)
		(drill 0.254)
		(layers "F.Cu" "B.Cu")
		(net "SG")
	)
	(via
		(at 161.648902 -110.133892)
		(size 0.4572)
		(drill 0.2032)
		(layers "F.Cu" "B.Cu")
		(net "SG")
	)
	(via
		(at 90.17 -61.595)
		(size 0.508)
		(drill 0.254)
		(layers "F.Cu" "B.Cu")
		(net "SG")
	)
	(via
		(at 113.346992 -40.323262)
		(size 0.4572)
		(drill 0.2032)
		(layers "F.Cu" "B.Cu")
		(net "SG")
	)
	(via
		(at 38.56736 -20.30349)
		(size 0.4572)
		(drill 0.2032)
		(layers "F.Cu" "B.Cu")
		(net "SG")
	)
	(via
		(at 18.946622 -51.360578)
		(size 0.508)
		(drill 0.254)
		(layers "F.Cu" "B.Cu")
		(net "SG")
	)
	(via
		(at 82.804 -94.996)
		(size 0.508)
		(drill 0.254)
		(layers "F.Cu" "B.Cu")
		(net "SG")
	)
	(via
		(at 41.91 -74.676)
		(size 0.508)
		(drill 0.254)
		(layers "F.Cu" "B.Cu")
		(net "SG")
	)
	(via
		(at 34.417 -99.187)
		(size 0.508)
		(drill 0.254)
		(layers "F.Cu" "B.Cu")
		(net "SG")
	)
	(via
		(at 139.296902 -110.133892)
		(size 0.4572)
		(drill 0.2032)
		(layers "F.Cu" "B.Cu")
		(net "SG")
	)
	(via
		(at 99.924108 -13.766038)
		(size 0.4572)
		(drill 0.2032)
		(layers "F.Cu" "B.Cu")
		(net "SG")
	)
	(via
		(at 143.3449 -16.5989)
		(size 0.508)
		(drill 0.254)
		(layers "F.Cu" "B.Cu")
		(net "SG")
	)
	(via
		(at 166.633906 -103.608886)
		(size 0.4572)
		(drill 0.2032)
		(layers "F.Cu" "B.Cu")
		(net "SG")
	)
	(via
		(at 166.633906 -45.01007)
		(size 0.4572)
		(drill 0.2032)
		(layers "F.Cu" "B.Cu")
		(net "SG")
	)
	(via
		(at 82.4992 -105.4608)
		(size 0.508)
		(drill 0.254)
		(layers "F.Cu" "B.Cu")
		(net "SG")
	)
	(via
		(at 36.10102 -82.71002)
		(size 0.508)
		(drill 0.254)
		(layers "F.Cu" "B.Cu")
		(net "SG")
	)
	(via
		(at 101.34727 -46.322996)
		(size 0.4572)
		(drill 0.2032)
		(layers "F.Cu" "B.Cu")
		(net "SG")
	)
	(via
		(at 102.347268 -43.323256)
		(size 0.4572)
		(drill 0.2032)
		(layers "F.Cu" "B.Cu")
		(net "SG")
	)
	(via
		(at 21.70684 -13.766038)
		(size 0.4572)
		(drill 0.2032)
		(layers "F.Cu" "B.Cu")
		(net "SG")
	)
	(via
		(at 4.318 -51.943)
		(size 0.508)
		(drill 0.254)
		(layers "F.Cu" "B.Cu")
		(net "SG")
	)
	(via
		(at 133.452108 -13.766038)
		(size 0.4572)
		(drill 0.2032)
		(layers "F.Cu" "B.Cu")
		(net "SG")
	)
	(via
		(at 69.369178 -19.3802)
		(size 0.4572)
		(drill 0.2032)
		(layers "F.Cu" "B.Cu")
		(net "SG")
	)
	(via
		(at 40.826944 -12.524486)
		(size 0.4572)
		(drill 0.2032)
		(layers "F.Cu" "B.Cu")
		(net "SG")
	)
	(via
		(at 1.016 -87.787226)
		(size 0.4572)
		(drill 0.2032)
		(layers "F.Cu" "B.Cu")
		(net "SG")
	)
	(via
		(at 117.196108 -13.766038)
		(size 0.4572)
		(drill 0.2032)
		(layers "F.Cu" "B.Cu")
		(net "SG")
	)
	(via
		(at 166.633906 -27.73807)
		(size 0.4572)
		(drill 0.2032)
		(layers "F.Cu" "B.Cu")
		(net "SG")
	)
	(via
		(at 143.383 -96.266)
		(size 0.508)
		(drill 0.254)
		(layers "F.Cu" "B.Cu")
		(net "SG")
	)
	(via
		(at 100.688902 -110.133892)
		(size 0.4572)
		(drill 0.2032)
		(layers "F.Cu" "B.Cu")
		(net "SG")
	)
	(via
		(at 103.378 -30.48)
		(size 0.508)
		(drill 0.254)
		(layers "F.Cu" "B.Cu")
		(net "SG")
	)
	(via
		(at 91.518994 -104.10952)
		(size 0.508)
		(drill 0.254)
		(layers "F.Cu" "B.Cu")
		(net "SG")
	)
	(via
		(at 51.920902 -110.133892)
		(size 0.4572)
		(drill 0.2032)
		(layers "F.Cu" "B.Cu")
		(net "SG")
	)
	(via
		(at 112.346994 -41.32326)
		(size 0.4572)
		(drill 0.2032)
		(layers "F.Cu" "B.Cu")
		(net "SG")
	)
	(via
		(at 42.2021 -77.2287)
		(size 0.508)
		(drill 0.254)
		(layers "F.Cu" "B.Cu")
		(net "SG")
	)
	(via
		(at 86.004146 -27.559)
		(size 0.4572)
		(drill 0.2032)
		(layers "F.Cu" "B.Cu")
		(net "SG")
	)
	(via
		(at 17.018 -71.9074)
		(size 0.4572)
		(drill 0.2032)
		(layers "F.Cu" "B.Cu")
		(net "SG")
	)
	(via
		(at 135.484108 -13.766038)
		(size 0.4572)
		(drill 0.2032)
		(layers "F.Cu" "B.Cu")
		(net "SG")
	)
	(via
		(at 30.099 -96.266)
		(size 0.508)
		(drill 0.254)
		(layers "F.Cu" "B.Cu")
		(net "SG")
	)
	(via
		(at 147.701 -67.818)
		(size 0.508)
		(drill 0.254)
		(layers "F.Cu" "B.Cu")
		(net "SG")
	)
	(via
		(at 51.2953 -7.3787)
		(size 0.4572)
		(drill 0.2032)
		(layers "F.Cu" "B.Cu")
		(net "SG")
	)
	(via
		(at 97.536 -27.813)
		(size 0.508)
		(drill 0.254)
		(layers "F.Cu" "B.Cu")
		(net "SG")
	)
	(via
		(at 32.385 -73.787)
		(size 0.508)
		(drill 0.254)
		(layers "F.Cu" "B.Cu")
		(net "SG")
	)
	(via
		(at 55.2704 -105.4354)
		(size 0.508)
		(drill 0.254)
		(layers "F.Cu" "B.Cu")
		(net "SG")
	)
	(via
		(at 119.7356 -92.2782)
		(size 0.508)
		(drill 0.254)
		(layers "F.Cu" "B.Cu")
		(net "SG")
	)
	(via
		(at 116.84 -72.263)
		(size 0.508)
		(drill 0.254)
		(layers "F.Cu" "B.Cu")
		(net "SG")
	)
	(via
		(at 90.780108 -13.766038)
		(size 0.4572)
		(drill 0.2032)
		(layers "F.Cu" "B.Cu")
		(net "SG")
	)
	(via
		(at 133.200902 -110.133892)
		(size 0.4572)
		(drill 0.2032)
		(layers "F.Cu" "B.Cu")
		(net "SG")
	)
	(via
		(at 131.168902 -110.133892)
		(size 0.4572)
		(drill 0.2032)
		(layers "F.Cu" "B.Cu")
		(net "SG")
	)
	(via
		(at 108.347256 -42.323258)
		(size 0.4572)
		(drill 0.2032)
		(layers "F.Cu" "B.Cu")
		(net "SG")
	)
	(via
		(at 27.051 -92.456)
		(size 0.508)
		(drill 0.254)
		(layers "F.Cu" "B.Cu")
		(net "SG")
	)
	(via
		(at 17.145 -56.6166)
		(size 0.508)
		(drill 0.254)
		(layers "F.Cu" "B.Cu")
		(net "SG")
	)
	(via
		(at 138.532108 -13.766038)
		(size 0.4572)
		(drill 0.2032)
		(layers "F.Cu" "B.Cu")
		(net "SG")
	)
	(via
		(at 151.488902 -110.133892)
		(size 0.4572)
		(drill 0.2032)
		(layers "F.Cu" "B.Cu")
		(net "SG")
	)
	(via
		(at 102.347268 -39.323264)
		(size 0.4572)
		(drill 0.2032)
		(layers "F.Cu" "B.Cu")
		(net "SG")
	)
	(via
		(at 89.2048 -49.9364)
		(size 0.508)
		(drill 0.254)
		(layers "F.Cu" "B.Cu")
		(net "SG")
	)
	(via
		(at 35.591242 -99.467416)
		(size 0.508)
		(drill 0.254)
		(layers "F.Cu" "B.Cu")
		(net "SG")
	)
	(via
		(at 12.415012 -5.516118)
		(size 0.4572)
		(drill 0.2032)
		(layers "F.Cu" "B.Cu")
		(net "SG")
	)
	(via
		(at 90.8304 -43.0276)
		(size 0.508)
		(drill 0.254)
		(layers "F.Cu" "B.Cu")
		(net "SG")
	)
	(via
		(at 76.454 -79.248)
		(size 0.508)
		(drill 0.254)
		(layers "F.Cu" "B.Cu")
		(net "SG")
	)
	(via
		(at 58.016902 -110.133892)
		(size 0.4572)
		(drill 0.2032)
		(layers "F.Cu" "B.Cu")
		(net "SG")
	)
	(via
		(at 72.240902 -110.133892)
		(size 0.4572)
		(drill 0.2032)
		(layers "F.Cu" "B.Cu")
		(net "SG")
	)
	(via
		(at 135.763 -34.671)
		(size 0.508)
		(drill 0.254)
		(layers "F.Cu" "B.Cu")
		(net "SG")
	)
	(via
		(at 17.0434 -90.805)
		(size 0.4572)
		(drill 0.2032)
		(layers "F.Cu" "B.Cu")
		(net "SG")
	)
	(via
		(at 165.712902 -110.133892)
		(size 0.4572)
		(drill 0.2032)
		(layers "F.Cu" "B.Cu")
		(net "SG")
	)
	(via
		(at 94.615 -58.928)
		(size 0.508)
		(drill 0.254)
		(layers "F.Cu" "B.Cu")
		(net "SG")
	)
	(via
		(at 97.282 -74.4728)
		(size 0.508)
		(drill 0.254)
		(layers "F.Cu" "B.Cu")
		(net "SG")
	)
	(via
		(at 146.408902 -110.133892)
		(size 0.4572)
		(drill 0.2032)
		(layers "F.Cu" "B.Cu")
		(net "SG")
	)
	(via
		(at 139.446 -67.945)
		(size 0.508)
		(drill 0.254)
		(layers "F.Cu" "B.Cu")
		(net "SG")
	)
	(via
		(at 159.616902 -110.133892)
		(size 0.4572)
		(drill 0.2032)
		(layers "F.Cu" "B.Cu")
		(net "SG")
	)
	(via
		(at 94.0562 -73.9394)
		(size 0.508)
		(drill 0.254)
		(layers "F.Cu" "B.Cu")
		(net "SG")
	)
	(via
		(at 112.776 -63.5)
		(size 0.508)
		(drill 0.254)
		(layers "F.Cu" "B.Cu")
		(net "SG")
	)
	(via
		(at 135.255 -69.215)
		(size 0.508)
		(drill 0.254)
		(layers "F.Cu" "B.Cu")
		(net "SG")
	)
	(via
		(at 33.528 -95.377)
		(size 0.508)
		(drill 0.254)
		(layers "F.Cu" "B.Cu")
		(net "SG")
	)
	(via
		(at 76.304902 -110.133892)
		(size 0.4572)
		(drill 0.2032)
		(layers "F.Cu" "B.Cu")
		(net "SG")
	)
	(via
		(at 16.764 -106.426)
		(size 0.508)
		(drill 0.254)
		(layers "F.Cu" "B.Cu")
		(net "SG")
	)
	(via
		(at 7.335012 -5.516118)
		(size 0.4572)
		(drill 0.2032)
		(layers "F.Cu" "B.Cu")
		(net "SG")
	)
	(via
		(at 166.633906 -35.86607)
		(size 0.4572)
		(drill 0.2032)
		(layers "F.Cu" "B.Cu")
		(net "SG")
	)
	(via
		(at 136.779 -48.133)
		(size 0.508)
		(drill 0.254)
		(layers "F.Cu" "B.Cu")
		(net "SG")
	)
	(via
		(at 166.633906 -79.224886)
		(size 0.4572)
		(drill 0.2032)
		(layers "F.Cu" "B.Cu")
		(net "SG")
	)
	(via
		(at 142.596108 -13.766038)
		(size 0.4572)
		(drill 0.2032)
		(layers "F.Cu" "B.Cu")
		(net "SG")
	)
	(via
		(at 54.968902 -110.133892)
		(size 0.4572)
		(drill 0.2032)
		(layers "F.Cu" "B.Cu")
		(net "SG")
	)
	(via
		(at 1.016 -105.059226)
		(size 0.4572)
		(drill 0.2032)
		(layers "F.Cu" "B.Cu")
		(net "SG")
	)
	(via
		(at 142.344902 -110.133892)
		(size 0.4572)
		(drill 0.2032)
		(layers "F.Cu" "B.Cu")
		(net "SG")
	)
	(via
		(at 114.912902 -110.133892)
		(size 0.4572)
		(drill 0.2032)
		(layers "F.Cu" "B.Cu")
		(net "SG")
	)
	(via
		(at 122.301 -46.232064)
		(size 0.508)
		(drill 0.254)
		(layers "F.Cu" "B.Cu")
		(net "SG")
	)
	(via
		(at 62.133226 -7.3406)
		(size 0.4572)
		(drill 0.2032)
		(layers "F.Cu" "B.Cu")
		(net "SG")
	)
	(via
		(at 135.4328 -55.88)
		(size 0.508)
		(drill 0.254)
		(layers "F.Cu" "B.Cu")
		(net "SG")
	)
	(via
		(at 89.916 -32.512)
		(size 0.508)
		(drill 0.254)
		(layers "F.Cu" "B.Cu")
		(net "SG")
	)
	(via
		(at 92.2274 -107.3912)
		(size 0.508)
		(drill 0.254)
		(layers "F.Cu" "B.Cu")
		(net "SG")
	)
	(via
		(at 152.7937 -52.9463)
		(size 0.508)
		(drill 0.254)
		(layers "F.Cu" "B.Cu")
		(net "SG")
	)
	(via
		(at 30.85084 -13.766038)
		(size 0.4572)
		(drill 0.2032)
		(layers "F.Cu" "B.Cu")
		(net "SG")
	)
	(via
		(at 166.633906 -34.85007)
		(size 0.4572)
		(drill 0.2032)
		(layers "F.Cu" "B.Cu")
		(net "SG")
	)
	(via
		(at 67.160902 -110.133892)
		(size 0.4572)
		(drill 0.2032)
		(layers "F.Cu" "B.Cu")
		(net "SG")
	)
	(via
		(at 118.976902 -110.133892)
		(size 0.4572)
		(drill 0.2032)
		(layers "F.Cu" "B.Cu")
		(net "SG")
	)
	(via
		(at 104.347264 -47.322994)
		(size 0.4572)
		(drill 0.2032)
		(layers "F.Cu" "B.Cu")
		(net "SG")
	)
	(via
		(at 1.016 -97.947226)
		(size 0.4572)
		(drill 0.2032)
		(layers "F.Cu" "B.Cu")
		(net "SG")
	)
	(via
		(at 114.34699 -50.322988)
		(size 0.4572)
		(drill 0.2032)
		(layers "F.Cu" "B.Cu")
		(net "SG")
	)
	(via
		(at 99.06 -25.527)
		(size 0.4572)
		(drill 0.2032)
		(layers "F.Cu" "B.Cu")
		(net "SG")
	)
	(via
		(at 15.611602 -13.728192)
		(size 0.4572)
		(drill 0.2032)
		(layers "F.Cu" "B.Cu")
		(net "SG")
	)
	(via
		(at 90.897456 -26.595578)
		(size 0.4572)
		(drill 0.2032)
		(layers "F.Cu" "B.Cu")
		(net "SG")
	)
	(via
		(at 166.633906 -59.83859)
		(size 0.4572)
		(drill 0.2032)
		(layers "F.Cu" "B.Cu")
		(net "SG")
	)
	(via
		(at 96.624902 -110.133892)
		(size 0.4572)
		(drill 0.2032)
		(layers "F.Cu" "B.Cu")
		(net "SG")
	)
	(via
		(at 114.3 -103.378)
		(size 0.508)
		(drill 0.254)
		(layers "F.Cu" "B.Cu")
		(net "SG")
	)
	(via
		(at 85.979 -95.504)
		(size 0.508)
		(drill 0.254)
		(layers "F.Cu" "B.Cu")
		(net "SG")
	)
	(via
		(at 90.297 -77.851)
		(size 0.508)
		(drill 0.254)
		(layers "F.Cu" "B.Cu")
		(net "SG")
	)
	(via
		(at 103.6447 -29.489146)
		(size 0.4572)
		(drill 0.2032)
		(layers "F.Cu" "B.Cu")
		(net "SG")
	)
	(via
		(at 25.0952 -69.1896)
		(size 0.508)
		(drill 0.254)
		(layers "F.Cu" "B.Cu")
		(net "SG")
	)
	(via
		(at 102.720902 -110.133892)
		(size 0.4572)
		(drill 0.2032)
		(layers "F.Cu" "B.Cu")
		(net "SG")
	)
	(via
		(at 44.4754 -98.3234)
		(size 0.508)
		(drill 0.254)
		(layers "F.Cu" "B.Cu")
		(net "SG")
	)
	(via
		(at 30.353 -14.654276)
		(size 0.508)
		(drill 0.254)
		(layers "F.Cu" "B.Cu")
		(net "SG")
	)
	(via
		(at 154.788108 -13.766038)
		(size 0.4572)
		(drill 0.2032)
		(layers "F.Cu" "B.Cu")
		(net "SG")
	)
	(via
		(at 132.436108 -13.766038)
		(size 0.4572)
		(drill 0.2032)
		(layers "F.Cu" "B.Cu")
		(net "SG")
	)
	(via
		(at 40.744902 -110.133892)
		(size 0.4572)
		(drill 0.2032)
		(layers "F.Cu" "B.Cu")
		(net "SG")
	)
	(via
		(at 95.608902 -110.133892)
		(size 0.4572)
		(drill 0.2032)
		(layers "F.Cu" "B.Cu")
		(net "SG")
	)
	(via
		(at 166.633906 -15.54607)
		(size 0.4572)
		(drill 0.2032)
		(layers "F.Cu" "B.Cu")
		(net "SG")
	)
	(via
		(at 92.9132 -72.6694)
		(size 0.508)
		(drill 0.254)
		(layers "F.Cu" "B.Cu")
		(net "SG")
	)
	(via
		(at 13.150088 -62.248796)
		(size 0.508)
		(drill 0.254)
		(layers "F.Cu" "B.Cu")
		(net "SG")
	)
	(via
		(at 45.3644 -95.1484)
		(size 0.508)
		(drill 0.254)
		(layers "F.Cu" "B.Cu")
		(net "SG")
	)
	(via
		(at 101.5492 -70.7136)
		(size 0.508)
		(drill 0.254)
		(layers "F.Cu" "B.Cu")
		(net "SG")
	)
	(via
		(at 17.653 -25.4)
		(size 0.508)
		(drill 0.254)
		(layers "F.Cu" "B.Cu")
		(net "SG")
	)
	(via
		(at 137.795 -48.133)
		(size 0.508)
		(drill 0.254)
		(layers "F.Cu" "B.Cu")
		(net "SG")
	)
	(via
		(at 112.776 -105.791)
		(size 0.4572)
		(drill 0.2032)
		(layers "F.Cu" "B.Cu")
		(net "SG")
	)
	(via
		(at 75.819 -46.863)
		(size 0.508)
		(drill 0.254)
		(layers "F.Cu" "B.Cu")
		(net "SG")
	)
	(via
		(at 107.347258 -48.322992)
		(size 0.4572)
		(drill 0.2032)
		(layers "F.Cu" "B.Cu")
		(net "SG")
	)
	(via
		(at 44.808902 -110.133892)
		(size 0.4572)
		(drill 0.2032)
		(layers "F.Cu" "B.Cu")
		(net "SG")
	)
	(via
		(at 82.6262 -98.3488)
		(size 0.508)
		(drill 0.254)
		(layers "F.Cu" "B.Cu")
		(net "SG")
	)
	(via
		(at 1.016 -73.563226)
		(size 0.4572)
		(drill 0.2032)
		(layers "F.Cu" "B.Cu")
		(net "SG")
	)
	(via
		(at 110.346998 -52.322984)
		(size 0.4572)
		(drill 0.2032)
		(layers "F.Cu" "B.Cu")
		(net "SG")
	)
	(via
		(at 82.6262 -100.6348)
		(size 0.508)
		(drill 0.254)
		(layers "F.Cu" "B.Cu")
		(net "SG")
	)
	(via
		(at 38.354 -82.3468)
		(size 0.508)
		(drill 0.254)
		(layers "F.Cu" "B.Cu")
		(net "SG")
	)
	(via
		(at 19.4818 -90.805)
		(size 0.4572)
		(drill 0.2032)
		(layers "F.Cu" "B.Cu")
		(net "SG")
	)
	(via
		(at 135.382 -22.098)
		(size 0.508)
		(drill 0.254)
		(layers "F.Cu" "B.Cu")
		(net "SG")
	)
	(via
		(at 117.348 -57.023)
		(size 0.508)
		(drill 0.254)
		(layers "F.Cu" "B.Cu")
		(net "SG")
	)
	(via
		(at 98.908108 -13.766038)
		(size 0.4572)
		(drill 0.2032)
		(layers "F.Cu" "B.Cu")
		(net "SG")
	)
	(via
		(at 98.347022 -39.323264)
		(size 0.4572)
		(drill 0.2032)
		(layers "F.Cu" "B.Cu")
		(net "SG")
	)
	(via
		(at 122.276108 -13.766038)
		(size 0.4572)
		(drill 0.2032)
		(layers "F.Cu" "B.Cu")
		(net "SG")
	)
	(via
		(at 104.347264 -39.323264)
		(size 0.4572)
		(drill 0.2032)
		(layers "F.Cu" "B.Cu")
		(net "SG")
	)
	(via
		(at 94.4372 -32.766)
		(size 0.508)
		(drill 0.254)
		(layers "F.Cu" "B.Cu")
		(net "SG")
	)
	(via
		(at 100.6856 -25.527)
		(size 0.4572)
		(drill 0.2032)
		(layers "F.Cu" "B.Cu")
		(net "SG")
	)
	(via
		(at 142.2908 -20.701)
		(size 0.508)
		(drill 0.254)
		(layers "F.Cu" "B.Cu")
		(net "SG")
	)
	(via
		(at 11.280902 -110.133892)
		(size 0.4572)
		(drill 0.2032)
		(layers "F.Cu" "B.Cu")
		(net "SG")
	)
	(via
		(at 136.248902 -110.133892)
		(size 0.4572)
		(drill 0.2032)
		(layers "F.Cu" "B.Cu")
		(net "SG")
	)
	(via
		(at 44.3484 -102.0064)
		(size 0.508)
		(drill 0.254)
		(layers "F.Cu" "B.Cu")
		(net "SG")
	)
	(via
		(at 15.5956 -26.6446)
		(size 0.508)
		(drill 0.254)
		(layers "F.Cu" "B.Cu")
		(net "SG")
	)
	(via
		(at 166.633906 -38.91407)
		(size 0.4572)
		(drill 0.2032)
		(layers "F.Cu" "B.Cu")
		(net "SG")
	)
	(via
		(at 147.3454 -93.1418)
		(size 0.508)
		(drill 0.254)
		(layers "F.Cu" "B.Cu")
		(net "SG")
	)
	(via
		(at 85.725 -31.1404)
		(size 0.4572)
		(drill 0.2032)
		(layers "F.Cu" "B.Cu")
		(net "SG")
	)
	(via
		(at 71.142098 -8.1534)
		(size 0.4572)
		(drill 0.2032)
		(layers "F.Cu" "B.Cu")
		(net "SG")
	)
	(via
		(at 35.814 -75.819)
		(size 0.508)
		(drill 0.254)
		(layers "F.Cu" "B.Cu")
		(net "SG")
	)
	(via
		(at 27.536902 -110.133892)
		(size 0.4572)
		(drill 0.2032)
		(layers "F.Cu" "B.Cu")
		(net "SG")
	)
	(via
		(at 166.633906 -16.56207)
		(size 0.4572)
		(drill 0.2032)
		(layers "F.Cu" "B.Cu")
		(net "SG")
	)
	(via
		(at 78.994 -49.149)
		(size 0.508)
		(drill 0.254)
		(layers "F.Cu" "B.Cu")
		(net "SG")
	)
	(via
		(at 111.346996 -42.323258)
		(size 0.4572)
		(drill 0.2032)
		(layers "F.Cu" "B.Cu")
		(net "SG")
	)
	(via
		(at 128.120902 -110.133892)
		(size 0.4572)
		(drill 0.2032)
		(layers "F.Cu" "B.Cu")
		(net "SG")
	)
	(via
		(at 104.347264 -40.323262)
		(size 0.4572)
		(drill 0.2032)
		(layers "F.Cu" "B.Cu")
		(net "SG")
	)
	(via
		(at 146.420586 -41.140634)
		(size 0.508)
		(drill 0.254)
		(layers "F.Cu" "B.Cu")
		(net "SG")
	)
	(via
		(at 93.218 -32.004)
		(size 0.508)
		(drill 0.254)
		(layers "F.Cu" "B.Cu")
		(net "SG")
	)
	(via
		(at 50.904902 -110.133892)
		(size 0.4572)
		(drill 0.2032)
		(layers "F.Cu" "B.Cu")
		(net "SG")
	)
	(via
		(at 164.338 -28.829)
		(size 0.508)
		(drill 0.254)
		(layers "F.Cu" "B.Cu")
		(net "SG")
	)
	(via
		(at 48.26 -77.597)
		(size 0.508)
		(drill 0.254)
		(layers "F.Cu" "B.Cu")
		(net "SG")
	)
	(via
		(at 1.016 -109.123226)
		(size 0.4572)
		(drill 0.2032)
		(layers "F.Cu" "B.Cu")
		(net "SG")
	)
	(via
		(at 131.318 -53.975)
		(size 0.508)
		(drill 0.254)
		(layers "F.Cu" "B.Cu")
		(net "SG")
	)
	(via
		(at 36.680902 -110.133892)
		(size 0.4572)
		(drill 0.2032)
		(layers "F.Cu" "B.Cu")
		(net "SG")
	)
	(via
		(at 135.3566 -81.0006)
		(size 0.508)
		(drill 0.254)
		(layers "F.Cu" "B.Cu")
		(net "SG")
	)
	(via
		(at 28.81884 -13.766038)
		(size 0.4572)
		(drill 0.2032)
		(layers "F.Cu" "B.Cu")
		(net "SG")
	)
	(via
		(at 10.383012 -5.516118)
		(size 0.4572)
		(drill 0.2032)
		(layers "F.Cu" "B.Cu")
		(net "SG")
	)
	(via
		(at 112.522 -101.981)
		(size 0.4572)
		(drill 0.2032)
		(layers "F.Cu" "B.Cu")
		(net "SG")
	)
	(via
		(at 109.474 -29.591)
		(size 0.508)
		(drill 0.254)
		(layers "F.Cu" "B.Cu")
		(net "SG")
	)
	(via
		(at 34.365946 -9.273286)
		(size 0.4572)
		(drill 0.2032)
		(layers "F.Cu" "B.Cu")
		(net "SG")
	)
	(via
		(at 1.016 -6.507226)
		(size 0.4572)
		(drill 0.2032)
		(layers "F.Cu" "B.Cu")
		(net "SG")
	)
	(via
		(at 4.445 -23.114)
		(size 0.508)
		(drill 0.254)
		(layers "F.Cu" "B.Cu")
		(net "SG")
	)
	(via
		(at 103.347266 -50.322988)
		(size 0.4572)
		(drill 0.2032)
		(layers "F.Cu" "B.Cu")
		(net "SG")
	)
	(via
		(at 136.6774 -86.5124)
		(size 0.508)
		(drill 0.254)
		(layers "F.Cu" "B.Cu")
		(net "SG")
	)
	(via
		(at 93.218 -58.928)
		(size 0.508)
		(drill 0.254)
		(layers "F.Cu" "B.Cu")
		(net "SG")
	)
	(via
		(at 136.8044 -81.0006)
		(size 0.508)
		(drill 0.254)
		(layers "F.Cu" "B.Cu")
		(net "SG")
	)
	(via
		(at 14.328902 -110.133892)
		(size 0.4572)
		(drill 0.2032)
		(layers "F.Cu" "B.Cu")
		(net "SG")
	)
	(via
		(at 88.9254 -43.0276)
		(size 0.508)
		(drill 0.254)
		(layers "F.Cu" "B.Cu")
		(net "SG")
	)
	(via
		(at 97.282 -86.741)
		(size 0.508)
		(drill 0.254)
		(layers "F.Cu" "B.Cu")
		(net "SG")
	)
	(via
		(at 105.347262 -54.32298)
		(size 0.4572)
		(drill 0.2032)
		(layers "F.Cu" "B.Cu")
		(net "SG")
	)
	(via
		(at 96.012 -74.4728)
		(size 0.508)
		(drill 0.254)
		(layers "F.Cu" "B.Cu")
		(net "SG")
	)
	(via
		(at 166.633906 -21.64207)
		(size 0.4572)
		(drill 0.2032)
		(layers "F.Cu" "B.Cu")
		(net "SG")
	)
	(via
		(at 57.404 -96.139)
		(size 0.508)
		(drill 0.254)
		(layers "F.Cu" "B.Cu")
		(net "SG")
	)
	(via
		(at 144.376902 -110.133892)
		(size 0.4572)
		(drill 0.2032)
		(layers "F.Cu" "B.Cu")
		(net "SG")
	)
	(via
		(at 148.692108 -13.766038)
		(size 0.4572)
		(drill 0.2032)
		(layers "F.Cu" "B.Cu")
		(net "SG")
	)
	(via
		(at 166.633906 -46.02607)
		(size 0.4572)
		(drill 0.2032)
		(layers "F.Cu" "B.Cu")
		(net "SG")
	)
	(via
		(at 25.77084 -13.766038)
		(size 0.4572)
		(drill 0.2032)
		(layers "F.Cu" "B.Cu")
		(net "SG")
	)
	(via
		(at 57.3024 -105.4354)
		(size 0.508)
		(drill 0.254)
		(layers "F.Cu" "B.Cu")
		(net "SG")
	)
	(via
		(at 166.633906 -98.528886)
		(size 0.4572)
		(drill 0.2032)
		(layers "F.Cu" "B.Cu")
		(net "SG")
	)
	(via
		(at 37.592 -93.98)
		(size 0.508)
		(drill 0.254)
		(layers "F.Cu" "B.Cu")
		(net "SG")
	)
	(via
		(at 89.512902 -110.133892)
		(size 0.4572)
		(drill 0.2032)
		(layers "F.Cu" "B.Cu")
		(net "SG")
	)
	(via
		(at 110.346998 -41.32326)
		(size 0.4572)
		(drill 0.2032)
		(layers "F.Cu" "B.Cu")
		(net "SG")
	)
	(via
		(at 34.365946 -7.241286)
		(size 0.4572)
		(drill 0.2032)
		(layers "F.Cu" "B.Cu")
		(net "SG")
	)
	(via
		(at 133.0198 -95.9358)
		(size 0.508)
		(drill 0.254)
		(layers "F.Cu" "B.Cu")
		(net "SG")
	)
	(via
		(at 91.2622 -23.368)
		(size 0.4572)
		(drill 0.2032)
		(layers "F.Cu" "B.Cu")
		(net "SG")
	)
	(via
		(at 84.432902 -110.133892)
		(size 0.4572)
		(drill 0.2032)
		(layers "F.Cu" "B.Cu")
		(net "SG")
	)
	(via
		(at 166.633906 -39.93007)
		(size 0.4572)
		(drill 0.2032)
		(layers "F.Cu" "B.Cu")
		(net "SG")
	)
	(via
		(at 158.600902 -110.133892)
		(size 0.4572)
		(drill 0.2032)
		(layers "F.Cu" "B.Cu")
		(net "SG")
	)
	(via
		(at 108.347256 -55.322978)
		(size 0.4572)
		(drill 0.2032)
		(layers "F.Cu" "B.Cu")
		(net "SG")
	)
	(via
		(at 165.964108 -13.766038)
		(size 0.4572)
		(drill 0.2032)
		(layers "F.Cu" "B.Cu")
		(net "SG")
	)
	(via
		(at 124.056902 -110.133892)
		(size 0.4572)
		(drill 0.2032)
		(layers "F.Cu" "B.Cu")
		(net "SG")
	)
	(via
		(at 55.372 -96.7994)
		(size 0.508)
		(drill 0.254)
		(layers "F.Cu" "B.Cu")
		(net "SG")
	)
	(via
		(at 1.016 -9.555226)
		(size 0.4572)
		(drill 0.2032)
		(layers "F.Cu" "B.Cu")
		(net "SG")
	)
	(via
		(at 110.346998 -43.323256)
		(size 0.4572)
		(drill 0.2032)
		(layers "F.Cu" "B.Cu")
		(net "SG")
	)
	(via
		(at 36.576 -15.875)
		(size 0.4572)
		(drill 0.2032)
		(layers "F.Cu" "B.Cu")
		(net "SG")
	)
	(via
		(at 113.284 -95.123)
		(size 0.508)
		(drill 0.254)
		(layers "F.Cu" "B.Cu")
		(net "SG")
	)
	(via
		(at 107.188 -19.685)
		(size 0.508)
		(drill 0.254)
		(layers "F.Cu" "B.Cu")
		(net "SG")
	)
	(via
		(at 152.146 -23.495)
		(size 0.508)
		(drill 0.254)
		(layers "F.Cu" "B.Cu")
		(net "SG")
	)
	(via
		(at 69.17182 -13.937234)
		(size 0.508)
		(drill 0.254)
		(layers "F.Cu" "B.Cu")
		(net "SG")
	)
	(via
		(at 53.25364 -84.201)
		(size 0.4572)
		(drill 0.2032)
		(layers "F.Cu" "B.Cu")
		(net "SG")
	)
	(via
		(at 49.888902 -110.133892)
		(size 0.4572)
		(drill 0.2032)
		(layers "F.Cu" "B.Cu")
		(net "SG")
	)
	(via
		(at 1.016 -79.659226)
		(size 0.4572)
		(drill 0.2032)
		(layers "F.Cu" "B.Cu")
		(net "SG")
	)
	(via
		(at 33.76168 -13.189204)
		(size 0.4572)
		(drill 0.2032)
		(layers "F.Cu" "B.Cu")
		(net "SG")
	)
	(via
		(at 103.9368 -25.527)
		(size 0.4572)
		(drill 0.2032)
		(layers "F.Cu" "B.Cu")
		(net "SG")
	)
	(via
		(at 111.346996 -41.32326)
		(size 0.4572)
		(drill 0.2032)
		(layers "F.Cu" "B.Cu")
		(net "SG")
	)
	(via
		(at 1.016 -106.075226)
		(size 0.4572)
		(drill 0.2032)
		(layers "F.Cu" "B.Cu")
		(net "SG")
	)
	(via
		(at 147.3962 -95.4278)
		(size 0.508)
		(drill 0.254)
		(layers "F.Cu" "B.Cu")
		(net "SG")
	)
	(via
		(at 99.34702 -35.323018)
		(size 0.4572)
		(drill 0.2032)
		(layers "F.Cu" "B.Cu")
		(net "SG")
	)
	(via
		(at 21.9964 -35.8902)
		(size 0.508)
		(drill 0.254)
		(layers "F.Cu" "B.Cu")
		(net "SG")
	)
	(via
		(at 77.089 -17.6276)
		(size 0.508)
		(drill 0.254)
		(layers "F.Cu" "B.Cu")
		(net "SG")
	)
	(via
		(at 134.5692 -56.642)
		(size 0.508)
		(drill 0.254)
		(layers "F.Cu" "B.Cu")
		(net "SG")
	)
	(via
		(at 100.9142 -81.4578)
		(size 0.508)
		(drill 0.254)
		(layers "F.Cu" "B.Cu")
		(net "SG")
	)
	(via
		(at 21.7424 -66.9798)
		(size 0.4572)
		(drill 0.2032)
		(layers "F.Cu" "B.Cu")
		(net "SG")
	)
	(via
		(at 142.875 -18.9484)
		(size 0.508)
		(drill 0.254)
		(layers "F.Cu" "B.Cu")
		(net "SG")
	)
	(via
		(at 33.632902 -110.133892)
		(size 0.4572)
		(drill 0.2032)
		(layers "F.Cu" "B.Cu")
		(net "SG")
	)
	(via
		(at 25.146 -88.9)
		(size 0.508)
		(drill 0.254)
		(layers "F.Cu" "B.Cu")
		(net "SG")
	)
	(via
		(at 100.940108 -13.766038)
		(size 0.4572)
		(drill 0.2032)
		(layers "F.Cu" "B.Cu")
		(net "SG")
	)
	(via
		(at 166.633906 -18.59407)
		(size 0.4572)
		(drill 0.2032)
		(layers "F.Cu" "B.Cu")
		(net "SG")
	)
	(via
		(at 30.48 -94.361)
		(size 0.508)
		(drill 0.254)
		(layers "F.Cu" "B.Cu")
		(net "SG")
	)
	(via
		(at 29.568902 -110.133892)
		(size 0.4572)
		(drill 0.2032)
		(layers "F.Cu" "B.Cu")
		(net "SG")
	)
	(via
		(at 166.633906 -106.656886)
		(size 0.4572)
		(drill 0.2032)
		(layers "F.Cu" "B.Cu")
		(net "SG")
	)
	(via
		(at 157.988 -34.544)
		(size 0.508)
		(drill 0.254)
		(layers "F.Cu" "B.Cu")
		(net "SG")
	)
	(via
		(at 64.649858 -7.3406)
		(size 0.4572)
		(drill 0.2032)
		(layers "F.Cu" "B.Cu")
		(net "SG")
	)
	(via
		(at 79.883 -70.231)
		(size 0.508)
		(drill 0.254)
		(layers "F.Cu" "B.Cu")
		(net "SG")
	)
	(via
		(at 107.442 -25.527)
		(size 0.508)
		(drill 0.254)
		(layers "F.Cu" "B.Cu")
		(net "SG")
	)
	(via
		(at 135.7884 -37.6682)
		(size 0.508)
		(drill 0.254)
		(layers "F.Cu" "B.Cu")
		(net "SG")
	)
	(via
		(at 20.128992 -67.5894)
		(size 0.4572)
		(drill 0.2032)
		(layers "F.Cu" "B.Cu")
		(net "SG")
	)
	(via
		(at 155.9814 -56.9214)
		(size 0.508)
		(drill 0.254)
		(layers "F.Cu" "B.Cu")
		(net "SG")
	)
	(via
		(at 90.17 -84.455)
		(size 0.4572)
		(drill 0.2032)
		(layers "F.Cu" "B.Cu")
		(net "SG")
	)
	(via
		(at 105.7783 -101.9175)
		(size 0.508)
		(drill 0.254)
		(layers "F.Cu" "B.Cu")
		(net "SG")
	)
	(via
		(at 103.9368 -74.0918)
		(size 0.508)
		(drill 0.254)
		(layers "F.Cu" "B.Cu")
		(net "SG")
	)
	(via
		(at 134.7089 -65.39992)
		(size 0.508)
		(drill 0.254)
		(layers "F.Cu" "B.Cu")
		(net "SG")
	)
	(via
		(at 147.483322 -15.4686)
		(size 0.508)
		(drill 0.254)
		(layers "F.Cu" "B.Cu")
		(net "SG")
	)
	(via
		(at 92.735654 -47.030386)
		(size 0.4572)
		(drill 0.2032)
		(layers "F.Cu" "B.Cu")
		(net "SG")
	)
	(via
		(at 1.016 -7.523226)
		(size 0.4572)
		(drill 0.2032)
		(layers "F.Cu" "B.Cu")
		(net "SG")
	)
	(via
		(at 143.9164 -54.0766)
		(size 0.4572)
		(drill 0.2032)
		(layers "F.Cu" "B.Cu")
		(net "SG")
	)
	(via
		(at 101.473 -30.48)
		(size 0.508)
		(drill 0.254)
		(layers "F.Cu" "B.Cu")
		(net "SG")
	)
	(via
		(at 102.5398 -65.8622)
		(size 0.508)
		(drill 0.254)
		(layers "F.Cu" "B.Cu")
		(net "SG")
	)
	(via
		(at 83.439 -65.7606)
		(size 0.508)
		(drill 0.254)
		(layers "F.Cu" "B.Cu")
		(net "SG")
	)
	(via
		(at 107.347258 -41.32326)
		(size 0.4572)
		(drill 0.2032)
		(layers "F.Cu" "B.Cu")
		(net "SG")
	)
	(via
		(at 129.136902 -110.133892)
		(size 0.4572)
		(drill 0.2032)
		(layers "F.Cu" "B.Cu")
		(net "SG")
	)
	(via
		(at 115.928902 -110.133892)
		(size 0.4572)
		(drill 0.2032)
		(layers "F.Cu" "B.Cu")
		(net "SG")
	)
	(via
		(at 46.840902 -110.133892)
		(size 0.4572)
		(drill 0.2032)
		(layers "F.Cu" "B.Cu")
		(net "SG")
	)
	(via
		(at 107.036108 -13.766038)
		(size 0.4572)
		(drill 0.2032)
		(layers "F.Cu" "B.Cu")
		(net "SG")
	)
	(via
		(at 116.713 -81.788)
		(size 0.508)
		(drill 0.254)
		(layers "F.Cu" "B.Cu")
		(net "SG")
	)
	(via
		(at 24.488902 -110.133892)
		(size 0.4572)
		(drill 0.2032)
		(layers "F.Cu" "B.Cu")
		(net "SG")
	)
	(via
		(at 103.988108 -13.766038)
		(size 0.4572)
		(drill 0.2032)
		(layers "F.Cu" "B.Cu")
		(net "SG")
	)
	(via
		(at 112.776 -66.802)
		(size 0.508)
		(drill 0.254)
		(layers "F.Cu" "B.Cu")
		(net "SG")
	)
	(via
		(at 101.092 -89.408)
		(size 0.508)
		(drill 0.254)
		(layers "F.Cu" "B.Cu")
		(net "SG")
	)
	(via
		(at 18.288 -85.09)
		(size 0.508)
		(drill 0.254)
		(layers "F.Cu" "B.Cu")
		(net "SG")
	)
	(via
		(at 1.016 -12.603226)
		(size 0.4572)
		(drill 0.2032)
		(layers "F.Cu" "B.Cu")
		(net "SG")
	)
	(via
		(at 88.2142 -45.466)
		(size 0.508)
		(drill 0.254)
		(layers "F.Cu" "B.Cu")
		(net "SG")
	)
	(via
		(at 138.049 -52.07)
		(size 0.508)
		(drill 0.254)
		(layers "F.Cu" "B.Cu")
		(net "SG")
	)
	(via
		(at 1.016 -103.027226)
		(size 0.4572)
		(drill 0.2032)
		(layers "F.Cu" "B.Cu")
		(net "SG")
	)
	(via
		(at 93.853 -67.945)
		(size 0.508)
		(drill 0.254)
		(layers "F.Cu" "B.Cu")
		(net "SG")
	)
	(via
		(at 166.633906 -93.448886)
		(size 0.4572)
		(drill 0.2032)
		(layers "F.Cu" "B.Cu")
		(net "SG")
	)
	(via
		(at 7.216902 -110.133892)
		(size 0.4572)
		(drill 0.2032)
		(layers "F.Cu" "B.Cu")
		(net "SG")
	)
	(via
		(at 112.346994 -46.322996)
		(size 0.4572)
		(drill 0.2032)
		(layers "F.Cu" "B.Cu")
		(net "SG")
	)
	(via
		(at 64.369188 -19.3802)
		(size 0.4572)
		(drill 0.2032)
		(layers "F.Cu" "B.Cu")
		(net "SG")
	)
	(via
		(at 16.8656 -19.6596)
		(size 0.508)
		(drill 0.254)
		(layers "F.Cu" "B.Cu")
		(net "SG")
	)
	(via
		(at 98.347022 -43.323256)
		(size 0.4572)
		(drill 0.2032)
		(layers "F.Cu" "B.Cu")
		(net "SG")
	)
	(via
		(at 147.447 -16.7132)
		(size 0.508)
		(drill 0.254)
		(layers "F.Cu" "B.Cu")
		(net "SG")
	)
	(via
		(at 104.0511 -102.6033)
		(size 0.508)
		(drill 0.254)
		(layers "F.Cu" "B.Cu")
		(net "SG")
	)
	(via
		(at 93.828108 -13.766038)
		(size 0.4572)
		(drill 0.2032)
		(layers "F.Cu" "B.Cu")
		(net "SG")
	)
	(via
		(at 11.557 -32.004)
		(size 0.508)
		(drill 0.254)
		(layers "F.Cu" "B.Cu")
		(net "SG")
	)
	(via
		(at 101.0412 -65.8622)
		(size 0.508)
		(drill 0.254)
		(layers "F.Cu" "B.Cu")
		(net "SG")
	)
	(via
		(at 96.012 -69.469)
		(size 0.508)
		(drill 0.254)
		(layers "F.Cu" "B.Cu")
		(net "SG")
	)
	(via
		(at 88.442546 -27.559)
		(size 0.4572)
		(drill 0.2032)
		(layers "F.Cu" "B.Cu")
		(net "SG")
	)
	(via
		(at 128.372108 -13.766038)
		(size 0.4572)
		(drill 0.2032)
		(layers "F.Cu" "B.Cu")
		(net "SG")
	)
	(via
		(at 102.972108 -13.766038)
		(size 0.4572)
		(drill 0.2032)
		(layers "F.Cu" "B.Cu")
		(net "SG")
	)
	(via
		(at 53.952902 -110.133892)
		(size 0.4572)
		(drill 0.2032)
		(layers "F.Cu" "B.Cu")
		(net "SG")
	)
	(via
		(at 106.34726 -51.322986)
		(size 0.4572)
		(drill 0.2032)
		(layers "F.Cu" "B.Cu")
		(net "SG")
	)
	(via
		(at 1.016 -74.579226)
		(size 0.4572)
		(drill 0.2032)
		(layers "F.Cu" "B.Cu")
		(net "SG")
	)
	(via
		(at 124.308108 -13.766038)
		(size 0.4572)
		(drill 0.2032)
		(layers "F.Cu" "B.Cu")
		(net "SG")
	)
	(via
		(at 36.068 -88.9)
		(size 0.508)
		(drill 0.254)
		(layers "F.Cu" "B.Cu")
		(net "SG")
	)
	(via
		(at 121.886218 -35.272218)
		(size 0.508)
		(drill 0.254)
		(layers "F.Cu" "B.Cu")
		(net "SG")
	)
	(via
		(at 96.4692 -44.9834)
		(size 0.508)
		(drill 0.254)
		(layers "F.Cu" "B.Cu")
		(net "SG")
	)
	(via
		(at 74.168 -74.85888)
		(size 0.508)
		(drill 0.254)
		(layers "F.Cu" "B.Cu")
		(net "SG")
	)
	(via
		(at 1.016 -75.595226)
		(size 0.4572)
		(drill 0.2032)
		(layers "F.Cu" "B.Cu")
		(net "SG")
	)
	(via
		(at 133.8834 -87.7824)
		(size 0.508)
		(drill 0.254)
		(layers "F.Cu" "B.Cu")
		(net "SG")
	)
	(via
		(at 80.620108 -13.766038)
		(size 0.4572)
		(drill 0.2032)
		(layers "F.Cu" "B.Cu")
		(net "SG")
	)
	(via
		(at 136.779 -103.60025)
		(size 0.508)
		(drill 0.254)
		(layers "F.Cu" "B.Cu")
		(net "SG")
	)
	(via
		(at 1.239012 -5.516118)
		(size 0.4572)
		(drill 0.2032)
		(layers "F.Cu" "B.Cu")
		(net "SG")
	)
	(via
		(at 88.496902 -110.133892)
		(size 0.4572)
		(drill 0.2032)
		(layers "F.Cu" "B.Cu")
		(net "SG")
	)
	(via
		(at 101.34727 -40.323262)
		(size 0.4572)
		(drill 0.2032)
		(layers "F.Cu" "B.Cu")
		(net "SG")
	)
	(via
		(at 166.633906 -42.97807)
		(size 0.4572)
		(drill 0.2032)
		(layers "F.Cu" "B.Cu")
		(net "SG")
	)
	(via
		(at 44.704 -105.664)
		(size 0.508)
		(drill 0.254)
		(layers "F.Cu" "B.Cu")
		(net "SG")
	)
	(via
		(at 2.136902 -110.133892)
		(size 0.4572)
		(drill 0.2032)
		(layers "F.Cu" "B.Cu")
		(net "SG")
	)
	(via
		(at 89.154 -33.147)
		(size 0.508)
		(drill 0.254)
		(layers "F.Cu" "B.Cu")
		(net "SG")
	)
	(via
		(at 104.347264 -38.323266)
		(size 0.4572)
		(drill 0.2032)
		(layers "F.Cu" "B.Cu")
		(net "SG")
	)
	(via
		(at 106.020108 -13.766038)
		(size 0.4572)
		(drill 0.2032)
		(layers "F.Cu" "B.Cu")
		(net "SG")
	)
	(via
		(at 166.633906 -32.81807)
		(size 0.4572)
		(drill 0.2032)
		(layers "F.Cu" "B.Cu")
		(net "SG")
	)
	(via
		(at 48.006 -82.804)
		(size 0.508)
		(drill 0.254)
		(layers "F.Cu" "B.Cu")
		(net "SG")
	)
	(via
		(at 115.346988 -47.322994)
		(size 0.4572)
		(drill 0.2032)
		(layers "F.Cu" "B.Cu")
		(net "SG")
	)
	(via
		(at 109.0676 -27.305)
		(size 0.508)
		(drill 0.254)
		(layers "F.Cu" "B.Cu")
		(net "SG")
	)
	(via
		(at 13.150088 -18.6944)
		(size 0.508)
		(drill 0.254)
		(layers "F.Cu" "B.Cu")
		(net "SG")
	)
	(via
		(at 161.544 -54.900068)
		(size 0.508)
		(drill 0.254)
		(layers "F.Cu" "B.Cu")
		(net "SG")
	)
	(via
		(at 111.346996 -38.323266)
		(size 0.4572)
		(drill 0.2032)
		(layers "F.Cu" "B.Cu")
		(net "SG")
	)
	(via
		(at 101.346 -56.237378)
		(size 0.508)
		(drill 0.254)
		(layers "F.Cu" "B.Cu")
		(net "SG")
	)
	(via
		(at 34.417 -100.584)
		(size 0.508)
		(drill 0.254)
		(layers "F.Cu" "B.Cu")
		(net "SG")
	)
	(via
		(at 98.347022 -41.32326)
		(size 0.4572)
		(drill 0.2032)
		(layers "F.Cu" "B.Cu")
		(net "SG")
	)
	(via
		(at 157.584902 -110.133892)
		(size 0.4572)
		(drill 0.2032)
		(layers "F.Cu" "B.Cu")
		(net "SG")
	)
	(via
		(at 79.352902 -110.133892)
		(size 0.4572)
		(drill 0.2032)
		(layers "F.Cu" "B.Cu")
		(net "SG")
	)
	(via
		(at 4.287012 -5.516118)
		(size 0.4572)
		(drill 0.2032)
		(layers "F.Cu" "B.Cu")
		(net "SG")
	)
	(via
		(at 87.249 -65.7606)
		(size 0.508)
		(drill 0.254)
		(layers "F.Cu" "B.Cu")
		(net "SG")
	)
	(via
		(at 121.285 -65.786)
		(size 0.508)
		(drill 0.254)
		(layers "F.Cu" "B.Cu")
		(net "SG")
	)
	(via
		(at 69.192902 -110.133892)
		(size 0.4572)
		(drill 0.2032)
		(layers "F.Cu" "B.Cu")
		(net "SG")
	)
	(via
		(at 95.0722 -32.766)
		(size 0.508)
		(drill 0.254)
		(layers "F.Cu" "B.Cu")
		(net "SG")
	)
	(via
		(at 87.706454 -49.859946)
		(size 0.4572)
		(drill 0.2032)
		(layers "F.Cu" "B.Cu")
		(net "SG")
	)
	(via
		(at 22.1488 -65.6082)
		(size 0.508)
		(drill 0.254)
		(layers "F.Cu" "B.Cu")
		(net "SG")
	)
	(via
		(at 92.6338 -43.0276)
		(size 0.508)
		(drill 0.254)
		(layers "F.Cu" "B.Cu")
		(net "SG")
	)
	(via
		(at 97.5106 -94.6404)
		(size 0.508)
		(drill 0.254)
		(layers "F.Cu" "B.Cu")
		(net "SG")
	)
	(via
		(at 89.5604 -43.0276)
		(size 0.508)
		(drill 0.254)
		(layers "F.Cu" "B.Cu")
		(net "SG")
	)
	(via
		(at 123.040902 -110.133892)
		(size 0.4572)
		(drill 0.2032)
		(layers "F.Cu" "B.Cu")
		(net "SG")
	)
	(via
		(at 65.913 -17.8054)
		(size 0.508)
		(drill 0.254)
		(layers "F.Cu" "B.Cu")
		(net "SG")
	)
	(via
		(at 44.3484 -103.1494)
		(size 0.508)
		(drill 0.254)
		(layers "F.Cu" "B.Cu")
		(net "SG")
	)
	(via
		(at 98.347022 -45.322998)
		(size 0.4572)
		(drill 0.2032)
		(layers "F.Cu" "B.Cu")
		(net "SG")
	)
	(via
		(at 87.706454 -47.421546)
		(size 0.4572)
		(drill 0.2032)
		(layers "F.Cu" "B.Cu")
		(net "SG")
	)
	(via
		(at 100.965 -79.4766)
		(size 0.508)
		(drill 0.254)
		(layers "F.Cu" "B.Cu")
		(net "SG")
	)
	(via
		(at 133.0198 -97.5614)
		(size 0.508)
		(drill 0.254)
		(layers "F.Cu" "B.Cu")
		(net "SG")
	)
	(via
		(at 99.34702 -45.322998)
		(size 0.4572)
		(drill 0.2032)
		(layers "F.Cu" "B.Cu")
		(net "SG")
	)
	(via
		(at 128.5494 -71.2724)
		(size 0.508)
		(drill 0.254)
		(layers "F.Cu" "B.Cu")
		(net "SG")
	)
	(via
		(at 31.600902 -110.133892)
		(size 0.4572)
		(drill 0.2032)
		(layers "F.Cu" "B.Cu")
		(net "SG")
	)
	(via
		(at 166.633906 -19.61007)
		(size 0.4572)
		(drill 0.2032)
		(layers "F.Cu" "B.Cu")
		(net "SG")
	)
	(via
		(at 138.280902 -110.133892)
		(size 0.4572)
		(drill 0.2032)
		(layers "F.Cu" "B.Cu")
		(net "SG")
	)
	(via
		(at 110.363 -19.558)
		(size 0.508)
		(drill 0.254)
		(layers "F.Cu" "B.Cu")
		(net "SG")
	)
	(via
		(at 48.872902 -110.133892)
		(size 0.4572)
		(drill 0.2032)
		(layers "F.Cu" "B.Cu")
		(net "SG")
	)
	(via
		(at 132.184902 -110.133892)
		(size 0.4572)
		(drill 0.2032)
		(layers "F.Cu" "B.Cu")
		(net "SG")
	)
	(via
		(at 17.1958 -16.51)
		(size 0.508)
		(drill 0.254)
		(layers "F.Cu" "B.Cu")
		(net "SG")
	)
	(via
		(at 103.347266 -37.323268)
		(size 0.4572)
		(drill 0.2032)
		(layers "F.Cu" "B.Cu")
		(net "SG")
	)
	(via
		(at 166.633906 -101.576886)
		(size 0.4572)
		(drill 0.2032)
		(layers "F.Cu" "B.Cu")
		(net "SG")
	)
	(via
		(at 67.142106 -10.5918)
		(size 0.4572)
		(drill 0.2032)
		(layers "F.Cu" "B.Cu")
		(net "SG")
	)
	(via
		(at 32.258 -100.853494)
		(size 0.508)
		(drill 0.254)
		(layers "F.Cu" "B.Cu")
		(net "SG")
	)
	(via
		(at 105.768902 -110.133892)
		(size 0.4572)
		(drill 0.2032)
		(layers "F.Cu" "B.Cu")
		(net "SG")
	)
	(via
		(at 105.059988 -19.05)
		(size 0.4572)
		(drill 0.2032)
		(layers "F.Cu" "B.Cu")
		(net "SG")
	)
	(via
		(at 147.3708 -91.8718)
		(size 0.508)
		(drill 0.254)
		(layers "F.Cu" "B.Cu")
		(net "SG")
	)
	(via
		(at 108.347256 -40.323262)
		(size 0.4572)
		(drill 0.2032)
		(layers "F.Cu" "B.Cu")
		(net "SG")
	)
	(via
		(at 75.876404 -12.565634)
		(size 0.4572)
		(drill 0.2032)
		(layers "F.Cu" "B.Cu")
		(net "SG")
	)
	(via
		(at 71.6788 -45.496734)
		(size 0.508)
		(drill 0.254)
		(layers "F.Cu" "B.Cu")
		(net "SG")
	)
	(via
		(at 114.3 -27.4828)
		(size 0.508)
		(drill 0.254)
		(layers "F.Cu" "B.Cu")
		(net "SG")
	)
	(via
		(at 133.394704 -104.62895)
		(size 0.508)
		(drill 0.254)
		(layers "F.Cu" "B.Cu")
		(net "SG")
	)
	(via
		(at 114.53622 -31.030418)
		(size 0.4572)
		(drill 0.2032)
		(layers "F.Cu" "B.Cu")
		(net "SG")
	)
	(via
		(at 17.376902 -110.133892)
		(size 0.4572)
		(drill 0.2032)
		(layers "F.Cu" "B.Cu")
		(net "SG")
	)
	(via
		(at 126.340108 -13.766038)
		(size 0.4572)
		(drill 0.2032)
		(layers "F.Cu" "B.Cu")
		(net "SG")
	)
	(via
		(at 160.909 -50.005996)
		(size 0.508)
		(drill 0.254)
		(layers "F.Cu" "B.Cu")
		(net "SG")
	)
	(via
		(at 90.528902 -110.133892)
		(size 0.4572)
		(drill 0.2032)
		(layers "F.Cu" "B.Cu")
		(net "SG")
	)
	(via
		(at 4.064 -76.835)
		(size 0.508)
		(drill 0.254)
		(layers "F.Cu" "B.Cu")
		(net "SG")
	)
	(via
		(at 112.522 -100.711)
		(size 0.4572)
		(drill 0.2032)
		(layers "F.Cu" "B.Cu")
		(net "SG")
	)
	(via
		(at 116.292376 -33.377632)
		(size 0.4572)
		(drill 0.2032)
		(layers "F.Cu" "B.Cu")
		(net "SG")
	)
	(via
		(at 22.72284 -13.766038)
		(size 0.4572)
		(drill 0.2032)
		(layers "F.Cu" "B.Cu")
		(net "SG")
	)
	(via
		(at 143.612108 -13.766038)
		(size 0.4572)
		(drill 0.2032)
		(layers "F.Cu" "B.Cu")
		(net "SG")
	)
	(via
		(at 159.868108 -13.766038)
		(size 0.4572)
		(drill 0.2032)
		(layers "F.Cu" "B.Cu")
		(net "SG")
	)
	(via
		(at 125.984 -52.197)
		(size 0.508)
		(drill 0.254)
		(layers "F.Cu" "B.Cu")
		(net "SG")
	)
	(via
		(at 83.947 -74.041)
		(size 0.508)
		(drill 0.254)
		(layers "F.Cu" "B.Cu")
		(net "SG")
	)
	(via
		(at 13.98397 -6.368542)
		(size 0.4572)
		(drill 0.2032)
		(layers "F.Cu" "B.Cu")
		(net "SG")
	)
	(via
		(at 93.218 -61.275722)
		(size 0.508)
		(drill 0.254)
		(layers "F.Cu" "B.Cu")
		(net "SG")
	)
	(via
		(at 162.664902 -110.133892)
		(size 0.4572)
		(drill 0.2032)
		(layers "F.Cu" "B.Cu")
		(net "SG")
	)
	(via
		(at 166.633906 -85.320886)
		(size 0.4572)
		(drill 0.2032)
		(layers "F.Cu" "B.Cu")
		(net "SG")
	)
	(via
		(at 43.792902 -110.133892)
		(size 0.4572)
		(drill 0.2032)
		(layers "F.Cu" "B.Cu")
		(net "SG")
	)
	(via
		(at 101.34727 -45.322998)
		(size 0.4572)
		(drill 0.2032)
		(layers "F.Cu" "B.Cu")
		(net "SG")
	)
	(via
		(at 1.016 -86.771226)
		(size 0.4572)
		(drill 0.2032)
		(layers "F.Cu" "B.Cu")
		(net "SG")
	)
	(via
		(at 108.347256 -41.32326)
		(size 0.4572)
		(drill 0.2032)
		(layers "F.Cu" "B.Cu")
		(net "SG")
	)
	(via
		(at 44.3484 -104.2924)
		(size 0.508)
		(drill 0.254)
		(layers "F.Cu" "B.Cu")
		(net "SG")
	)
	(via
		(at 166.633906 -43.99407)
		(size 0.4572)
		(drill 0.2032)
		(layers "F.Cu" "B.Cu")
		(net "SG")
	)
	(via
		(at 43.1419 -75.9333)
		(size 0.508)
		(drill 0.254)
		(layers "F.Cu" "B.Cu")
		(net "SG")
	)
	(via
		(at 110.346998 -42.323258)
		(size 0.4572)
		(drill 0.2032)
		(layers "F.Cu" "B.Cu")
		(net "SG")
	)
	(via
		(at 4.064 -78.105)
		(size 0.508)
		(drill 0.254)
		(layers "F.Cu" "B.Cu")
		(net "SG")
	)
	(via
		(at 61.326014 -54.61)
		(size 0.508)
		(drill 0.254)
		(layers "F.Cu" "B.Cu")
		(net "SG")
	)
	(via
		(at 81.8388 -82.55)
		(size 0.4572)
		(drill 0.2032)
		(layers "F.Cu" "B.Cu")
		(net "SG")
	)
	(via
		(at 24.003 -26.67)
		(size 0.508)
		(drill 0.254)
		(layers "F.Cu" "B.Cu")
		(net "SG")
	)
	(via
		(at 106.34726 -45.322998)
		(size 0.4572)
		(drill 0.2032)
		(layers "F.Cu" "B.Cu")
		(net "SG")
	)
	(via
		(at 24.280622 -84.670138)
		(size 0.508)
		(drill 0.254)
		(layers "F.Cu" "B.Cu")
		(net "SG")
	)
	(via
		(at 1.016 -78.643226)
		(size 0.4572)
		(drill 0.2032)
		(layers "F.Cu" "B.Cu")
		(net "SG")
	)
	(via
		(at 119.34698 -45.322998)
		(size 0.4572)
		(drill 0.2032)
		(layers "F.Cu" "B.Cu")
		(net "SG")
	)
	(via
		(at 23.73884 -13.766038)
		(size 0.4572)
		(drill 0.2032)
		(layers "F.Cu" "B.Cu")
		(net "SG")
	)
	(via
		(at 96.876108 -13.766038)
		(size 0.4572)
		(drill 0.2032)
		(layers "F.Cu" "B.Cu")
		(net "SG")
	)
	(via
		(at 18.65884 -13.766038)
		(size 0.4572)
		(drill 0.2032)
		(layers "F.Cu" "B.Cu")
		(net "SG")
	)
	(via
		(at 36.83 -75.311)
		(size 0.508)
		(drill 0.254)
		(layers "F.Cu" "B.Cu")
		(net "SG")
	)
	(via
		(at 58.039 -97.155)
		(size 0.508)
		(drill 0.254)
		(layers "F.Cu" "B.Cu")
		(net "SG")
	)
	(via
		(at 72.7964 -50.4698)
		(size 0.4572)
		(drill 0.2032)
		(layers "F.Cu" "B.Cu")
		(net "SG")
	)
	(via
		(at 102.347268 -53.322982)
		(size 0.4572)
		(drill 0.2032)
		(layers "F.Cu" "B.Cu")
		(net "SG")
	)
	(via
		(at 166.633906 -37.89807)
		(size 0.4572)
		(drill 0.2032)
		(layers "F.Cu" "B.Cu")
		(net "SG")
	)
	(via
		(at 16.764 -23.1394)
		(size 0.508)
		(drill 0.254)
		(layers "F.Cu" "B.Cu")
		(net "SG")
	)
	(via
		(at 59.032902 -110.133892)
		(size 0.4572)
		(drill 0.2032)
		(layers "F.Cu" "B.Cu")
		(net "SG")
	)
	(via
		(at 114.148108 -13.766038)
		(size 0.4572)
		(drill 0.2032)
		(layers "F.Cu" "B.Cu")
		(net "SG")
	)
	(via
		(at 103.347266 -43.323256)
		(size 0.4572)
		(drill 0.2032)
		(layers "F.Cu" "B.Cu")
		(net "SG")
	)
	(via
		(at 81.6102 -107.5944)
		(size 0.508)
		(drill 0.254)
		(layers "F.Cu" "B.Cu")
		(net "SG")
	)
	(via
		(at 27.94 -92.456)
		(size 0.508)
		(drill 0.254)
		(layers "F.Cu" "B.Cu")
		(net "SG")
	)
	(via
		(at 166.633906 -109.704886)
		(size 0.4572)
		(drill 0.2032)
		(layers "F.Cu" "B.Cu")
		(net "SG")
	)
	(via
		(at 90.424 -33.147)
		(size 0.508)
		(drill 0.254)
		(layers "F.Cu" "B.Cu")
		(net "SG")
	)
	(via
		(at 31.369 -88.265)
		(size 0.508)
		(drill 0.254)
		(layers "F.Cu" "B.Cu")
		(net "SG")
	)
	(via
		(at 87.732108 -13.766038)
		(size 0.4572)
		(drill 0.2032)
		(layers "F.Cu" "B.Cu")
		(net "SG")
	)
	(via
		(at 96.393 -18.415)
		(size 0.4572)
		(drill 0.2032)
		(layers "F.Cu" "B.Cu")
		(net "SG")
	)
	(via
		(at 98.347022 -35.323018)
		(size 0.4572)
		(drill 0.2032)
		(layers "F.Cu" "B.Cu")
		(net "SG")
	)
	(via
		(at 166.633906 -97.512886)
		(size 0.4572)
		(drill 0.2032)
		(layers "F.Cu" "B.Cu")
		(net "SG")
	)
	(via
		(at 127.356108 -13.766038)
		(size 0.4572)
		(drill 0.2032)
		(layers "F.Cu" "B.Cu")
		(net "SG")
	)
	(via
		(at 166.633906 -80.240886)
		(size 0.4572)
		(drill 0.2032)
		(layers "F.Cu" "B.Cu")
		(net "SG")
	)
	(via
		(at 48.133 -81.026)
		(size 0.508)
		(drill 0.254)
		(layers "F.Cu" "B.Cu")
		(net "SG")
	)
	(via
		(at 9.248902 -110.133892)
		(size 0.4572)
		(drill 0.2032)
		(layers "F.Cu" "B.Cu")
		(net "SG")
	)
	(via
		(at 89.027 -58.293)
		(size 0.508)
		(drill 0.254)
		(layers "F.Cu" "B.Cu")
		(net "SG")
	)
	(via
		(at 104.7369 -101.9175)
		(size 0.508)
		(drill 0.254)
		(layers "F.Cu" "B.Cu")
		(net "SG")
	)
	(via
		(at 112.346994 -39.323264)
		(size 0.4572)
		(drill 0.2032)
		(layers "F.Cu" "B.Cu")
		(net "SG")
	)
	(via
		(at 141.986 -22.5552)
		(size 0.508)
		(drill 0.254)
		(layers "F.Cu" "B.Cu")
		(net "SG")
	)
	(via
		(at 5.184902 -110.133892)
		(size 0.4572)
		(drill 0.2032)
		(layers "F.Cu" "B.Cu")
		(net "SG")
	)
	(via
		(at 166.633906 -86.336886)
		(size 0.4572)
		(drill 0.2032)
		(layers "F.Cu" "B.Cu")
		(net "SG")
	)
	(via
		(at 111.100108 -13.766038)
		(size 0.4572)
		(drill 0.2032)
		(layers "F.Cu" "B.Cu")
		(net "SG")
	)
	(via
		(at 147.3962 -97.9678)
		(size 0.508)
		(drill 0.254)
		(layers "F.Cu" "B.Cu")
		(net "SG")
	)
	(via
		(at 33.528 -96.266)
		(size 0.508)
		(drill 0.254)
		(layers "F.Cu" "B.Cu")
		(net "SG")
	)
	(via
		(at 91.796108 -13.766038)
		(size 0.4572)
		(drill 0.2032)
		(layers "F.Cu" "B.Cu")
		(net "SG")
	)
	(via
		(at 42.776902 -110.133892)
		(size 0.4572)
		(drill 0.2032)
		(layers "F.Cu" "B.Cu")
		(net "SG")
	)
	(via
		(at 98.347022 -37.323268)
		(size 0.4572)
		(drill 0.2032)
		(layers "F.Cu" "B.Cu")
		(net "SG")
	)
	(via
		(at 91.821 -75.2094)
		(size 0.508)
		(drill 0.254)
		(layers "F.Cu" "B.Cu")
		(net "SG")
	)
	(via
		(at 3.271012 -5.516118)
		(size 0.4572)
		(drill 0.2032)
		(layers "F.Cu" "B.Cu")
		(net "SG")
	)
	(via
		(at 13.431012 -5.516118)
		(size 0.4572)
		(drill 0.2032)
		(layers "F.Cu" "B.Cu")
		(net "SG")
	)
	(via
		(at 55.88 -17.526)
		(size 0.508)
		(drill 0.254)
		(layers "F.Cu" "B.Cu")
		(net "SG")
	)
	(via
		(at 135.636 -40.767)
		(size 0.508)
		(drill 0.254)
		(layers "F.Cu" "B.Cu")
		(net "SG")
	)
	(via
		(at 136.398 -17.526)
		(size 0.508)
		(drill 0.254)
		(layers "F.Cu" "B.Cu")
		(net "SG")
	)
	(via
		(at 26.78684 -13.766038)
		(size 0.4572)
		(drill 0.2032)
		(layers "F.Cu" "B.Cu")
		(net "SG")
	)
	(via
		(at 100.347018 -49.32299)
		(size 0.4572)
		(drill 0.2032)
		(layers "F.Cu" "B.Cu")
		(net "SG")
	)
	(via
		(at 135.232902 -110.133892)
		(size 0.4572)
		(drill 0.2032)
		(layers "F.Cu" "B.Cu")
		(net "SG")
	)
	(via
		(at 135.2296 -87.7824)
		(size 0.508)
		(drill 0.254)
		(layers "F.Cu" "B.Cu")
		(net "SG")
	)
	(via
		(at 106.34726 -42.323258)
		(size 0.4572)
		(drill 0.2032)
		(layers "F.Cu" "B.Cu")
		(net "SG")
	)
	(via
		(at 88.459056 -26.595578)
		(size 0.4572)
		(drill 0.2032)
		(layers "F.Cu" "B.Cu")
		(net "SG")
	)
	(via
		(at 108.6612 -25.4762)
		(size 0.508)
		(drill 0.254)
		(layers "F.Cu" "B.Cu")
		(net "SG")
	)
	(via
		(at 62.080902 -110.133892)
		(size 0.4572)
		(drill 0.2032)
		(layers "F.Cu" "B.Cu")
		(net "SG")
	)
	(via
		(at 22.456902 -110.133892)
		(size 0.4572)
		(drill 0.2032)
		(layers "F.Cu" "B.Cu")
		(net "SG")
	)
	(via
		(at 56.261 -96.139)
		(size 0.508)
		(drill 0.254)
		(layers "F.Cu" "B.Cu")
		(net "SG")
	)
	(via
		(at 120.346978 -52.322984)
		(size 0.4572)
		(drill 0.2032)
		(layers "F.Cu" "B.Cu")
		(net "SG")
	)
	(via
		(at 93.576902 -110.133892)
		(size 0.4572)
		(drill 0.2032)
		(layers "F.Cu" "B.Cu")
		(net "SG")
	)
	(via
		(at 137.922 -100.7618)
		(size 0.508)
		(drill 0.254)
		(layers "F.Cu" "B.Cu")
		(net "SG")
	)
	(via
		(at 31.77413 -77.74813)
		(size 0.508)
		(drill 0.254)
		(layers "F.Cu" "B.Cu")
		(net "SG")
	)
	(via
		(at 1.016 -77.627226)
		(size 0.4572)
		(drill 0.2032)
		(layers "F.Cu" "B.Cu")
		(net "SG")
	)
	(via
		(at 111.633 -85.824568)
		(size 0.4572)
		(drill 0.2032)
		(layers "F.Cu" "B.Cu")
		(net "SG")
	)
	(via
		(at 117.729 -21.971)
		(size 0.508)
		(drill 0.254)
		(layers "F.Cu" "B.Cu")
		(net "SG")
	)
	(via
		(at 166.633906 -83.288886)
		(size 0.4572)
		(drill 0.2032)
		(layers "F.Cu" "B.Cu")
		(net "SG")
	)
	(via
		(at 116.180108 -13.766038)
		(size 0.4572)
		(drill 0.2032)
		(layers "F.Cu" "B.Cu")
		(net "SG")
	)
	(via
		(at 100.347018 -35.323018)
		(size 0.4572)
		(drill 0.2032)
		(layers "F.Cu" "B.Cu")
		(net "SG")
	)
	(via
		(at 140.564108 -13.766038)
		(size 0.4572)
		(drill 0.2032)
		(layers "F.Cu" "B.Cu")
		(net "SG")
	)
	(via
		(at 110.084108 -13.766038)
		(size 0.4572)
		(drill 0.2032)
		(layers "F.Cu" "B.Cu")
		(net "SG")
	)
	(via
		(at 113.90122 -22.74316)
		(size 0.508)
		(drill 0.254)
		(layers "F.Cu" "B.Cu")
		(net "SG")
	)
	(via
		(at 166.633906 -87.352886)
		(size 0.4572)
		(drill 0.2032)
		(layers "F.Cu" "B.Cu")
		(net "SG")
	)
	(via
		(at 48.26 -76.581)
		(size 0.508)
		(drill 0.254)
		(layers "F.Cu" "B.Cu")
		(net "SG")
	)
	(via
		(at 119.992902 -110.133892)
		(size 0.4572)
		(drill 0.2032)
		(layers "F.Cu" "B.Cu")
		(net "SG")
	)
	(via
		(at 81.384902 -110.133892)
		(size 0.4572)
		(drill 0.2032)
		(layers "F.Cu" "B.Cu")
		(net "SG")
	)
	(via
		(at 73.152 -74.422)
		(size 0.508)
		(drill 0.254)
		(layers "F.Cu" "B.Cu")
		(net "SG")
	)
	(via
		(at 40.4114 -89.0016)
		(size 0.508)
		(drill 0.254)
		(layers "F.Cu" "B.Cu")
		(net "SG")
	)
	(via
		(at 103.736902 -110.133892)
		(size 0.4572)
		(drill 0.2032)
		(layers "F.Cu" "B.Cu")
		(net "SG")
	)
	(via
		(at 154.536902 -110.133892)
		(size 0.4572)
		(drill 0.2032)
		(layers "F.Cu" "B.Cu")
		(net "SG")
	)
	(via
		(at 1.120902 -110.133892)
		(size 0.4572)
		(drill 0.2032)
		(layers "F.Cu" "B.Cu")
		(net "SG")
	)
	(via
		(at 137.516108 -13.766038)
		(size 0.4572)
		(drill 0.2032)
		(layers "F.Cu" "B.Cu")
		(net "SG")
	)
	(via
		(at 143.1798 -89.5096)
		(size 0.508)
		(drill 0.254)
		(layers "F.Cu" "B.Cu")
		(net "SG")
	)
	(via
		(at 26.520902 -110.133892)
		(size 0.4572)
		(drill 0.2032)
		(layers "F.Cu" "B.Cu")
		(net "SG")
	)
	(via
		(at 70.208902 -110.133892)
		(size 0.4572)
		(drill 0.2032)
		(layers "F.Cu" "B.Cu")
		(net "SG")
	)
	(via
		(at 67.133216 -7.3406)
		(size 0.4572)
		(drill 0.2032)
		(layers "F.Cu" "B.Cu")
		(net "SG")
	)
	(via
		(at 34.365946 -6.225286)
		(size 0.4572)
		(drill 0.2032)
		(layers "F.Cu" "B.Cu")
		(net "SG")
	)
	(via
		(at 124.9172 -70.5358)
		(size 0.508)
		(drill 0.254)
		(layers "F.Cu" "B.Cu")
		(net "SG")
	)
	(via
		(at 166.633906 -102.592886)
		(size 0.4572)
		(drill 0.2032)
		(layers "F.Cu" "B.Cu")
		(net "SG")
	)
	(via
		(at 61.930788 -19.3802)
		(size 0.4572)
		(drill 0.2032)
		(layers "F.Cu" "B.Cu")
		(net "SG")
	)
	(via
		(at 105.004108 -13.766038)
		(size 0.4572)
		(drill 0.2032)
		(layers "F.Cu" "B.Cu")
		(net "SG")
	)
	(via
		(at 1.016 -107.091226)
		(size 0.4572)
		(drill 0.2032)
		(layers "F.Cu" "B.Cu")
		(net "SG")
	)
	(via
		(at 29.718 -100.838)
		(size 0.508)
		(drill 0.254)
		(layers "F.Cu" "B.Cu")
		(net "SG")
	)
	(via
		(at 137.3886 -51.181)
		(size 0.508)
		(drill 0.254)
		(layers "F.Cu" "B.Cu")
		(net "SG")
	)
	(via
		(at 166.633906 -88.368886)
		(size 0.4572)
		(drill 0.2032)
		(layers "F.Cu" "B.Cu")
		(net "SG")
	)
	(via
		(at 2.255012 -5.516118)
		(size 0.4572)
		(drill 0.2032)
		(layers "F.Cu" "B.Cu")
		(net "SG")
	)
	(via
		(at 22.5806 -17.018)
		(size 0.508)
		(drill 0.254)
		(layers "F.Cu" "B.Cu")
		(net "SG")
	)
	(via
		(at 104.7369 -100.8761)
		(size 0.508)
		(drill 0.254)
		(layers "F.Cu" "B.Cu")
		(net "SG")
	)
	(via
		(at 166.633906 -40.94607)
		(size 0.4572)
		(drill 0.2032)
		(layers "F.Cu" "B.Cu")
		(net "SG")
	)
	(via
		(at 8.351012 -5.516118)
		(size 0.4572)
		(drill 0.2032)
		(layers "F.Cu" "B.Cu")
		(net "SG")
	)
	(via
		(at 139.548108 -13.766038)
		(size 0.4572)
		(drill 0.2032)
		(layers "F.Cu" "B.Cu")
		(net "SG")
	)
	(via
		(at 69.166486 -7.3406)
		(size 0.4572)
		(drill 0.2032)
		(layers "F.Cu" "B.Cu")
		(net "SG")
	)
	(via
		(at 1.016 -89.819226)
		(size 0.4572)
		(drill 0.2032)
		(layers "F.Cu" "B.Cu")
		(net "SG")
	)
	(via
		(at 156.568902 -110.133892)
		(size 0.4572)
		(drill 0.2032)
		(layers "F.Cu" "B.Cu")
		(net "SG")
	)
	(via
		(at 64.516 -54.229)
		(size 0.508)
		(drill 0.254)
		(layers "F.Cu" "B.Cu")
		(net "SG")
	)
	(via
		(at 98.347022 -34.32302)
		(size 0.4572)
		(drill 0.2032)
		(layers "F.Cu" "B.Cu")
		(net "SG")
	)
	(via
		(at 166.633906 -105.640886)
		(size 0.4572)
		(drill 0.2032)
		(layers "F.Cu" "B.Cu")
		(net "SG")
	)
	(via
		(at 14.605 -73.406)
		(size 0.508)
		(drill 0.254)
		(layers "F.Cu" "B.Cu")
		(net "SG")
	)
	(via
		(at 146.3802 -94.2848)
		(size 0.508)
		(drill 0.254)
		(layers "F.Cu" "B.Cu")
		(net "SG")
	)
	(via
		(at 112.8268 -25.527)
		(size 0.508)
		(drill 0.254)
		(layers "F.Cu" "B.Cu")
		(net "SG")
	)
	(via
		(at 142.4051 -17.8943)
		(size 0.508)
		(drill 0.254)
		(layers "F.Cu" "B.Cu")
		(net "SG")
	)
	(via
		(at 147.3962 -96.6978)
		(size 0.508)
		(drill 0.254)
		(layers "F.Cu" "B.Cu")
		(net "SG")
	)
	(via
		(at 116.586 -82.804)
		(size 0.508)
		(drill 0.254)
		(layers "F.Cu" "B.Cu")
		(net "SG")
	)
	(via
		(at 84.201 -95.504)
		(size 0.508)
		(drill 0.254)
		(layers "F.Cu" "B.Cu")
		(net "SG")
	)
	(via
		(at 156.820108 -13.766038)
		(size 0.4572)
		(drill 0.2032)
		(layers "F.Cu" "B.Cu")
		(net "SG")
	)
	(via
		(at 1.016 -85.755226)
		(size 0.4572)
		(drill 0.2032)
		(layers "F.Cu" "B.Cu")
		(net "SG")
	)
	(via
		(at 75.14209 -10.5918)
		(size 0.4572)
		(drill 0.2032)
		(layers "F.Cu" "B.Cu")
		(net "SG")
	)
	(via
		(at 85.852 -80.01)
		(size 0.508)
		(drill 0.254)
		(layers "F.Cu" "B.Cu")
		(net "SG")
	)
	(via
		(at 21.1582 -22.1234)
		(size 0.508)
		(drill 0.254)
		(layers "F.Cu" "B.Cu")
		(net "SG")
	)
	(via
		(at 23.472902 -110.133892)
		(size 0.4572)
		(drill 0.2032)
		(layers "F.Cu" "B.Cu")
		(net "SG")
	)
	(via
		(at 42.799 -74.676)
		(size 0.508)
		(drill 0.254)
		(layers "F.Cu" "B.Cu")
		(net "SG")
	)
	(via
		(at 52.9082 -73.533)
		(size 0.4572)
		(drill 0.2032)
		(layers "F.Cu" "B.Cu")
		(net "SG")
	)
	(via
		(at 71.142098 -10.5918)
		(size 0.4572)
		(drill 0.2032)
		(layers "F.Cu" "B.Cu")
		(net "SG")
	)
	(via
		(at 93.86824 -54.102)
		(size 0.508)
		(drill 0.254)
		(layers "F.Cu" "B.Cu")
		(net "SG")
	)
	(via
		(at 37.696902 -110.133892)
		(size 0.4572)
		(drill 0.2032)
		(layers "F.Cu" "B.Cu")
		(net "SG")
	)
	(via
		(at 14.111732 -12.456414)
		(size 0.4572)
		(drill 0.2032)
		(layers "F.Cu" "B.Cu")
		(net "SG")
	)
	(via
		(at 97.640902 -110.133892)
		(size 0.4572)
		(drill 0.2032)
		(layers "F.Cu" "B.Cu")
		(net "SG")
	)
	(via
		(at 104.347264 -45.322998)
		(size 0.4572)
		(drill 0.2032)
		(layers "F.Cu" "B.Cu")
		(net "SG")
	)
	(via
		(at 116.84 -73.533)
		(size 0.508)
		(drill 0.254)
		(layers "F.Cu" "B.Cu")
		(net "SG")
	)
	(via
		(at 106.34726 -40.323262)
		(size 0.4572)
		(drill 0.2032)
		(layers "F.Cu" "B.Cu")
		(net "SG")
	)
	(via
		(at 30.48 -93.472)
		(size 0.508)
		(drill 0.254)
		(layers "F.Cu" "B.Cu")
		(net "SG")
	)
	(via
		(at 117.346984 -40.323262)
		(size 0.4572)
		(drill 0.2032)
		(layers "F.Cu" "B.Cu")
		(net "SG")
	)
	(via
		(at 166.633906 -41.96207)
		(size 0.4572)
		(drill 0.2032)
		(layers "F.Cu" "B.Cu")
		(net "SG")
	)
	(via
		(at 39.728902 -110.133892)
		(size 0.4572)
		(drill 0.2032)
		(layers "F.Cu" "B.Cu")
		(net "SG")
	)
	(via
		(at 111.633 -67.691)
		(size 0.508)
		(drill 0.254)
		(layers "F.Cu" "B.Cu")
		(net "SG")
	)
	(via
		(at 112.776 -57.404)
		(size 0.508)
		(drill 0.254)
		(layers "F.Cu" "B.Cu")
		(net "SG")
	)
	(via
		(at 85.448902 -110.133892)
		(size 0.4572)
		(drill 0.2032)
		(layers "F.Cu" "B.Cu")
		(net "SG")
	)
	(via
		(at 61.064902 -110.133892)
		(size 0.4572)
		(drill 0.2032)
		(layers "F.Cu" "B.Cu")
		(net "SG")
	)
	(via
		(at 34.365946 -11.305286)
		(size 0.4572)
		(drill 0.2032)
		(layers "F.Cu" "B.Cu")
		(net "SG")
	)
	(via
		(at 115.316 -99.949)
		(size 0.508)
		(drill 0.254)
		(layers "F.Cu" "B.Cu")
		(net "SG")
	)
	(via
		(at 125.984 -42.545)
		(size 0.508)
		(drill 0.254)
		(layers "F.Cu" "B.Cu")
		(net "SG")
	)
	(via
		(at 166.633906 -22.65807)
		(size 0.4572)
		(drill 0.2032)
		(layers "F.Cu" "B.Cu")
		(net "SG")
	)
	(via
		(at 32.766 -94.107)
		(size 0.508)
		(drill 0.254)
		(layers "F.Cu" "B.Cu")
		(net "SG")
	)
	(via
		(at 166.633906 -29.77007)
		(size 0.4572)
		(drill 0.2032)
		(layers "F.Cu" "B.Cu")
		(net "SG")
	)
	(via
		(at 134.216902 -110.133892)
		(size 0.4572)
		(drill 0.2032)
		(layers "F.Cu" "B.Cu")
		(net "SG")
	)
	(via
		(at 119.634 -65.8368)
		(size 0.508)
		(drill 0.254)
		(layers "F.Cu" "B.Cu")
		(net "SG")
	)
	(via
		(at 18.1356 -56.3118)
		(size 0.508)
		(drill 0.254)
		(layers "F.Cu" "B.Cu")
		(net "SG")
	)
	(via
		(at 30.48 -92.583)
		(size 0.508)
		(drill 0.254)
		(layers "F.Cu" "B.Cu")
		(net "SG")
	)
	(via
		(at 108.347256 -34.32302)
		(size 0.4572)
		(drill 0.2032)
		(layers "F.Cu" "B.Cu")
		(net "SG")
	)
	(via
		(at 143.088614 -15.773908)
		(size 0.508)
		(drill 0.254)
		(layers "F.Cu" "B.Cu")
		(net "SG")
	)
	(via
		(at 45.3644 -96.1644)
		(size 0.508)
		(drill 0.254)
		(layers "F.Cu" "B.Cu")
		(net "SG")
	)
	(via
		(at 166.633906 -26.72207)
		(size 0.4572)
		(drill 0.2032)
		(layers "F.Cu" "B.Cu")
		(net "SG")
	)
	(via
		(at 27.80284 -13.766038)
		(size 0.4572)
		(drill 0.2032)
		(layers "F.Cu" "B.Cu")
		(net "SG")
	)
	(via
		(at 45.824902 -110.133892)
		(size 0.4572)
		(drill 0.2032)
		(layers "F.Cu" "B.Cu")
		(net "SG")
	)
	(via
		(at 166.633906 -23.67407)
		(size 0.4572)
		(drill 0.2032)
		(layers "F.Cu" "B.Cu")
		(net "SG")
	)
	(via
		(at 11.557 -40.894)
		(size 0.508)
		(drill 0.254)
		(layers "F.Cu" "B.Cu")
		(net "SG")
	)
	(via
		(at 18.392902 -110.133892)
		(size 0.4572)
		(drill 0.2032)
		(layers "F.Cu" "B.Cu")
		(net "SG")
	)
	(via
		(at 136.500108 -13.766038)
		(size 0.4572)
		(drill 0.2032)
		(layers "F.Cu" "B.Cu")
		(net "SG")
	)
	(via
		(at 61.089032 -16.9418)
		(size 0.4572)
		(drill 0.2032)
		(layers "F.Cu" "B.Cu")
		(net "SG")
	)
	(via
		(at 66.930778 -19.3802)
		(size 0.4572)
		(drill 0.2032)
		(layers "F.Cu" "B.Cu")
		(net "SG")
	)
	(via
		(at 153.520902 -110.133892)
		(size 0.4572)
		(drill 0.2032)
		(layers "F.Cu" "B.Cu")
		(net "SG")
	)
	(via
		(at 101.2063 -29.489146)
		(size 0.4572)
		(drill 0.2032)
		(layers "F.Cu" "B.Cu")
		(net "SG")
	)
	(via
		(at 35.179 -19.05)
		(size 0.4572)
		(drill 0.2032)
		(layers "F.Cu" "B.Cu")
		(net "SG")
	)
	(via
		(at 113.132108 -13.766038)
		(size 0.4572)
		(drill 0.2032)
		(layers "F.Cu" "B.Cu")
		(net "SG")
	)
	(via
		(at 111.864902 -110.133892)
		(size 0.4572)
		(drill 0.2032)
		(layers "F.Cu" "B.Cu")
		(net "SG")
	)
	(via
		(at 52.936902 -110.133892)
		(size 0.4572)
		(drill 0.2032)
		(layers "F.Cu" "B.Cu")
		(net "SG")
	)
	(via
		(at 38.31844 -17.1196)
		(size 0.508)
		(drill 0.254)
		(layers "F.Cu" "B.Cu")
		(net "SG")
	)
	(via
		(at 78.157832 -7.3406)
		(size 0.4572)
		(drill 0.2032)
		(layers "F.Cu" "B.Cu")
		(net "SG")
	)
	(via
		(at 101.956108 -13.766038)
		(size 0.4572)
		(drill 0.2032)
		(layers "F.Cu" "B.Cu")
		(net "SG")
	)
	(via
		(at 116.346986 -42.323258)
		(size 0.4572)
		(drill 0.2032)
		(layers "F.Cu" "B.Cu")
		(net "SG")
	)
	(via
		(at 130.0988 -65.7098)
		(size 0.508)
		(drill 0.254)
		(layers "F.Cu" "B.Cu")
		(net "SG")
	)
	(via
		(at 81.636108 -13.766038)
		(size 0.4572)
		(drill 0.2032)
		(layers "F.Cu" "B.Cu")
		(net "SG")
	)
	(via
		(at 48.80864 -19.77136)
		(size 0.508)
		(drill 0.254)
		(layers "F.Cu" "B.Cu")
		(net "SG")
	)
	(via
		(at 13.98397 -10.432542)
		(size 0.4572)
		(drill 0.2032)
		(layers "F.Cu" "B.Cu")
		(net "SG")
	)
	(via
		(at 99.34702 -52.322984)
		(size 0.4572)
		(drill 0.2032)
		(layers "F.Cu" "B.Cu")
		(net "SG")
	)
	(via
		(at 150.368 -34.544)
		(size 0.508)
		(drill 0.254)
		(layers "F.Cu" "B.Cu")
		(net "SG")
	)
	(via
		(at 111.346996 -40.323262)
		(size 0.4572)
		(drill 0.2032)
		(layers "F.Cu" "B.Cu")
		(net "SG")
	)
	(via
		(at 115.346988 -36.32327)
		(size 0.4572)
		(drill 0.2032)
		(layers "F.Cu" "B.Cu")
		(net "SG")
	)
	(via
		(at 158.852108 -13.766038)
		(size 0.4572)
		(drill 0.2032)
		(layers "F.Cu" "B.Cu")
		(net "SG")
	)
	(via
		(at 79.1464 -64.1096)
		(size 0.508)
		(drill 0.254)
		(layers "F.Cu" "B.Cu")
		(net "SG")
	)
	(via
		(at 10.264902 -110.133892)
		(size 0.4572)
		(drill 0.2032)
		(layers "F.Cu" "B.Cu")
		(net "SG")
	)
	(via
		(at 90.16365 -62.9666)
		(size 0.508)
		(drill 0.254)
		(layers "F.Cu" "B.Cu")
		(net "SG")
	)
	(via
		(at 1.016 -93.883226)
		(size 0.4572)
		(drill 0.2032)
		(layers "F.Cu" "B.Cu")
		(net "SG")
	)
	(via
		(at 79.248 -75.057)
		(size 0.508)
		(drill 0.254)
		(layers "F.Cu" "B.Cu")
		(net "SG")
	)
	(via
		(at 1.016 -11.587226)
		(size 0.4572)
		(drill 0.2032)
		(layers "F.Cu" "B.Cu")
		(net "SG")
	)
	(via
		(at 128.27 -96.393)
		(size 0.508)
		(drill 0.254)
		(layers "F.Cu" "B.Cu")
		(net "SG")
	)
	(via
		(at 166.633906 -104.624886)
		(size 0.4572)
		(drill 0.2032)
		(layers "F.Cu" "B.Cu")
		(net "SG")
	)
	(via
		(at 19.408902 -110.133892)
		(size 0.4572)
		(drill 0.2032)
		(layers "F.Cu" "B.Cu")
		(net "SG")
	)
	(via
		(at 93.3704 -43.0022)
		(size 0.508)
		(drill 0.254)
		(layers "F.Cu" "B.Cu")
		(net "SG")
	)
	(via
		(at 102.347268 -37.323268)
		(size 0.4572)
		(drill 0.2032)
		(layers "F.Cu" "B.Cu")
		(net "SG")
	)
	(via
		(at 138.165078 -15.377922)
		(size 0.508)
		(drill 0.254)
		(layers "F.Cu" "B.Cu")
		(net "SG")
	)
	(via
		(at 153.772108 -13.766038)
		(size 0.4572)
		(drill 0.2032)
		(layers "F.Cu" "B.Cu")
		(net "SG")
	)
	(via
		(at 79.248 -55.118)
		(size 0.508)
		(drill 0.254)
		(layers "F.Cu" "B.Cu")
		(net "SG")
	)
	(via
		(at 108.816902 -110.133892)
		(size 0.4572)
		(drill 0.2032)
		(layers "F.Cu" "B.Cu")
		(net "SG")
	)
	(via
		(at 94.592902 -110.133892)
		(size 0.4572)
		(drill 0.2032)
		(layers "F.Cu" "B.Cu")
		(net "SG")
	)
	(via
		(at 129.2733 -69.4055)
		(size 0.508)
		(drill 0.254)
		(layers "F.Cu" "B.Cu")
		(net "SG")
	)
	(via
		(at 56.261 -105.41)
		(size 0.508)
		(drill 0.254)
		(layers "F.Cu" "B.Cu")
		(net "SG")
	)
	(via
		(at 76.073 -75.057)
		(size 0.508)
		(drill 0.254)
		(layers "F.Cu" "B.Cu")
		(net "SG")
	)
	(via
		(at 145.5928 -51.8922)
		(size 0.508)
		(drill 0.254)
		(layers "F.Cu" "B.Cu")
		(net "SG")
	)
	(via
		(at 1.016 -102.011226)
		(size 0.4572)
		(drill 0.2032)
		(layers "F.Cu" "B.Cu")
		(net "SG")
	)
	(via
		(at 72.263 -48.4378)
		(size 0.4572)
		(drill 0.2032)
		(layers "F.Cu" "B.Cu")
		(net "SG")
	)
	(via
		(at 59.1058 -7.3914)
		(size 0.4572)
		(drill 0.2032)
		(layers "F.Cu" "B.Cu")
		(net "SG")
	)
	(via
		(at 40.33393 -6.519418)
		(size 0.4572)
		(drill 0.2032)
		(layers "F.Cu" "B.Cu")
		(net "SG")
	)
	(via
		(at 113.896902 -110.133892)
		(size 0.4572)
		(drill 0.2032)
		(layers "F.Cu" "B.Cu")
		(net "SG")
	)
	(via
		(at 67.142106 -8.1534)
		(size 0.4572)
		(drill 0.2032)
		(layers "F.Cu" "B.Cu")
		(net "SG")
	)
	(via
		(at 65.786 -56.642)
		(size 0.508)
		(drill 0.254)
		(layers "F.Cu" "B.Cu")
		(net "SG")
	)
	(via
		(at 68.834 -46.863)
		(size 0.508)
		(drill 0.254)
		(layers "F.Cu" "B.Cu")
		(net "SG")
	)
	(via
		(at 34.284158 -12.317984)
		(size 0.4572)
		(drill 0.2032)
		(layers "F.Cu" "B.Cu")
		(net "SG")
	)
	(via
		(at 75.288902 -110.133892)
		(size 0.4572)
		(drill 0.2032)
		(layers "F.Cu" "B.Cu")
		(net "SG")
	)
	(via
		(at 5.303012 -5.516118)
		(size 0.4572)
		(drill 0.2032)
		(layers "F.Cu" "B.Cu")
		(net "SG")
	)
	(via
		(at 164.696902 -110.133892)
		(size 0.4572)
		(drill 0.2032)
		(layers "F.Cu" "B.Cu")
		(net "SG")
	)
	(via
		(at 97.6122 -93.6498)
		(size 0.508)
		(drill 0.254)
		(layers "F.Cu" "B.Cu")
		(net "SG")
	)
	(via
		(at 115.164108 -13.766038)
		(size 0.4572)
		(drill 0.2032)
		(layers "F.Cu" "B.Cu")
		(net "SG")
	)
	(via
		(at 20.357592 -64.426592)
		(size 0.508)
		(drill 0.254)
		(layers "F.Cu" "B.Cu")
		(net "SG")
	)
	(via
		(at 125.2982 -30.861)
		(size 0.508)
		(drill 0.254)
		(layers "F.Cu" "B.Cu")
		(net "SG")
	)
	(via
		(at 147.6756 -74.2315)
		(size 0.508)
		(drill 0.254)
		(layers "F.Cu" "B.Cu")
		(net "SG")
	)
	(via
		(at 31.86684 -13.766038)
		(size 0.4572)
		(drill 0.2032)
		(layers "F.Cu" "B.Cu")
		(net "SG")
	)
	(via
		(at 130.2131 -68.1101)
		(size 0.508)
		(drill 0.254)
		(layers "F.Cu" "B.Cu")
		(net "SG")
	)
	(via
		(at 32.616902 -110.133892)
		(size 0.4572)
		(drill 0.2032)
		(layers "F.Cu" "B.Cu")
		(net "SG")
	)
	(via
		(at 16.360902 -110.133892)
		(size 0.4572)
		(drill 0.2032)
		(layers "F.Cu" "B.Cu")
		(net "SG")
	)
	(via
		(at 61.089032 -19.3802)
		(size 0.4572)
		(drill 0.2032)
		(layers "F.Cu" "B.Cu")
		(net "SG")
	)
	(via
		(at 35.093402 -5.516118)
		(size 0.4572)
		(drill 0.2032)
		(layers "F.Cu" "B.Cu")
		(net "SG")
	)
	(via
		(at 83.416902 -110.133892)
		(size 0.4572)
		(drill 0.2032)
		(layers "F.Cu" "B.Cu")
		(net "SG")
	)
	(via
		(at 25.504902 -110.133892)
		(size 0.4572)
		(drill 0.2032)
		(layers "F.Cu" "B.Cu")
		(net "SG")
	)
	(via
		(at 114.34699 -41.32326)
		(size 0.4572)
		(drill 0.2032)
		(layers "F.Cu" "B.Cu")
		(net "SG")
	)
	(via
		(at 82.652108 -13.766038)
		(size 0.4572)
		(drill 0.2032)
		(layers "F.Cu" "B.Cu")
		(net "SG")
	)
	(via
		(at 101.34727 -35.323018)
		(size 0.4572)
		(drill 0.2032)
		(layers "F.Cu" "B.Cu")
		(net "SG")
	)
	(via
		(at 1.016 -92.867226)
		(size 0.4572)
		(drill 0.2032)
		(layers "F.Cu" "B.Cu")
		(net "SG")
	)
	(via
		(at 116.346986 -54.32298)
		(size 0.4572)
		(drill 0.2032)
		(layers "F.Cu" "B.Cu")
		(net "SG")
	)
	(via
		(at 73.256902 -110.133892)
		(size 0.4572)
		(drill 0.2032)
		(layers "F.Cu" "B.Cu")
		(net "SG")
	)
	(via
		(at 125.984 -45.531532)
		(size 0.508)
		(drill 0.254)
		(layers "F.Cu" "B.Cu")
		(net "SG")
	)
	(via
		(at 146.660108 -13.766038)
		(size 0.4572)
		(drill 0.2032)
		(layers "F.Cu" "B.Cu")
		(net "SG")
	)
	(via
		(at 95.0722 -33.528)
		(size 0.508)
		(drill 0.254)
		(layers "F.Cu" "B.Cu")
		(net "SG")
	)
	(via
		(at 77.320902 -110.133892)
		(size 0.4572)
		(drill 0.2032)
		(layers "F.Cu" "B.Cu")
		(net "SG")
	)
	(via
		(at 164.948108 -13.766038)
		(size 0.4572)
		(drill 0.2032)
		(layers "F.Cu" "B.Cu")
		(net "SG")
	)
	(via
		(at 135.509 -31.623)
		(size 0.508)
		(drill 0.254)
		(layers "F.Cu" "B.Cu")
		(net "SG")
	)
	(via
		(at 40.414448 -11.596116)
		(size 0.4572)
		(drill 0.2032)
		(layers "F.Cu" "B.Cu")
		(net "SG")
	)
	(via
		(at 125.072902 -110.133892)
		(size 0.4572)
		(drill 0.2032)
		(layers "F.Cu" "B.Cu")
		(net "SG")
	)
	(via
		(at 38.141402 -5.516118)
		(size 0.4572)
		(drill 0.2032)
		(layers "F.Cu" "B.Cu")
		(net "SG")
	)
	(via
		(at 85.700108 -13.766038)
		(size 0.4572)
		(drill 0.2032)
		(layers "F.Cu" "B.Cu")
		(net "SG")
	)
	(via
		(at 12.0904 -17.5006)
		(size 0.508)
		(drill 0.254)
		(layers "F.Cu" "B.Cu")
		(net "SG")
	)
	(via
		(at 78.800198 -22.799802)
		(size 0.4572)
		(drill 0.2032)
		(layers "F.Cu" "B.Cu")
		(net "SG")
	)
	(via
		(at 55.1942 -73.533)
		(size 0.4572)
		(drill 0.2032)
		(layers "F.Cu" "B.Cu")
		(net "SG")
	)
	(via
		(at 114.34699 -43.323256)
		(size 0.4572)
		(drill 0.2032)
		(layers "F.Cu" "B.Cu")
		(net "SG")
	)
	(via
		(at 34.417 -97.282)
		(size 0.508)
		(drill 0.254)
		(layers "F.Cu" "B.Cu")
		(net "SG")
	)
	(via
		(at 55.984902 -110.133892)
		(size 0.4572)
		(drill 0.2032)
		(layers "F.Cu" "B.Cu")
		(net "SG")
	)
	(via
		(at 113.346992 -53.322982)
		(size 0.4572)
		(drill 0.2032)
		(layers "F.Cu" "B.Cu")
		(net "SG")
	)
	(via
		(at 88.748108 -13.766038)
		(size 0.4572)
		(drill 0.2032)
		(layers "F.Cu" "B.Cu")
		(net "SG")
	)
	(via
		(at 1.016 -95.915226)
		(size 0.4572)
		(drill 0.2032)
		(layers "F.Cu" "B.Cu")
		(net "SG")
	)
	(via
		(at 26.3652 -19.36496)
		(size 0.508)
		(drill 0.254)
		(layers "F.Cu" "B.Cu")
		(net "SG")
	)
	(via
		(at 1.016 -88.803226)
		(size 0.4572)
		(drill 0.2032)
		(layers "F.Cu" "B.Cu")
		(net "SG")
	)
	(via
		(at 19.67484 -13.766038)
		(size 0.4572)
		(drill 0.2032)
		(layers "F.Cu" "B.Cu")
		(net "SG")
	)
	(via
		(at 103.505 -77.47)
		(size 0.508)
		(drill 0.254)
		(layers "F.Cu" "B.Cu")
		(net "SG")
	)
	(via
		(at 108.052108 -13.766038)
		(size 0.4572)
		(drill 0.2032)
		(layers "F.Cu" "B.Cu")
		(net "SG")
	)
	(via
		(at 118.346982 -48.322992)
		(size 0.4572)
		(drill 0.2032)
		(layers "F.Cu" "B.Cu")
		(net "SG")
	)
	(via
		(at 82.4992 -104.3178)
		(size 0.508)
		(drill 0.254)
		(layers "F.Cu" "B.Cu")
		(net "SG")
	)
	(via
		(at 68.326 -54.61)
		(size 0.508)
		(drill 0.254)
		(layers "F.Cu" "B.Cu")
		(net "SG")
	)
	(via
		(at 110.848902 -110.133892)
		(size 0.4572)
		(drill 0.2032)
		(layers "F.Cu" "B.Cu")
		(net "SG")
	)
	(via
		(at 147.447 -49.403)
		(size 0.508)
		(drill 0.254)
		(layers "F.Cu" "B.Cu")
		(net "SG")
	)
	(via
		(at 82.6262 -99.4918)
		(size 0.508)
		(drill 0.254)
		(layers "F.Cu" "B.Cu")
		(net "SG")
	)
	(via
		(at 110.3503 -29.616146)
		(size 0.4572)
		(drill 0.2032)
		(layers "F.Cu" "B.Cu")
		(net "SG")
	)
	(via
		(at 93.7006 -23.368)
		(size 0.4572)
		(drill 0.2032)
		(layers "F.Cu" "B.Cu")
		(net "SG")
	)
	(via
		(at 21.082 -105.918)
		(size 0.508)
		(drill 0.254)
		(layers "F.Cu" "B.Cu")
		(net "SG")
	)
	(via
		(at 26.543 -77.597)
		(size 0.508)
		(drill 0.254)
		(layers "F.Cu" "B.Cu")
		(net "SG")
	)
	(via
		(at 35.5854 -100.4824)
		(size 0.508)
		(drill 0.254)
		(layers "F.Cu" "B.Cu")
		(net "SG")
	)
	(via
		(at 37.125402 -5.516118)
		(size 0.4572)
		(drill 0.2032)
		(layers "F.Cu" "B.Cu")
		(net "SG")
	)
	(via
		(at 89.789 -33.147)
		(size 0.508)
		(drill 0.254)
		(layers "F.Cu" "B.Cu")
		(net "SG")
	)
	(via
		(at 71.247 -56.9722)
		(size 0.508)
		(drill 0.254)
		(layers "F.Cu" "B.Cu")
		(net "SG")
	)
	(via
		(at 101.34727 -36.32327)
		(size 0.4572)
		(drill 0.2032)
		(layers "F.Cu" "B.Cu")
		(net "SG")
	)
	(via
		(at 130.0734 -61.1378)
		(size 0.508)
		(drill 0.254)
		(layers "F.Cu" "B.Cu")
		(net "SG")
	)
	(via
		(at 137.264902 -110.133892)
		(size 0.4572)
		(drill 0.2032)
		(layers "F.Cu" "B.Cu")
		(net "SG")
	)
	(via
		(at 130.404108 -13.766038)
		(size 0.4572)
		(drill 0.2032)
		(layers "F.Cu" "B.Cu")
		(net "SG")
	)
	(via
		(at 120.244108 -13.766038)
		(size 0.4572)
		(drill 0.2032)
		(layers "F.Cu" "B.Cu")
		(net "SG")
	)
	(via
		(at 73.279 -80.518)
		(size 0.508)
		(drill 0.254)
		(layers "F.Cu" "B.Cu")
		(net "SG")
	)
	(via
		(at 136.6774 -87.7824)
		(size 0.508)
		(drill 0.254)
		(layers "F.Cu" "B.Cu")
		(net "SG")
	)
	(via
		(at 105.347262 -39.323264)
		(size 0.4572)
		(drill 0.2032)
		(layers "F.Cu" "B.Cu")
		(net "SG")
	)
	(via
		(at 73.166478 -7.3406)
		(size 0.4572)
		(drill 0.2032)
		(layers "F.Cu" "B.Cu")
		(net "SG")
	)
	(via
		(at 148.440902 -110.133892)
		(size 0.4572)
		(drill 0.2032)
		(layers "F.Cu" "B.Cu")
		(net "SG")
	)
	(via
		(at 150.724108 -13.766038)
		(size 0.4572)
		(drill 0.2032)
		(layers "F.Cu" "B.Cu")
		(net "SG")
	)
	(via
		(at 128.8034 -61.1378)
		(size 0.508)
		(drill 0.254)
		(layers "F.Cu" "B.Cu")
		(net "SG")
	)
	(via
		(at 117.960902 -110.133892)
		(size 0.4572)
		(drill 0.2032)
		(layers "F.Cu" "B.Cu")
		(net "SG")
	)
	(via
		(at 166.633906 -81.256886)
		(size 0.4572)
		(drill 0.2032)
		(layers "F.Cu" "B.Cu")
		(net "SG")
	)
	(via
		(at 113.346992 -42.323258)
		(size 0.4572)
		(drill 0.2032)
		(layers "F.Cu" "B.Cu")
		(net "SG")
	)
	(via
		(at 75.876404 -11.056366)
		(size 0.4572)
		(drill 0.2032)
		(layers "F.Cu" "B.Cu")
		(net "SG")
	)
	(via
		(at 40.33393 -10.583418)
		(size 0.4572)
		(drill 0.2032)
		(layers "F.Cu" "B.Cu")
		(net "SG")
	)
	(via
		(at 57.000902 -110.133892)
		(size 0.4572)
		(drill 0.2032)
		(layers "F.Cu" "B.Cu")
		(net "SG")
	)
	(via
		(at 45.261784 -12.852654)
		(size 0.4572)
		(drill 0.2032)
		(layers "F.Cu" "B.Cu")
		(net "SG")
	)
	(via
		(at 47.856902 -110.133892)
		(size 0.4572)
		(drill 0.2032)
		(layers "F.Cu" "B.Cu")
		(net "SG")
	)
	(via
		(at 166.633906 -91.416886)
		(size 0.4572)
		(drill 0.2032)
		(layers "F.Cu" "B.Cu")
		(net "SG")
	)
	(via
		(at 166.633906 -100.560886)
		(size 0.4572)
		(drill 0.2032)
		(layers "F.Cu" "B.Cu")
		(net "SG")
	)
	(via
		(at 152.504902 -110.133892)
		(size 0.4572)
		(drill 0.2032)
		(layers "F.Cu" "B.Cu")
		(net "SG")
	)
	(via
		(at 23.876 -106.68)
		(size 0.508)
		(drill 0.254)
		(layers "F.Cu" "B.Cu")
		(net "SG")
	)
	(via
		(at 102.347268 -36.32327)
		(size 0.4572)
		(drill 0.2032)
		(layers "F.Cu" "B.Cu")
		(net "SG")
	)
	(via
		(at 115.316 -100.838)
		(size 0.508)
		(drill 0.254)
		(layers "F.Cu" "B.Cu")
		(net "SG")
	)
	(via
		(at 122.024902 -110.133892)
		(size 0.4572)
		(drill 0.2032)
		(layers "F.Cu" "B.Cu")
		(net "SG")
	)
	(via
		(at 39.157402 -5.516118)
		(size 0.4572)
		(drill 0.2032)
		(layers "F.Cu" "B.Cu")
		(net "SG")
	)
	(via
		(at 123.292108 -13.766038)
		(size 0.4572)
		(drill 0.2032)
		(layers "F.Cu" "B.Cu")
		(net "SG")
	)
	(via
		(at 155.552902 -110.133892)
		(size 0.4572)
		(drill 0.2032)
		(layers "F.Cu" "B.Cu")
		(net "SG")
	)
	(via
		(at 94.4372 -33.528)
		(size 0.508)
		(drill 0.254)
		(layers "F.Cu" "B.Cu")
		(net "SG")
	)
	(via
		(at 6.319012 -5.516118)
		(size 0.4572)
		(drill 0.2032)
		(layers "F.Cu" "B.Cu")
		(net "SG")
	)
	(via
		(at 148.8186 -20.2184)
		(size 0.508)
		(drill 0.254)
		(layers "F.Cu" "B.Cu")
		(net "SG")
	)
	(via
		(at 100.347018 -45.322998)
		(size 0.4572)
		(drill 0.2032)
		(layers "F.Cu" "B.Cu")
		(net "SG")
	)
	(via
		(at 91.544902 -110.133892)
		(size 0.4572)
		(drill 0.2032)
		(layers "F.Cu" "B.Cu")
		(net "SG")
	)
	(via
		(at 112.1156 -19.8374)
		(size 0.508)
		(drill 0.254)
		(layers "F.Cu" "B.Cu")
		(net "SG")
	)
	(via
		(at 87.480902 -110.133892)
		(size 0.4572)
		(drill 0.2032)
		(layers "F.Cu" "B.Cu")
		(net "SG")
	)
	(via
		(at 159.255206 -60.449206)
		(size 0.508)
		(drill 0.254)
		(layers "F.Cu" "B.Cu")
		(net "SG")
	)
	(via
		(at 109.068108 -13.766038)
		(size 0.4572)
		(drill 0.2032)
		(layers "F.Cu" "B.Cu")
		(net "SG")
	)
	(via
		(at 166.633906 -108.688886)
		(size 0.4572)
		(drill 0.2032)
		(layers "F.Cu" "B.Cu")
		(net "SG")
	)
	(via
		(at 148.082 -48.768)
		(size 0.508)
		(drill 0.254)
		(layers "F.Cu" "B.Cu")
		(net "SG")
	)
	(via
		(at 70.77837 -19.3802)
		(size 0.4572)
		(drill 0.2032)
		(layers "F.Cu" "B.Cu")
		(net "SG")
	)
	(via
		(at 147.676108 -13.766038)
		(size 0.4572)
		(drill 0.2032)
		(layers "F.Cu" "B.Cu")
		(net "SG")
	)
	(via
		(at 110.346998 -39.323264)
		(size 0.4572)
		(drill 0.2032)
		(layers "F.Cu" "B.Cu")
		(net "SG")
	)
	(via
		(at 166.633906 -20.62607)
		(size 0.4572)
		(drill 0.2032)
		(layers "F.Cu" "B.Cu")
		(net "SG")
	)
	(via
		(at 84.684108 -13.766038)
		(size 0.4572)
		(drill 0.2032)
		(layers "F.Cu" "B.Cu")
		(net "SG")
	)
	(via
		(at 1.016 -96.931226)
		(size 0.4572)
		(drill 0.2032)
		(layers "F.Cu" "B.Cu")
		(net "SG")
	)
	(via
		(at 166.633906 -99.544886)
		(size 0.4572)
		(drill 0.2032)
		(layers "F.Cu" "B.Cu")
		(net "SG")
	)
	(via
		(at 166.633906 -33.83407)
		(size 0.4572)
		(drill 0.2032)
		(layers "F.Cu" "B.Cu")
		(net "SG")
	)
	(via
		(at 1.016 -104.043226)
		(size 0.4572)
		(drill 0.2032)
		(layers "F.Cu" "B.Cu")
		(net "SG")
	)
	(via
		(at 44.4754 -97.1804)
		(size 0.508)
		(drill 0.254)
		(layers "F.Cu" "B.Cu")
		(net "SG")
	)
	(via
		(at 18.161 -62.9412)
		(size 0.508)
		(drill 0.254)
		(layers "F.Cu" "B.Cu")
		(net "SG")
	)
	(via
		(at 105.347262 -43.323256)
		(size 0.4572)
		(drill 0.2032)
		(layers "F.Cu" "B.Cu")
		(net "SG")
	)
	(via
		(at 104.0511 -100.1903)
		(size 0.508)
		(drill 0.254)
		(layers "F.Cu" "B.Cu")
		(net "SG")
	)
	(via
		(at 34.365946 -10.289286)
		(size 0.4572)
		(drill 0.2032)
		(layers "F.Cu" "B.Cu")
		(net "SG")
	)
	(via
		(at 8.232902 -110.133892)
		(size 0.4572)
		(drill 0.2032)
		(layers "F.Cu" "B.Cu")
		(net "SG")
	)
	(via
		(at 166.633906 -17.57807)
		(size 0.4572)
		(drill 0.2032)
		(layers "F.Cu" "B.Cu")
		(net "SG")
	)
	(via
		(at 81.762346 -87.122)
		(size 0.508)
		(drill 0.254)
		(layers "F.Cu" "B.Cu")
		(net "SG")
	)
	(via
		(at 157.836108 -13.766038)
		(size 0.4572)
		(drill 0.2032)
		(layers "F.Cu" "B.Cu")
		(net "SG")
	)
	(via
		(at 32.766 -92.71)
		(size 0.508)
		(drill 0.254)
		(layers "F.Cu" "B.Cu")
		(net "SG")
	)
	(via
		(at 166.633906 -24.69007)
		(size 0.4572)
		(drill 0.2032)
		(layers "F.Cu" "B.Cu")
		(net "SG")
	)
	(via
		(at 86.602062 -60.198)
		(size 0.508)
		(drill 0.254)
		(layers "F.Cu" "B.Cu")
		(net "SG")
	)
	(via
		(at 34.648902 -110.133892)
		(size 0.4572)
		(drill 0.2032)
		(layers "F.Cu" "B.Cu")
		(net "SG")
	)
	(via
		(at 166.633906 -89.384886)
		(size 0.4572)
		(drill 0.2032)
		(layers "F.Cu" "B.Cu")
		(net "SG")
	)
	(via
		(at 130.152902 -110.133892)
		(size 0.4572)
		(drill 0.2032)
		(layers "F.Cu" "B.Cu")
		(net "SG")
	)
	(via
		(at 140.312902 -110.133892)
		(size 0.4572)
		(drill 0.2032)
		(layers "F.Cu" "B.Cu")
		(net "SG")
	)
	(via
		(at 1.016 -72.547226)
		(size 0.4572)
		(drill 0.2032)
		(layers "F.Cu" "B.Cu")
		(net "SG")
	)
	(via
		(at 134.0104 -81.0006)
		(size 0.508)
		(drill 0.254)
		(layers "F.Cu" "B.Cu")
		(net "SG")
	)
	(via
		(at 152.756108 -13.766038)
		(size 0.4572)
		(drill 0.2032)
		(layers "F.Cu" "B.Cu")
		(net "SG")
	)
	(via
		(at 112.346994 -43.323256)
		(size 0.4572)
		(drill 0.2032)
		(layers "F.Cu" "B.Cu")
		(net "SG")
	)
	(via
		(at 166.633906 -94.464886)
		(size 0.4572)
		(drill 0.2032)
		(layers "F.Cu" "B.Cu")
		(net "SG")
	)
	(via
		(at 155.804108 -13.766038)
		(size 0.4572)
		(drill 0.2032)
		(layers "F.Cu" "B.Cu")
		(net "SG")
	)
	(via
		(at 13.98397 -9.416542)
		(size 0.4572)
		(drill 0.2032)
		(layers "F.Cu" "B.Cu")
		(net "SG")
	)
	(via
		(at 92.2274 -106.2482)
		(size 0.508)
		(drill 0.254)
		(layers "F.Cu" "B.Cu")
		(net "SG")
	)
	(via
		(at 92.560902 -110.133892)
		(size 0.4572)
		(drill 0.2032)
		(layers "F.Cu" "B.Cu")
		(net "SG")
	)
	(via
		(at 30.584902 -110.133892)
		(size 0.4572)
		(drill 0.2032)
		(layers "F.Cu" "B.Cu")
		(net "SG")
	)
	(via
		(at 83.668108 -13.766038)
		(size 0.4572)
		(drill 0.2032)
		(layers "F.Cu" "B.Cu")
		(net "SG")
	)
	(via
		(at 135.763 -33.02)
		(size 0.508)
		(drill 0.254)
		(layers "F.Cu" "B.Cu")
		(net "SG")
	)
	(via
		(at 130.1242 -64.6176)
		(size 0.508)
		(drill 0.254)
		(layers "F.Cu" "B.Cu")
		(net "SG")
	)
	(via
		(at 101.704902 -110.133892)
		(size 0.4572)
		(drill 0.2032)
		(layers "F.Cu" "B.Cu")
		(net "SG")
	)
	(via
		(at 147.3962 -90.6018)
		(size 0.508)
		(drill 0.254)
		(layers "F.Cu" "B.Cu")
		(net "SG")
	)
	(via
		(at 75.14209 -8.1534)
		(size 0.4572)
		(drill 0.2032)
		(layers "F.Cu" "B.Cu")
		(net "SG")
	)
	(via
		(at 97.536 -26.15692)
		(size 0.508)
		(drill 0.254)
		(layers "F.Cu" "B.Cu")
		(net "SG")
	)
	(via
		(at 102.347268 -41.32326)
		(size 0.4572)
		(drill 0.2032)
		(layers "F.Cu" "B.Cu")
		(net "SG")
	)
	(via
		(at 143.360902 -110.133892)
		(size 0.4572)
		(drill 0.2032)
		(layers "F.Cu" "B.Cu")
		(net "SG")
	)
	(via
		(at 71.224902 -110.133892)
		(size 0.4572)
		(drill 0.2032)
		(layers "F.Cu" "B.Cu")
		(net "SG")
	)
	(via
		(at 10.668 -60.1472)
		(size 0.508)
		(drill 0.254)
		(layers "F.Cu" "B.Cu")
		(net "SG")
	)
	(via
		(at 90.1192 -73.6092)
		(size 0.4572)
		(drill 0.2032)
		(layers "F.Cu" "B.Cu")
		(net "SG")
	)
	(via
		(at 99.8982 -79.375)
		(size 0.508)
		(drill 0.254)
		(layers "F.Cu" "B.Cu")
		(net "SG")
	)
	(via
		(at 86.868 -95.504)
		(size 0.508)
		(drill 0.254)
		(layers "F.Cu" "B.Cu")
		(net "SG")
	)
	(via
		(at 1.016 -76.611226)
		(size 0.4572)
		(drill 0.2032)
		(layers "F.Cu" "B.Cu")
		(net "SG")
	)
	(via
		(at 89.764108 -13.766038)
		(size 0.4572)
		(drill 0.2032)
		(layers "F.Cu" "B.Cu")
		(net "SG")
	)
	(via
		(at 99.672902 -110.133892)
		(size 0.4572)
		(drill 0.2032)
		(layers "F.Cu" "B.Cu")
		(net "SG")
	)
	(via
		(at 79.248 -59.5376)
		(size 0.508)
		(drill 0.254)
		(layers "F.Cu" "B.Cu")
		(net "SG")
	)
	(via
		(at 15.618206 -84.411566)
		(size 0.508)
		(drill 0.254)
		(layers "F.Cu" "B.Cu")
		(net "SG")
	)
	(via
		(at 166.633906 -90.400886)
		(size 0.4572)
		(drill 0.2032)
		(layers "F.Cu" "B.Cu")
		(net "SG")
	)
	(via
		(at 166.633906 -82.272886)
		(size 0.4572)
		(drill 0.2032)
		(layers "F.Cu" "B.Cu")
		(net "SG")
	)
	(via
		(at 124.3076 -32.0802)
		(size 0.508)
		(drill 0.254)
		(layers "F.Cu" "B.Cu")
		(net "SG")
	)
	(via
		(at 129.388108 -13.766038)
		(size 0.4572)
		(drill 0.2032)
		(layers "F.Cu" "B.Cu")
		(net "SG")
	)
	(via
		(at 5.0546 -71.882)
		(size 0.508)
		(drill 0.254)
		(layers "F.Cu" "B.Cu")
		(net "SG")
	)
	(via
		(at 141.580108 -13.766038)
		(size 0.4572)
		(drill 0.2032)
		(layers "F.Cu" "B.Cu")
		(net "SG")
	)
	(via
		(at 149.708108 -13.766038)
		(size 0.4572)
		(drill 0.2032)
		(layers "F.Cu" "B.Cu")
		(net "SG")
	)
	(via
		(at 88.646 -76.962)
		(size 0.508)
		(drill 0.254)
		(layers "F.Cu" "B.Cu")
		(net "SG")
	)
	(via
		(at 74.272902 -110.133892)
		(size 0.4572)
		(drill 0.2032)
		(layers "F.Cu" "B.Cu")
		(net "SG")
	)
	(via
		(at 163.680902 -110.133892)
		(size 0.4572)
		(drill 0.2032)
		(layers "F.Cu" "B.Cu")
		(net "SG")
	)
	(via
		(at 13.98397 -8.400542)
		(size 0.4572)
		(drill 0.2032)
		(layers "F.Cu" "B.Cu")
		(net "SG")
	)
	(via
		(at 66.144902 -110.133892)
		(size 0.4572)
		(drill 0.2032)
		(layers "F.Cu" "B.Cu")
		(net "SG")
	)
	(via
		(at 80.52435 -21.07565)
		(size 0.4572)
		(drill 0.2032)
		(layers "F.Cu" "B.Cu")
		(net "SG")
	)
	(via
		(at 145.392902 -110.133892)
		(size 0.4572)
		(drill 0.2032)
		(layers "F.Cu" "B.Cu")
		(net "SG")
	)
	(via
		(at 40.33393 -7.535418)
		(size 0.4572)
		(drill 0.2032)
		(layers "F.Cu" "B.Cu")
		(net "SG")
	)
	(via
		(at 64.112902 -110.133892)
		(size 0.4572)
		(drill 0.2032)
		(layers "F.Cu" "B.Cu")
		(net "SG")
	)
	(via
		(at 112.7887 -29.616146)
		(size 0.4572)
		(drill 0.2032)
		(layers "F.Cu" "B.Cu")
		(net "SG")
	)
	(via
		(at 72.682354 -83.693)
		(size 0.4572)
		(drill 0.2032)
		(layers "F.Cu" "B.Cu")
		(net "SG")
	)
	(via
		(at 116.944902 -110.133892)
		(size 0.4572)
		(drill 0.2032)
		(layers "F.Cu" "B.Cu")
		(net "SG")
	)
	(via
		(at 112.346994 -35.323018)
		(size 0.4572)
		(drill 0.2032)
		(layers "F.Cu" "B.Cu")
		(net "SG")
	)
	(via
		(at 107.347258 -39.323264)
		(size 0.4572)
		(drill 0.2032)
		(layers "F.Cu" "B.Cu")
		(net "SG")
	)
	(via
		(at 71.133208 -7.3406)
		(size 0.4572)
		(drill 0.2032)
		(layers "F.Cu" "B.Cu")
		(net "SG")
	)
	(via
		(at 38.712902 -110.133892)
		(size 0.4572)
		(drill 0.2032)
		(layers "F.Cu" "B.Cu")
		(net "SG")
	)
	(via
		(at 86.464902 -110.133892)
		(size 0.4572)
		(drill 0.2032)
		(layers "F.Cu" "B.Cu")
		(net "SG")
	)
	(via
		(at 68.176902 -110.133892)
		(size 0.4572)
		(drill 0.2032)
		(layers "F.Cu" "B.Cu")
		(net "SG")
	)
	(via
		(at 26.4414 -97.155)
		(size 0.4572)
		(drill 0.2032)
		(layers "F.Cu" "B.Cu")
		(net "SG")
	)
	(via
		(at 92.583 -54.102)
		(size 0.508)
		(drill 0.254)
		(layers "F.Cu" "B.Cu")
		(net "SG")
	)
	(via
		(at 116.97462 -31.030418)
		(size 0.4572)
		(drill 0.2032)
		(layers "F.Cu" "B.Cu")
		(net "SG")
	)
	(via
		(at 3.152902 -110.133892)
		(size 0.4572)
		(drill 0.2032)
		(layers "F.Cu" "B.Cu")
		(net "SG")
	)
	(via
		(at 25.0698 -68.1482)
		(size 0.508)
		(drill 0.254)
		(layers "F.Cu" "B.Cu")
		(net "SG")
	)
	(via
		(at 105.029 -22.479)
		(size 0.508)
		(drill 0.254)
		(layers "F.Cu" "B.Cu")
		(net "SG")
	)
	(via
		(at 1.016 -10.571226)
		(size 0.4572)
		(drill 0.2032)
		(layers "F.Cu" "B.Cu")
		(net "SG")
	)
	(via
		(at 86.716108 -13.766038)
		(size 0.4572)
		(drill 0.2032)
		(layers "F.Cu" "B.Cu")
		(net "SG")
	)
	(via
		(at 100.347018 -42.323258)
		(size 0.4572)
		(drill 0.2032)
		(layers "F.Cu" "B.Cu")
		(net "SG")
	)
	(via
		(at 42.4434 -103.0224)
		(size 0.4572)
		(drill 0.2032)
		(layers "F.Cu" "B.Cu")
		(net "SG")
	)
	(via
		(at 105.7783 -100.8761)
		(size 0.508)
		(drill 0.254)
		(layers "F.Cu" "B.Cu")
		(net "SG")
	)
	(via
		(at 147.424902 -110.133892)
		(size 0.4572)
		(drill 0.2032)
		(layers "F.Cu" "B.Cu")
		(net "SG")
	)
	(via
		(at 130.0734 -62.1538)
		(size 0.508)
		(drill 0.254)
		(layers "F.Cu" "B.Cu")
		(net "SG")
	)
	(via
		(at 94.844108 -13.766038)
		(size 0.4572)
		(drill 0.2032)
		(layers "F.Cu" "B.Cu")
		(net "SG")
	)
	(via
		(at 149.456902 -110.133892)
		(size 0.4572)
		(drill 0.2032)
		(layers "F.Cu" "B.Cu")
		(net "SG")
	)
	(via
		(at 42.3418 -86.0552)
		(size 0.508)
		(drill 0.254)
		(layers "F.Cu" "B.Cu")
		(net "SG")
	)
	(via
		(at 142.225014 -15.77848)
		(size 0.508)
		(drill 0.254)
		(layers "F.Cu" "B.Cu")
		(net "SG")
	)
	(via
		(at 118.212108 -13.766038)
		(size 0.4572)
		(drill 0.2032)
		(layers "F.Cu" "B.Cu")
		(net "SG")
	)
	(via
		(at 106.4641 -100.1903)
		(size 0.508)
		(drill 0.254)
		(layers "F.Cu" "B.Cu")
		(net "SG")
	)
	(via
		(at 21.7932 -73.012808)
		(size 0.4572)
		(drill 0.2032)
		(layers "F.Cu" "B.Cu")
		(net "SG")
	)
	(via
		(at 126.088902 -110.133892)
		(size 0.4572)
		(drill 0.2032)
		(layers "F.Cu" "B.Cu")
		(net "SG")
	)
	(via
		(at 81.6102 -105.8418)
		(size 0.508)
		(drill 0.254)
		(layers "F.Cu" "B.Cu")
		(net "SG")
	)
	(via
		(at 75.1332 -7.3406)
		(size 0.4572)
		(drill 0.2032)
		(layers "F.Cu" "B.Cu")
		(net "SG")
	)
	(via
		(at 122.174 -17.9578)
		(size 0.508)
		(drill 0.254)
		(layers "F.Cu" "B.Cu")
		(net "SG")
	)
	(via
		(at 16.62684 -13.766038)
		(size 0.4572)
		(drill 0.2032)
		(layers "F.Cu" "B.Cu")
		(net "SG")
	)
	(via
		(at 20.69084 -13.766038)
		(size 0.4572)
		(drill 0.2032)
		(layers "F.Cu" "B.Cu")
		(net "SG")
	)
	(via
		(at 140.6652 -61.0108)
		(size 0.508)
		(drill 0.254)
		(layers "F.Cu" "B.Cu")
		(net "SG")
	)
	(via
		(at 101.346 -57.15)
		(size 0.508)
		(drill 0.254)
		(layers "F.Cu" "B.Cu")
		(net "SG")
	)
	(via
		(at 140.1318 -65.1002)
		(size 0.508)
		(drill 0.254)
		(layers "F.Cu" "B.Cu")
		(net "SG")
	)
	(via
		(at 155.067 -57.658)
		(size 0.508)
		(drill 0.254)
		(layers "F.Cu" "B.Cu")
		(net "SG")
	)
	(via
		(at 35.7886 -90.2716)
		(size 0.508)
		(drill 0.254)
		(layers "F.Cu" "B.Cu")
		(net "SG")
	)
	(via
		(at 107.347258 -43.323256)
		(size 0.4572)
		(drill 0.2032)
		(layers "F.Cu" "B.Cu")
		(net "SG")
	)
	(via
		(at 166.633906 -92.432886)
		(size 0.4572)
		(drill 0.2032)
		(layers "F.Cu" "B.Cu")
		(net "SG")
	)
	(via
		(at 104.752902 -110.133892)
		(size 0.4572)
		(drill 0.2032)
		(layers "F.Cu" "B.Cu")
		(net "SG")
	)
	(via
		(at 1.016 -98.963226)
		(size 0.4572)
		(drill 0.2032)
		(layers "F.Cu" "B.Cu")
		(net "SG")
	)
	(via
		(at 146.068288 -42.037)
		(size 0.508)
		(drill 0.254)
		(layers "F.Cu" "B.Cu")
		(net "SG")
	)
	(via
		(at 151.4983 -53.4289)
		(size 0.508)
		(drill 0.254)
		(layers "F.Cu" "B.Cu")
		(net "SG")
	)
	(via
		(at 98.7171 -74.3331)
		(size 0.508)
		(drill 0.254)
		(layers "F.Cu" "B.Cu")
		(net "SG")
	)
	(via
		(at 93.218 -54.102)
		(size 0.508)
		(drill 0.254)
		(layers "F.Cu" "B.Cu")
		(net "SG")
	)
	(via
		(at 113.5888 -88.265)
		(size 0.508)
		(drill 0.254)
		(layers "F.Cu" "B.Cu")
		(net "SG")
	)
	(via
		(at 141.328902 -110.133892)
		(size 0.4572)
		(drill 0.2032)
		(layers "F.Cu" "B.Cu")
		(net "SG")
	)
	(via
		(at 139.333478 -98.4758)
		(size 0.508)
		(drill 0.254)
		(layers "F.Cu" "B.Cu")
		(net "SG")
	)
	(via
		(at 21.440902 -110.133892)
		(size 0.4572)
		(drill 0.2032)
		(layers "F.Cu" "B.Cu")
		(net "SG")
	)
	(via
		(at 16.129 -91.3384)
		(size 0.508)
		(drill 0.254)
		(layers "F.Cu" "B.Cu")
		(net "SG")
	)
	(via
		(at 103.9622 -72.7202)
		(size 0.508)
		(drill 0.254)
		(layers "F.Cu" "B.Cu")
		(net "SG")
	)
	(via
		(at 13.150088 -33.147)
		(size 0.508)
		(drill 0.254)
		(layers "F.Cu" "B.Cu")
		(net "SG")
	)
	(via
		(at 81.15554 -48.335946)
		(size 0.4572)
		(drill 0.2032)
		(layers "F.Cu" "B.Cu")
		(net "SG")
	)
	(via
		(at 11.938 -25.4)
		(size 0.508)
		(drill 0.254)
		(layers "F.Cu" "B.Cu")
		(net "SG")
	)
	(via
		(at 30.776926 -100.810568)
		(size 0.508)
		(drill 0.254)
		(layers "F.Cu" "B.Cu")
		(net "SG")
	)
	(via
		(at 56.3372 -73.533)
		(size 0.4572)
		(drill 0.2032)
		(layers "F.Cu" "B.Cu")
		(net "SG")
	)
	(via
		(at 90.1954 -43.0276)
		(size 0.508)
		(drill 0.254)
		(layers "F.Cu" "B.Cu")
		(net "SG")
	)
	(via
		(at 1.016 -71.531226)
		(size 0.4572)
		(drill 0.2032)
		(layers "F.Cu" "B.Cu")
		(net "SG")
	)
	(via
		(at 113.411 -73.533)
		(size 0.4572)
		(drill 0.2032)
		(layers "F.Cu" "B.Cu")
		(net "SG")
	)
	(via
		(at 105.347262 -41.32326)
		(size 0.4572)
		(drill 0.2032)
		(layers "F.Cu" "B.Cu")
		(net "SG")
	)
	(via
		(at 41.760902 -110.133892)
		(size 0.4572)
		(drill 0.2032)
		(layers "F.Cu" "B.Cu")
		(net "SG")
	)
	(via
		(at 58.293 -105.41)
		(size 0.508)
		(drill 0.254)
		(layers "F.Cu" "B.Cu")
		(net "SG")
	)
	(via
		(at 29.337 -98.806)
		(size 0.508)
		(drill 0.254)
		(layers "F.Cu" "B.Cu")
		(net "SG")
	)
	(via
		(at 107.800902 -110.133892)
		(size 0.4572)
		(drill 0.2032)
		(layers "F.Cu" "B.Cu")
		(net "SG")
	)
	(via
		(at 131.420108 -13.766038)
		(size 0.4572)
		(drill 0.2032)
		(layers "F.Cu" "B.Cu")
		(net "SG")
	)
	(via
		(at 150.472902 -110.133892)
		(size 0.4572)
		(drill 0.2032)
		(layers "F.Cu" "B.Cu")
		(net "SG")
	)
	(via
		(at 13.98397 -11.448542)
		(size 0.4572)
		(drill 0.2032)
		(layers "F.Cu" "B.Cu")
		(net "SG")
	)
	(via
		(at 35.664902 -110.133892)
		(size 0.4572)
		(drill 0.2032)
		(layers "F.Cu" "B.Cu")
		(net "SG")
	)
	(via
		(at 160.909 -76.581)
		(size 0.508)
		(drill 0.254)
		(layers "F.Cu" "B.Cu")
		(net "SG")
	)
	(via
		(at 95.860108 -13.766038)
		(size 0.4572)
		(drill 0.2032)
		(layers "F.Cu" "B.Cu")
		(net "SG")
	)
	(via
		(at 15.3924 -40.9448)
		(size 0.508)
		(drill 0.254)
		(layers "F.Cu" "B.Cu")
		(net "SG")
	)
	(via
		(at 21.7805 -51.4985)
		(size 0.508)
		(drill 0.254)
		(layers "F.Cu" "B.Cu")
		(net "SG")
	)
	(via
		(at 105.347262 -33.323022)
		(size 0.4572)
		(drill 0.2032)
		(layers "F.Cu" "B.Cu")
		(net "SG")
	)
	(via
		(at 103.9114 -71.4502)
		(size 0.508)
		(drill 0.254)
		(layers "F.Cu" "B.Cu")
		(net "SG")
	)
	(via
		(at 94.869 -19.812)
		(size 0.4572)
		(drill 0.2032)
		(layers "F.Cu" "B.Cu")
		(net "SG")
	)
	(via
		(at 86.741 -59.309)
		(size 0.508)
		(drill 0.254)
		(layers "F.Cu" "B.Cu")
		(net "SG")
	)
	(via
		(at 96.52 -51.943)
		(size 0.508)
		(drill 0.254)
		(layers "F.Cu" "B.Cu")
		(net "SG")
	)
	(via
		(at 95.1992 -73.9394)
		(size 0.508)
		(drill 0.254)
		(layers "F.Cu" "B.Cu")
		(net "SG")
	)
	(via
		(at 85.725 -28.702)
		(size 0.4572)
		(drill 0.2032)
		(layers "F.Cu" "B.Cu")
		(net "SG")
	)
	(via
		(at 148.971 -58.42)
		(size 0.508)
		(drill 0.254)
		(layers "F.Cu" "B.Cu")
		(net "SG")
	)
	(via
		(at 73.21677 -19.3802)
		(size 0.4572)
		(drill 0.2032)
		(layers "F.Cu" "B.Cu")
		(net "SG")
	)
	(via
		(at 130.0734 -63.373)
		(size 0.508)
		(drill 0.254)
		(layers "F.Cu" "B.Cu")
		(net "SG")
	)
	(via
		(at 166.633906 -25.70607)
		(size 0.4572)
		(drill 0.2032)
		(layers "F.Cu" "B.Cu")
		(net "SG")
	)
	(via
		(at 111.346996 -49.32299)
		(size 0.4572)
		(drill 0.2032)
		(layers "F.Cu" "B.Cu")
		(net "SG")
	)
	(via
		(at 166.633906 -84.304886)
		(size 0.4572)
		(drill 0.2032)
		(layers "F.Cu" "B.Cu")
		(net "SG")
	)
	(via
		(at 130.0226 -70.1548)
		(size 0.508)
		(drill 0.254)
		(layers "F.Cu" "B.Cu")
		(net "SG")
	)
	(via
		(at 1.016 -90.835226)
		(size 0.4572)
		(drill 0.2032)
		(layers "F.Cu" "B.Cu")
		(net "SG")
	)
	(via
		(at 28.552902 -110.133892)
		(size 0.4572)
		(drill 0.2032)
		(layers "F.Cu" "B.Cu")
		(net "SG")
	)
	(via
		(at 20.424902 -110.133892)
		(size 0.4572)
		(drill 0.2032)
		(layers "F.Cu" "B.Cu")
		(net "SG")
	)
	(via
		(at 1.016 -91.851226)
		(size 0.4572)
		(drill 0.2032)
		(layers "F.Cu" "B.Cu")
		(net "SG")
	)
	(via
		(at 32.8803 -13.694918)
		(size 0.4572)
		(drill 0.2032)
		(layers "F.Cu" "B.Cu")
		(net "SG")
	)
	(via
		(at 98.347022 -55.322978)
		(size 0.4572)
		(drill 0.2032)
		(layers "F.Cu" "B.Cu")
		(net "SG")
	)
	(via
		(at 98.656902 -110.133892)
		(size 0.4572)
		(drill 0.2032)
		(layers "F.Cu" "B.Cu")
		(net "SG")
	)
	(via
		(at 160.632902 -110.133892)
		(size 0.4572)
		(drill 0.2032)
		(layers "F.Cu" "B.Cu")
		(net "SG")
	)
	(via
		(at 26.162 -92.456)
		(size 0.508)
		(drill 0.254)
		(layers "F.Cu" "B.Cu")
		(net "SG")
	)
	(via
		(at 107.347258 -37.323268)
		(size 0.4572)
		(drill 0.2032)
		(layers "F.Cu" "B.Cu")
		(net "SG")
	)
	(via
		(at 157.470094 -58.641996)
		(size 0.4572)
		(drill 0.2032)
		(layers "F.Cu" "B.Cu")
		(net "SG")
	)
	(via
		(at 151.816562 -47.498)
		(size 0.508)
		(drill 0.254)
		(layers "F.Cu" "B.Cu")
		(net "SG")
	)
	(via
		(at 48.64989 -7.3406)
		(size 0.4572)
		(drill 0.2032)
		(layers "F.Cu" "B.Cu")
		(net "SG")
	)
	(via
		(at 94.50324 -54.102)
		(size 0.508)
		(drill 0.254)
		(layers "F.Cu" "B.Cu")
		(net "SG")
	)
	(via
		(at 119.634 -88.138)
		(size 0.508)
		(drill 0.254)
		(layers "F.Cu" "B.Cu")
		(net "SG")
	)
	(via
		(at 14.696186 -13.287502)
		(size 0.4572)
		(drill 0.2032)
		(layers "F.Cu" "B.Cu")
		(net "SG")
	)
	(via
		(at 166.633906 -30.78607)
		(size 0.4572)
		(drill 0.2032)
		(layers "F.Cu" "B.Cu")
		(net "SG")
	)
	(via
		(at 126.111 -48.895)
		(size 0.508)
		(drill 0.254)
		(layers "F.Cu" "B.Cu")
		(net "SG")
	)
	(via
		(at 92.3544 -44.8564)
		(size 0.508)
		(drill 0.254)
		(layers "F.Cu" "B.Cu")
		(net "SG")
	)
	(via
		(at 121.412 -50.292)
		(size 0.508)
		(drill 0.254)
		(layers "F.Cu" "B.Cu")
		(net "SG")
	)
	(via
		(at 9.367012 -5.516118)
		(size 0.4572)
		(drill 0.2032)
		(layers "F.Cu" "B.Cu")
		(net "SG")
	)
	(via
		(at 144.628108 -13.766038)
		(size 0.4572)
		(drill 0.2032)
		(layers "F.Cu" "B.Cu")
		(net "SG")
	)
	(via
		(at 166.633906 -28.75407)
		(size 0.4572)
		(drill 0.2032)
		(layers "F.Cu" "B.Cu")
		(net "SG")
	)
	(via
		(at 82.400902 -110.133892)
		(size 0.4572)
		(drill 0.2032)
		(layers "F.Cu" "B.Cu")
		(net "SG")
	)
	(via
		(at 36.109402 -5.516118)
		(size 0.4572)
		(drill 0.2032)
		(layers "F.Cu" "B.Cu")
		(net "SG")
	)
	(via
		(at 104.14 -91.069922)
		(size 0.508)
		(drill 0.254)
		(layers "F.Cu" "B.Cu")
		(net "SG")
	)
	(via
		(at 128.0033 -36.322)
		(size 0.508)
		(drill 0.254)
		(layers "F.Cu" "B.Cu")
		(net "SG")
	)
	(via
		(at 13.312902 -110.133892)
		(size 0.4572)
		(drill 0.2032)
		(layers "F.Cu" "B.Cu")
		(net "SG")
	)
	(via
		(at 92.9132 -73.9394)
		(size 0.508)
		(drill 0.254)
		(layers "F.Cu" "B.Cu")
		(net "SG")
	)
	(via
		(at 24.75484 -13.766038)
		(size 0.4572)
		(drill 0.2032)
		(layers "F.Cu" "B.Cu")
		(net "SG")
	)
	(via
		(at 104.347264 -42.323258)
		(size 0.4572)
		(drill 0.2032)
		(layers "F.Cu" "B.Cu")
		(net "SG")
	)
	(via
		(at 109.832902 -110.133892)
		(size 0.4572)
		(drill 0.2032)
		(layers "F.Cu" "B.Cu")
		(net "SG")
	)
	(via
		(at 166.633906 -95.480886)
		(size 0.4572)
		(drill 0.2032)
		(layers "F.Cu" "B.Cu")
		(net "SG")
	)
	(via
		(at 23.630128 -62.605158)
		(size 0.508)
		(drill 0.254)
		(layers "F.Cu" "B.Cu")
		(net "SG")
	)
	(via
		(at 100.347018 -38.323266)
		(size 0.4572)
		(drill 0.2032)
		(layers "F.Cu" "B.Cu")
		(net "SG")
	)
	(via
		(at 141.986 -21.59)
		(size 0.508)
		(drill 0.254)
		(layers "F.Cu" "B.Cu")
		(net "SG")
	)
	(via
		(at 135.2296 -86.5124)
		(size 0.508)
		(drill 0.254)
		(layers "F.Cu" "B.Cu")
		(net "SG")
	)
	(via
		(at 95.716852 -25.45842)
		(size 0.508)
		(drill 0.254)
		(layers "F.Cu" "B.Cu")
		(net "SG")
	)
	(via
		(at 91.9734 -73.914)
		(size 0.508)
		(drill 0.254)
		(layers "F.Cu" "B.Cu")
		(net "SG")
	)
	(via
		(at 60.048902 -110.133892)
		(size 0.4572)
		(drill 0.2032)
		(layers "F.Cu" "B.Cu")
		(net "SG")
	)
	(via
		(at 106.784902 -110.133892)
		(size 0.4572)
		(drill 0.2032)
		(layers "F.Cu" "B.Cu")
		(net "SG")
	)
	(via
		(at 117.346984 -51.322986)
		(size 0.4572)
		(drill 0.2032)
		(layers "F.Cu" "B.Cu")
		(net "SG")
	)
	(via
		(at 135.1788 -95.9358)
		(size 0.508)
		(drill 0.254)
		(layers "F.Cu" "B.Cu")
		(net "SG")
	)
	(via
		(at 40.33393 -8.551418)
		(size 0.4572)
		(drill 0.2032)
		(layers "F.Cu" "B.Cu")
		(net "SG")
	)
	(via
		(at 106.4641 -102.6033)
		(size 0.508)
		(drill 0.254)
		(layers "F.Cu" "B.Cu")
		(net "SG")
	)
	(via
		(at 13.98397 -7.384542)
		(size 0.4572)
		(drill 0.2032)
		(layers "F.Cu" "B.Cu")
		(net "SG")
	)
	(via
		(at 78.8924 -83.947)
		(size 0.4572)
		(drill 0.2032)
		(layers "F.Cu" "B.Cu")
		(net "SG")
	)
	(via
		(at 121.260108 -13.766038)
		(size 0.4572)
		(drill 0.2032)
		(layers "F.Cu" "B.Cu")
		(net "SG")
	)
	(via
		(at 157.470094 -56.203596)
		(size 0.4572)
		(drill 0.2032)
		(layers "F.Cu" "B.Cu")
		(net "SG")
	)
	(via
		(at 91.567 -61.722)
		(size 0.508)
		(drill 0.254)
		(layers "F.Cu" "B.Cu")
		(net "SG")
	)
	(via
		(at 134.1628 -95.9358)
		(size 0.508)
		(drill 0.254)
		(layers "F.Cu" "B.Cu")
		(net "SG")
	)
	(via
		(at 92.735654 -49.468786)
		(size 0.4572)
		(drill 0.2032)
		(layers "F.Cu" "B.Cu")
		(net "SG")
	)
	(via
		(at 1.016 -100.995226)
		(size 0.4572)
		(drill 0.2032)
		(layers "F.Cu" "B.Cu")
		(net "SG")
	)
	(via
		(at 91.44 -102.2096)
		(size 0.508)
		(drill 0.254)
		(layers "F.Cu" "B.Cu")
		(net "SG")
	)
	(via
		(at 54.61 -17.526)
		(size 0.508)
		(drill 0.254)
		(layers "F.Cu" "B.Cu")
		(net "SG")
	)
	(via
		(at 115.347242 -43.323256)
		(size 0.4572)
		(drill 0.2032)
		(layers "F.Cu" "B.Cu")
		(net "SG")
	)
	(via
		(at 96.647 -19.6596)
		(size 0.4572)
		(drill 0.2032)
		(layers "F.Cu" "B.Cu")
		(net "SG")
	)
	(via
		(at 134.468108 -13.766038)
		(size 0.4572)
		(drill 0.2032)
		(layers "F.Cu" "B.Cu")
		(net "SG")
	)
	(via
		(at 137.501884 -77.090778)
		(size 0.508)
		(drill 0.254)
		(layers "F.Cu" "B.Cu")
		(net "SG")
	)
	(via
		(at 125.095 -69.1388)
		(size 0.508)
		(drill 0.254)
		(layers "F.Cu" "B.Cu")
		(net "SG")
	)
	(via
		(at 151.740108 -13.766038)
		(size 0.4572)
		(drill 0.2032)
		(layers "F.Cu" "B.Cu")
		(net "SG")
	)
	(via
		(at 166.633906 -96.496886)
		(size 0.4572)
		(drill 0.2032)
		(layers "F.Cu" "B.Cu")
		(net "SG")
	)
	(via
		(at 109.474 -105.664)
		(size 0.508)
		(drill 0.254)
		(layers "F.Cu" "B.Cu")
		(net "SG")
	)
	(via
		(at 1.016 -8.539226)
		(size 0.4572)
		(drill 0.2032)
		(layers "F.Cu" "B.Cu")
		(net "SG")
	)
	(via
		(at 13.150088 -47.748698)
		(size 0.508)
		(drill 0.254)
		(layers "F.Cu" "B.Cu")
		(net "SG")
	)
	(via
		(at 40.33393 -9.567418)
		(size 0.4572)
		(drill 0.2032)
		(layers "F.Cu" "B.Cu")
		(net "SG")
	)
	(via
		(at 166.633906 -36.88207)
		(size 0.4572)
		(drill 0.2032)
		(layers "F.Cu" "B.Cu")
		(net "SG")
	)
	(via
		(at 125.324108 -13.766038)
		(size 0.4572)
		(drill 0.2032)
		(layers "F.Cu" "B.Cu")
		(net "SG")
	)
	(via
		(at 92.0242 -72.6694)
		(size 0.508)
		(drill 0.254)
		(layers "F.Cu" "B.Cu")
		(net "SG")
	)
	(via
		(at 14.605 -55.499)
		(size 0.508)
		(drill 0.254)
		(layers "F.Cu" "B.Cu")
		(net "SG")
	)
	(via
		(at 63.096902 -110.133892)
		(size 0.4572)
		(drill 0.2032)
		(layers "F.Cu" "B.Cu")
		(net "SG")
	)
	(via
		(at 29.83484 -13.766038)
		(size 0.4572)
		(drill 0.2032)
		(layers "F.Cu" "B.Cu")
		(net "SG")
	)
	(via
		(at 130.0734 -66.675)
		(size 0.508)
		(drill 0.254)
		(layers "F.Cu" "B.Cu")
		(net "SG")
	)
	(via
		(at 13.6906 -39.878)
		(size 0.508)
		(drill 0.254)
		(layers "F.Cu" "B.Cu")
		(net "SG")
	)
	(via
		(at 143.4338 -51.9176)
		(size 0.508)
		(drill 0.254)
		(layers "F.Cu" "B.Cu")
		(net "SG")
	)
	(via
		(at 38.481 -93.98)
		(size 0.508)
		(drill 0.254)
		(layers "F.Cu" "B.Cu")
		(net "SG")
	)
	(segment
		(start 30.861 -91.7194)
		(end 30.861 -92.202)
		(width 0.381)
		(layer "B.Cu")
		(net "SG")
	)
	(segment
		(start 21.844 -21.1582)
		(end 21.844 -21.4376)
		(width 0.381)
		(layer "B.Cu")
		(net "SG")
	)
	(segment
		(start 108.585 -24.4094)
		(end 108.585 -25.4)
		(width 0.381)
		(layer "B.Cu")
		(net "SG")
	)
	(segment
		(start 119.84736 -52.82311)
		(end 119.84736 -52.822602)
		(width 0.381)
		(layer "B.Cu")
		(net "SG")
	)
	(segment
		(start 119.34698 -45.322998)
		(end 119.063516 -45.606716)
		(width 0.381)
		(layer "B.Cu")
		(net "SG")
	)
	(segment
		(start 112.776 -57.404)
		(end 113.202974 -56.977026)
		(width 0.381)
		(layer "B.Cu")
		(net "SG")
	)
	(segment
		(start 125.1204 -42.545)
		(end 125.984 -42.545)
		(width 0.381)
		(layer "B.Cu")
		(net "SG")
	)
	(segment
		(start 102.5398 -64.8208)
		(end 103.9622 -64.8208)
		(width 0.381)
		(layer "B.Cu")
		(net "SG")
	)
	(segment
		(start 88.2396 -45.4406)
		(end 89.027 -45.4406)
		(width 0.381)
		(layer "B.Cu")
		(net "SG")
	)
	(segment
		(start 110.847124 -37.823394)
		(end 111.346996 -38.323266)
		(width 0.381)
		(layer "B.Cu")
		(net "SG")
	)
	(segment
		(start 81.762346 -87.122)
		(end 82.7024 -87.122)
		(width 0.3048)
		(layer "B.Cu")
		(net "SG")
	)
	(segment
		(start 115.847114 -47.82312)
		(end 115.346988 -47.322994)
		(width 0.381)
		(layer "B.Cu")
		(net "SG")
	)
	(segment
		(start 107.347258 -48.322992)
		(end 106.84764 -47.823374)
		(width 0.381)
		(layer "B.Cu")
		(net "SG")
	)
	(segment
		(start 111.903256 -39.767256)
		(end 111.847376 -39.822882)
		(width 0.381)
		(layer "B.Cu")
		(net "SG")
	)
	(segment
		(start 115.9764 -73.533)
		(end 116.84 -73.533)
		(width 0.381)
		(layer "B.Cu")
		(net "SG")
	)
	(segment
		(start 114.847116 -35.82289)
		(end 114.847116 -35.823398)
		(width 0.381)
		(layer "B.Cu")
		(net "SG")
	)
	(segment
		(start 100.847144 -46.823122)
		(end 101.34727 -46.322996)
		(width 0.381)
		(layer "B.Cu")
		(net "SG")
	)
	(segment
		(start 83.947 -74.041)
		(end 83.947 -73.025)
		(width 0.381)
		(layer "B.Cu")
		(net "SG")
	)
	(segment
		(start 114.846608 -41.822878)
		(end 114.847116 -41.822878)
		(width 0.381)
		(layer "B.Cu")
		(net "SG")
	)
	(segment
		(start 101.34727 -40.323262)
		(end 101.846888 -40.82288)
		(width 0.381)
		(layer "B.Cu")
		(net "SG")
	)
	(segment
		(start 62.133226 -7.3406)
		(end 61.649864 -6.857238)
		(width 0.381)
		(layer "B.Cu")
		(net "SG")
	)
	(segment
		(start 111.847376 -39.822882)
		(end 111.847122 -39.822882)
		(width 0.381)
		(layer "B.Cu")
		(net "SG")
	)
	(segment
		(start 111.846868 -48.823118)
		(end 111.346996 -49.32299)
		(width 0.381)
		(layer "B.Cu")
		(net "SG")
	)
	(segment
		(start 97.3582 -27.813)
		(end 96.4692 -26.924)
		(width 0.381)
		(layer "B.Cu")
		(net "SG")
	)
	(segment
		(start 14.605 -73.406)
		(end 13.9827 -74.0283)
		(width 0.381)
		(layer "B.Cu")
		(net "SG")
	)
	(segment
		(start 118.8974 -44.577)
		(end 118.8974 -44.873418)
		(width 0.381)
		(layer "B.Cu")
		(net "SG")
	)
	(segment
		(start 118.847108 -45.823378)
		(end 118.847362 -45.823124)
		(width 0.254)
		(layer "B.Cu")
		(net "SG")
	)
	(segment
		(start 147.701 -67.818)
		(end 146.685 -67.818)
		(width 0.381)
		(layer "B.Cu")
		(net "SG")
	)
	(segment
		(start 120.880886 -50.823114)
		(end 121.412 -50.292)
		(width 0.381)
		(layer "B.Cu")
		(net "SG")
	)
	(segment
		(start 104.847136 -39.823136)
		(end 104.347264 -39.323264)
		(width 0.381)
		(layer "B.Cu")
		(net "SG")
	)
	(segment
		(start 134.7089 -65.42532)
		(end 134.7089 -65.39992)
		(width 0.381)
		(layer "B.Cu")
		(net "SG")
	)
	(segment
		(start 101.346 -56.237378)
		(end 102.185978 -56.237378)
		(width 0.381)
		(layer "B.Cu")
		(net "SG")
	)
	(segment
		(start 112.846866 -35.82289)
		(end 112.84712 -35.82289)
		(width 0.381)
		(layer "B.Cu")
		(net "SG")
	)
	(segment
		(start 113.846864 -49.823116)
		(end 113.847118 -49.823116)
		(width 0.381)
		(layer "B.Cu")
		(net "SG")
	)
	(segment
		(start 100.84689 -38.823138)
		(end 100.847144 -38.823138)
		(width 0.381)
		(layer "B.Cu")
		(net "SG")
	)
	(segment
		(start 98.347022 -37.323522)
		(end 98.84664 -37.82314)
		(width 0.381)
		(layer "B.Cu")
		(net "SG")
	)
	(segment
		(start 29.718 -92.964)
		(end 29.718 -91.7194)
		(width 0.381)
		(layer "B.Cu")
		(net "SG")
	)
	(segment
		(start 112.346994 -39.323264)
		(end 111.903256 -39.767256)
		(width 0.381)
		(layer "B.Cu")
		(net "SG")
	)
	(segment
		(start 104.84739 -40.823134)
		(end 104.347264 -41.32326)
		(width 0.381)
		(layer "B.Cu")
		(net "SG")
	)
	(segment
		(start 28.702 -91.5924)
		(end 28.702 -91.821)
		(width 0.381)
		(layer "B.Cu")
		(net "SG")
	)
	(segment
		(start 98.347022 -34.32302)
		(end 98.457766 -34.212276)
		(width 0.381)
		(layer "B.Cu")
		(net "SG")
	)
	(segment
		(start 47.879 -75.7174)
		(end 47.879 -76.2)
		(width 0.381)
		(layer "B.Cu")
		(net "SG")
	)
	(segment
		(start 102.347268 -36.32327)
		(end 101.84765 -36.822888)
		(width 0.381)
		(layer "B.Cu")
		(net "SG")
	)
	(segment
		(start 108.347256 -41.32326)
		(end 108.78566 -41.32326)
		(width 0.381)
		(layer "B.Cu")
		(net "SG")
	)
	(segment
		(start 146.3548 -99.2378)
		(end 146.3548 -97.9678)
		(width 0.381)
		(layer "B.Cu")
		(net "SG")
	)
	(segment
		(start 37.5666 -76.2)
		(end 37.5666 -76.0476)
		(width 0.381)
		(layer "B.Cu")
		(net "SG")
	)
	(segment
		(start 74.649838 -6.857238)
		(end 74.649838 -3.500374)
		(width 0.381)
		(layer "B.Cu")
		(net "SG")
	)
	(segment
		(start 101.847142 -39.82339)
		(end 101.34727 -40.323262)
		(width 0.381)
		(layer "B.Cu")
		(net "SG")
	)
	(segment
		(start 113.846864 -45.82287)
		(end 113.346992 -45.322998)
		(width 0.381)
		(layer "B.Cu")
		(net "SG")
	)
	(segment
		(start 104.347264 -39.323264)
		(end 104.846882 -38.823646)
		(width 0.381)
		(layer "B.Cu")
		(net "SG")
	)
	(segment
		(start 116.847112 -39.82339)
		(end 117.346984 -40.323262)
		(width 0.381)
		(layer "B.Cu")
		(net "SG")
	)
	(segment
		(start 117.348 -62.5094)
		(end 117.348 -63.5)
		(width 0.381)
		(layer "B.Cu")
		(net "SG")
	)
	(segment
		(start 58.64987 -3.500374)
		(end 58.64987 -6.93547)
		(width 0.381)
		(layer "B.Cu")
		(net "SG")
	)
	(segment
		(start 64.516 -55.2196)
		(end 64.516 -54.229)
		(width 0.381)
		(layer "B.Cu")
		(net "SG")
	)
	(segment
		(start 26.3652 -18.2372)
		(end 26.3652 -19.36496)
		(width 0.381)
		(layer "B.Cu")
		(net "SG")
	)
	(segment
		(start 99.34702 -45.322998)
		(end 99.846638 -44.82338)
		(width 0.381)
		(layer "B.Cu")
		(net "SG")
	)
	(segment
		(start 98.457766 -34.212276)
		(end 98.457766 -32.857694)
		(width 0.381)
		(layer "B.Cu")
		(net "SG")
	)
	(segment
		(start 125.2982 -30.861)
		(end 125.2982 -32.0802)
		(width 0.381)
		(layer "B.Cu")
		(net "SG")
	)
	(segment
		(start 28.702 -91.821)
		(end 28.067 -92.456)
		(width 0.381)
		(layer "B.Cu")
		(net "SG")
	)
	(segment
		(start 109.4486 -38.277546)
		(end 109.4486 -37.711126)
		(width 0.381)
		(layer "B.Cu")
		(net "SG")
	)
	(segment
		(start 145.7325 -74.2315)
		(end 147.6756 -74.2315)
		(width 0.381)
		(layer "B.Cu")
		(net "SG")
	)
	(segment
		(start 113.202974 -56.977026)
		(end 113.202974 -56.437784)
		(width 0.381)
		(layer "B.Cu")
		(net "SG")
	)
	(segment
		(start 134.0612 -66.07302)
		(end 134.7089 -65.42532)
		(width 0.381)
		(layer "B.Cu")
		(net "SG")
	)
	(segment
		(start 163.0934 -27.432)
		(end 163.0934 -27.5844)
		(width 0.381)
		(layer "B.Cu")
		(net "SG")
	)
	(segment
		(start 105.847388 -51.822858)
		(end 106.34726 -51.322986)
		(width 0.381)
		(layer "B.Cu")
		(net "SG")
	)
	(segment
		(start 106.34726 -51.322986)
		(end 105.847642 -50.823368)
		(width 0.381)
		(layer "B.Cu")
		(net "SG")
	)
	(segment
		(start 115.9764 -72.263)
		(end 116.84 -72.263)
		(width 0.381)
		(layer "B.Cu")
		(net "SG")
	)
	(segment
		(start 118.847108 -46.823122)
		(end 118.847108 -45.823378)
		(width 0.254)
		(layer "B.Cu")
		(net "SG")
	)
	(segment
		(start 100.84689 -37.823394)
		(end 100.347018 -38.323266)
		(width 0.381)
		(layer "B.Cu")
		(net "SG")
	)
	(segment
		(start 27.2415 -92.16644)
		(end 27.2415 -92.2655)
		(width 0.381)
		(layer "B.Cu")
		(net "SG")
	)
	(segment
		(start 104.347264 -37.323268)
		(end 104.846882 -37.822886)
		(width 0.381)
		(layer "B.Cu")
		(net "SG")
	)
	(segment
		(start 30.988 -91.5924)
		(end 30.861 -91.7194)
		(width 0.381)
		(layer "B.Cu")
		(net "SG")
	)
	(segment
		(start 146.1262 -51.3588)
		(end 145.5928 -51.8922)
		(width 0.381)
		(layer "B.Cu")
		(net "SG")
	)
	(segment
		(start 102.84714 -35.823144)
		(end 102.84714 -35.823398)
		(width 0.381)
		(layer "B.Cu")
		(net "SG")
	)
	(segment
		(start 102.185978 -56.237378)
		(end 102.2096 -56.261)
		(width 0.381)
		(layer "B.Cu")
		(net "SG")
	)
	(segment
		(start 122.25528 -46.232064)
		(end 122.23115 -46.256194)
		(width 0.381)
		(layer "B.Cu")
		(net "SG")
	)
	(segment
		(start 101.84765 -36.822888)
		(end 101.847142 -36.822888)
		(width 0.381)
		(layer "B.Cu")
		(net "SG")
	)
	(segment
		(start 26.289 -77.851)
		(end 26.543 -77.597)
		(width 0.381)
		(layer "B.Cu")
		(net "SG")
	)
	(segment
		(start 104.347264 -44.708064)
		(end 104.0892 -44.45)
		(width 0.381)
		(layer "B.Cu")
		(net "SG")
	)
	(segment
		(start 117.84711 -47.823374)
		(end 117.847364 -47.823374)
		(width 0.381)
		(layer "B.Cu")
		(net "SG")
	)
	(segment
		(start 66.649854 -6.857238)
		(end 66.649854 -3.500374)
		(width 0.381)
		(layer "B.Cu")
		(net "SG")
	)
	(segment
		(start 116.846858 -42.82313)
		(end 116.346986 -42.323258)
		(width 0.381)
		(layer "B.Cu")
		(net "SG")
	)
	(segment
		(start 110.346998 -39.175944)
		(end 109.4486 -38.277546)
		(width 0.381)
		(layer "B.Cu")
		(net "SG")
	)
	(segment
		(start 147.955 -20.2184)
		(end 148.8186 -20.2184)
		(width 0.381)
		(layer "B.Cu")
		(net "SG")
	)
	(segment
		(start 114.34699 -41.32326)
		(end 114.846608 -41.822878)
		(width 0.381)
		(layer "B.Cu")
		(net "SG")
	)
	(segment
		(start 77.9272 -83.947)
		(end 78.8924 -83.947)
		(width 0.381)
		(layer "B.Cu")
		(net "SG")
	)
	(segment
		(start 107.347258 -41.32326)
		(end 107.84713 -41.823132)
		(width 0.381)
		(layer "B.Cu")
		(net "SG")
	)
	(segment
		(start 138.4935 -68.0593)
		(end 139.3317 -68.0593)
		(width 0.381)
		(layer "B.Cu")
		(net "SG")
	)
	(segment
		(start 112.84712 -45.82287)
		(end 112.346994 -46.322996)
		(width 0.381)
		(layer "B.Cu")
		(net "SG")
	)
	(segment
		(start 73.64984 -6.857238)
		(end 73.64984 -3.500374)
		(width 0.381)
		(layer "B.Cu")
		(net "SG")
	)
	(segment
		(start 111.346996 -49.32299)
		(end 110.850426 -48.82642)
		(width 0.254)
		(layer "B.Cu")
		(net "SG")
	)
	(segment
		(start 111.847376 -45.823124)
		(end 111.847376 -45.823378)
		(width 0.381)
		(layer "B.Cu")
		(net "SG")
	)
	(segment
		(start 61.4426 -59.817)
		(end 61.4426 -60.6552)
		(width 0.381)
		(layer "B.Cu")
		(net "SG")
	)
	(segment
		(start 110.847124 -41.823132)
		(end 110.847124 -41.823386)
		(width 0.381)
		(layer "B.Cu")
		(net "SG")
	)
	(segment
		(start 112.776 -62.5094)
		(end 113.919 -62.5094)
		(width 0.381)
		(layer "B.Cu")
		(net "SG")
	)
	(segment
		(start 109.8042 -43.866054)
		(end 109.8042 -44.2214)
		(width 0.381)
		(layer "B.Cu")
		(net "SG")
	)
	(segment
		(start 111.346996 -41.32326)
		(end 110.847124 -41.823132)
		(width 0.381)
		(layer "B.Cu")
		(net "SG")
	)
	(segment
		(start 95.758 -19.5326)
		(end 95.885 -19.6596)
		(width 0.381)
		(layer "B.Cu")
		(net "SG")
	)
	(segment
		(start 115.84686 -35.823398)
		(end 115.84686 -35.82289)
		(width 0.381)
		(layer "B.Cu")
		(net "SG")
	)
	(segment
		(start 109.3724 -44.6532)
		(end 109.8042 -44.2214)
		(width 0.381)
		(layer "B.Cu")
		(net "SG")
	)
	(segment
		(start 17.1958 -15.621)
		(end 17.1958 -16.51)
		(width 0.4572)
		(layer "B.Cu")
		(net "SG")
	)
	(segment
		(start 105.847134 -39.822882)
		(end 105.84688 -39.822882)
		(width 0.381)
		(layer "B.Cu")
		(net "SG")
	)
	(segment
		(start 119.847106 -42.82313)
		(end 120.346978 -42.323258)
		(width 0.381)
		(layer "B.Cu")
		(net "SG")
	)
	(segment
		(start 104.84739 -39.823136)
		(end 104.847136 -39.823136)
		(width 0.381)
		(layer "B.Cu")
		(net "SG")
	)
	(segment
		(start 25.146 -90.3986)
		(end 25.273 -90.5256)
		(width 0.381)
		(layer "B.Cu")
		(net "SG")
	)
	(segment
		(start 105.347262 -41.32326)
		(end 104.847644 -41.822878)
		(width 0.381)
		(layer "B.Cu")
		(net "SG")
	)
	(segment
		(start 98.044 -64.8208)
		(end 99.5426 -64.8208)
		(width 0.381)
		(layer "B.Cu")
		(net "SG")
	)
	(segment
		(start 27.2415 -92.2655)
		(end 27.051 -92.456)
		(width 0.381)
		(layer "B.Cu")
		(net "SG")
	)
	(segment
		(start 108.347256 -40.323262)
		(end 108.435394 -40.4114)
		(width 0.381)
		(layer "B.Cu")
		(net "SG")
	)
	(segment
		(start 102.347268 -41.32326)
		(end 102.84714 -41.823132)
		(width 0.381)
		(layer "B.Cu")
		(net "SG")
	)
	(segment
		(start 55.1942 -74.4474)
		(end 54.0512 -74.4474)
		(width 0.381)
		(layer "B.Cu")
		(net "SG")
	)
	(segment
		(start 109.853476 -48.82642)
		(end 109.475524 -49.204372)
		(width 0.254)
		(layer "B.Cu")
		(net "SG")
	)
	(segment
		(start 111.847122 -41.822878)
		(end 111.846614 -41.822878)
		(width 0.381)
		(layer "B.Cu")
		(net "SG")
	)
	(segment
		(start 52.9082 -73.533)
		(end 52.9082 -74.4474)
		(width 0.381)
		(layer "B.Cu")
		(net "SG")
	)
	(segment
		(start 69.166486 -7.3406)
		(end 69.649848 -6.857238)
		(width 0.381)
		(layer "B.Cu")
		(net "SG")
	)
	(segment
		(start 117.847364 -49.823116)
		(end 117.847364 -48.823118)
		(width 0.254)
		(layer "B.Cu")
		(net "SG")
	)
	(segment
		(start 35.5854 -100.4824)
		(end 35.8394 -100.2284)
		(width 0.3048)
		(layer "B.Cu")
		(net "SG")
	)
	(segment
		(start 99.61626 -51.053746)
		(end 99.61626 -51.592734)
		(width 0.381)
		(layer "B.Cu")
		(net "SG")
	)
	(segment
		(start 163.0934 -27.432)
		(end 163.0934 -25.908)
		(width 0.381)
		(layer "B.Cu")
		(net "SG")
	)
	(segment
		(start 141.1478 -18.9738)
		(end 141.1478 -20.2438)
		(width 0.381)
		(layer "B.Cu")
		(net "SG")
	)
	(segment
		(start 105.847388 -51.823112)
		(end 105.847388 -51.822858)
		(width 0.381)
		(layer "B.Cu")
		(net "SG")
	)
	(segment
		(start 105.41 -64.8208)
		(end 106.9086 -64.8208)
		(width 0.381)
		(layer "B.Cu")
		(net "SG")
	)
	(segment
		(start 106.846878 -40.82288)
		(end 106.847132 -40.82288)
		(width 0.381)
		(layer "B.Cu")
		(net "SG")
	)
	(segment
		(start 98.347022 -45.322998)
		(end 97.917 -44.892976)
		(width 0.381)
		(layer "B.Cu")
		(net "SG")
	)
	(segment
		(start 70.649846 -6.857238)
		(end 70.649846 -3.500374)
		(width 0.381)
		(layer "B.Cu")
		(net "SG")
	)
	(segment
		(start 115.4684 -27.559)
		(end 115.062 -27.9654)
		(width 0.381)
		(layer "B.Cu")
		(net "SG")
	)
	(segment
		(start 101.092 -88.1634)
		(end 101.092 -89.408)
		(width 0.381)
		(layer "B.Cu")
		(net "SG")
	)
	(segment
		(start 110.346998 -39.323264)
		(end 110.346998 -39.175944)
		(width 0.381)
		(layer "B.Cu")
		(net "SG")
	)
	(segment
		(start 29.718 -91.7194)
		(end 29.845 -91.5924)
		(width 0.381)
		(layer "B.Cu")
		(net "SG")
	)
	(segment
		(start 99.61626 -51.592734)
		(end 99.846638 -51.823112)
		(width 0.381)
		(layer "B.Cu")
		(net "SG")
	)
	(segment
		(start 106.6546 -44.45)
		(end 106.6546 -45.015658)
		(width 0.381)
		(layer "B.Cu")
		(net "SG")
	)
	(segment
		(start 108.78566 -41.32326)
		(end 109.347 -41.8846)
		(width 0.381)
		(layer "B.Cu")
		(net "SG")
	)
	(segment
		(start 82.7024 -83.693)
		(end 82.7024 -82.55)
		(width 0.381)
		(layer "B.Cu")
		(net "SG")
	)
	(segment
		(start 114.84737 -46.823376)
		(end 114.847116 -46.823376)
		(width 0.381)
		(layer "B.Cu")
		(net "SG")
	)
	(segment
		(start 100.847144 -41.823132)
		(end 100.347018 -42.323258)
		(width 0.381)
		(layer "B.Cu")
		(net "SG")
	)
	(segment
		(start 119.063516 -45.606716)
		(end 118.847362 -45.822616)
		(width 0.381)
		(layer "B.Cu")
		(net "SG")
	)
	(segment
		(start 117.9576 -21.971)
		(end 119.2276 -23.241)
		(width 0.381)
		(layer "B.Cu")
		(net "SG")
	)
	(segment
		(start 97.536 -27.813)
		(end 97.3582 -27.813)
		(width 0.381)
		(layer "B.Cu")
		(net "SG")
	)
	(segment
		(start 106.6546 -45.015658)
		(end 106.34726 -45.322998)
		(width 0.381)
		(layer "B.Cu")
		(net "SG")
	)
	(segment
		(start 98.347022 -37.323268)
		(end 98.347022 -37.323522)
		(width 0.381)
		(layer "B.Cu")
		(net "SG")
	)
	(segment
		(start 112.846866 -40.823388)
		(end 112.84712 -40.823388)
		(width 0.381)
		(layer "B.Cu")
		(net "SG")
	)
	(segment
		(start 30.861 -92.202)
		(end 30.48 -92.583)
		(width 0.381)
		(layer "B.Cu")
		(net "SG")
	)
	(segment
		(start 116.459 -28.9306)
		(end 115.062 -28.9306)
		(width 0.381)
		(layer "B.Cu")
		(net "SG")
	)
	(segment
		(start 17.78 -85.9536)
		(end 17.78 -85.598)
		(width 0.381)
		(layer "B.Cu")
		(net "SG")
	)
	(segment
		(start 98.84664 -54.82336)
		(end 98.84664 -54.823106)
		(width 0.381)
		(layer "B.Cu")
		(net "SG")
	)
	(segment
		(start 98.347022 -55.322978)
		(end 98.84664 -54.82336)
		(width 0.381)
		(layer "B.Cu")
		(net "SG")
	)
	(segment
		(start 83.5406 -72.6186)
		(end 82.423 -72.6186)
		(width 0.381)
		(layer "B.Cu")
		(net "SG")
	)
	(segment
		(start 61.649864 -6.857238)
		(end 61.649864 -3.500374)
		(width 0.381)
		(layer "B.Cu")
		(net "SG")
	)
	(segment
		(start 107.347258 -39.323264)
		(end 107.84713 -39.823136)
		(width 0.381)
		(layer "B.Cu")
		(net "SG")
	)
	(segment
		(start 102.84714 -49.82337)
		(end 102.847648 -49.82337)
		(width 0.381)
		(layer "B.Cu")
		(net "SG")
	)
	(segment
		(start 106.846878 -42.822876)
		(end 106.846878 -42.82313)
		(width 0.381)
		(layer "B.Cu")
		(net "SG")
	)
	(segment
		(start 112.346994 -41.32326)
		(end 112.846866 -40.823388)
		(width 0.381)
		(layer "B.Cu")
		(net "SG")
	)
	(segment
		(start 65.786 -57.5056)
		(end 65.786 -56.642)
		(width 0.381)
		(layer "B.Cu")
		(net "SG")
	)
	(segment
		(start 88.2142 -45.466)
		(end 88.2396 -45.4406)
		(width 0.381)
		(layer "B.Cu")
		(net "SG")
	)
	(segment
		(start 71.133208 -7.3406)
		(end 70.649846 -6.857238)
		(width 0.381)
		(layer "B.Cu")
		(net "SG")
	)
	(segment
		(start 113.847118 -49.823116)
		(end 114.34699 -50.322988)
		(width 0.381)
		(layer "B.Cu")
		(net "SG")
	)
	(segment
		(start 55.1942 -73.533)
		(end 55.1942 -74.4474)
		(width 0.381)
		(layer "B.Cu")
		(net "SG")
	)
	(segment
		(start 119.847106 -54.82336)
		(end 119.846598 -54.82336)
		(width 0.381)
		(layer "B.Cu")
		(net "SG")
	)
	(segment
		(start 104.847644 -41.822878)
		(end 104.847136 -41.822878)
		(width 0.381)
		(layer "B.Cu")
		(net "SG")
	)
	(segment
		(start 117.729 -21.971)
		(end 117.9576 -21.971)
		(width 0.381)
		(layer "B.Cu")
		(net "SG")
	)
	(segment
		(start 109.4994 -18.542)
		(end 110.363 -19.4056)
		(width 0.381)
		(layer "B.Cu")
		(net "SG")
	)
	(segment
		(start 113.846864 -52.82311)
		(end 113.346992 -53.322982)
		(width 0.381)
		(layer "B.Cu")
		(net "SG")
	)
	(segment
		(start 70.866 -57.3532)
		(end 70.866 -58.3184)
		(width 0.381)
		(layer "B.Cu")
		(net "SG")
	)
	(segment
		(start 113.346992 -40.323262)
		(end 113.847118 -39.823136)
		(width 0.381)
		(layer "B.Cu")
		(net "SG")
	)
	(segment
		(start 69.649848 -6.857238)
		(end 69.649848 -3.500374)
		(width 0.381)
		(layer "B.Cu")
		(net "SG")
	)
	(segment
		(start 95.885 -19.6596)
		(end 96.647 -19.6596)
		(width 0.381)
		(layer "B.Cu")
		(net "SG")
	)
	(segment
		(start 106.84764 -47.823374)
		(end 106.847132 -47.823374)
		(width 0.381)
		(layer "B.Cu")
		(net "SG")
	)
	(segment
		(start 37.5666 -76.0476)
		(end 36.83 -75.311)
		(width 0.381)
		(layer "B.Cu")
		(net "SG")
	)
	(segment
		(start 118.8974 -44.873418)
		(end 119.34698 -45.322998)
		(width 0.381)
		(layer "B.Cu")
		(net "SG")
	)
	(segment
		(start 54.0512 -74.4474)
		(end 52.9082 -74.4474)
		(width 0.381)
		(layer "B.Cu")
		(net "SG")
	)
	(segment
		(start 70.866 -56.0324)
		(end 70.866 -56.13654)
		(width 0.381)
		(layer "B.Cu")
		(net "SG")
	)
	(segment
		(start 102.847648 -49.82337)
		(end 103.347266 -50.322988)
		(width 0.381)
		(layer "B.Cu")
		(net "SG")
	)
	(segment
		(start 106.847132 -36.823142)
		(end 107.347258 -37.323268)
		(width 0.381)
		(layer "B.Cu")
		(net "SG")
	)
	(segment
		(start 120.847358 -50.823114)
		(end 120.880886 -50.823114)
		(width 0.381)
		(layer "B.Cu")
		(net "SG")
	)
	(segment
		(start 114.847116 -35.823398)
		(end 115.346988 -36.32327)
		(width 0.381)
		(layer "B.Cu")
		(net "SG")
	)
	(segment
		(start 99.846638 -44.82338)
		(end 99.846892 -44.82338)
		(width 0.381)
		(layer "B.Cu")
		(net "SG")
	)
	(segment
		(start 151.816562 -48.276256)
		(end 151.816562 -47.498)
		(width 0.381)
		(layer "B.Cu")
		(net "SG")
	)
	(segment
		(start 97.23628 -26.15692)
		(end 96.4692 -26.924)
		(width 0.381)
		(layer "B.Cu")
		(net "SG")
	)
	(segment
		(start 99.5426 -64.8208)
		(end 101.0412 -64.8208)
		(width 0.381)
		(layer "B.Cu")
		(net "SG")
	)
	(segment
		(start 163.0934 -24.511)
		(end 163.0934 -25.908)
		(width 0.381)
		(layer "B.Cu")
		(net "SG")
	)
	(segment
		(start 34.9504 -88.9)
		(end 36.068 -88.9)
		(width 0.381)
		(layer "B.Cu")
		(net "SG")
	)
	(segment
		(start 101.0412 -64.8208)
		(end 101.0412 -65.8622)
		(width 0.381)
		(layer "B.Cu")
		(net "SG")
	)
	(segment
		(start 5.0546 -78.105)
		(end 4.064 -78.105)
		(width 0.381)
		(layer "B.Cu")
		(net "SG")
	)
	(segment
		(start 17.7292 -23.1394)
		(end 16.764 -23.1394)
		(width 0.381)
		(layer "B.Cu")
		(net "SG")
	)
	(segment
		(start 119.84736 -52.822602)
		(end 120.346978 -52.322984)
		(width 0.381)
		(layer "B.Cu")
		(net "SG")
	)
	(segment
		(start 140.6652 -61.0108)
		(end 141.097 -60.579)
		(width 0.254)
		(layer "B.Cu")
		(net "SG")
	)
	(segment
		(start 77.649832 -3.500374)
		(end 77.649832 -6.8326)
		(width 0.381)
		(layer "B.Cu")
		(net "SG")
	)
	(segment
		(start 32.131 -92.075)
		(end 32.766 -92.71)
		(width 0.381)
		(layer "B.Cu")
		(net "SG")
	)
	(segment
		(start 21.844 -21.4376)
		(end 21.1582 -22.1234)
		(width 0.381)
		(layer "B.Cu")
		(net "SG")
	)
	(segment
		(start 111.346996 -38.323266)
		(end 110.847378 -38.822884)
		(width 0.381)
		(layer "B.Cu")
		(net "SG")
	)
	(segment
		(start 47.5742 -104.902)
		(end 48.641 -104.902)
		(width 0.381)
		(layer "B.Cu")
		(net "SG")
	)
	(segment
		(start 54.737 -16.6624)
		(end 54.737 -17.399)
		(width 0.381)
		(layer "B.Cu")
		(net "SG")
	)
	(segment
		(start 77.5589 -54.4322)
		(end 78.5622 -54.4322)
		(width 0.381)
		(layer "B.Cu")
		(net "SG")
	)
	(segment
		(start 113.346992 -42.323258)
		(end 113.847118 -41.823132)
		(width 0.381)
		(layer "B.Cu")
		(net "SG")
	)
	(segment
		(start 113.847118 -39.823136)
		(end 113.847118 -39.822882)
		(width 0.381)
		(layer "B.Cu")
		(net "SG")
	)
	(segment
		(start 70.36054 -56.642)
		(end 69.91604 -56.642)
		(width 0.381)
		(layer "B.Cu")
		(net "SG")
	)
	(segment
		(start 141.097 -60.579)
		(end 141.097 -60.4012)
		(width 0.254)
		(layer "B.Cu")
		(net "SG")
	)
	(segment
		(start 108.435394 -40.4114)
		(end 109.347 -40.4114)
		(width 0.381)
		(layer "B.Cu")
		(net "SG")
	)
	(segment
		(start 157.734 -49.980596)
		(end 157.0736 -49.980596)
		(width 0.381)
		(layer "B.Cu")
		(net "SG")
	)
	(segment
		(start 113.847372 -42.823638)
		(end 113.847372 -42.82313)
		(width 0.381)
		(layer "B.Cu")
		(net "SG")
	)
	(segment
		(start 22.5806 -18.034)
		(end 22.5806 -17.018)
		(width 0.381)
		(layer "B.Cu")
		(net "SG")
	)
	(segment
		(start 101.846888 -40.82288)
		(end 101.847142 -40.82288)
		(width 0.381)
		(layer "B.Cu")
		(net "SG")
	)
	(segment
		(start 106.34726 -42.323258)
		(end 106.846878 -42.822876)
		(width 0.381)
		(layer "B.Cu")
		(net "SG")
	)
	(segment
		(start 112.411764 -56.388)
		(end 113.15319 -56.388)
		(width 0.381)
		(layer "B.Cu")
		(net "SG")
	)
	(segment
		(start 106.045 -89.408)
		(end 105.918 -89.281)
		(width 0.381)
		(layer "B.Cu")
		(net "SG")
	)
	(segment
		(start 97.917 -44.59478)
		(end 97.64522 -44.323)
		(width 0.381)
		(layer "B.Cu")
		(net "SG")
	)
	(segment
		(start 117.346984 -40.323262)
		(end 117.846856 -39.82339)
		(width 0.381)
		(layer "B.Cu")
		(net "SG")
	)
	(segment
		(start 101.346 -58.8645)
		(end 101.1555 -59.055)
		(width 0.381)
		(layer "B.Cu")
		(net "SG")
	)
	(segment
		(start 30.226 -93.472)
		(end 29.718 -92.964)
		(width 0.381)
		(layer "B.Cu")
		(net "SG")
	)
	(segment
		(start 13.9827 -74.0283)
		(end 13.9827 -74.97064)
		(width 0.381)
		(layer "B.Cu")
		(net "SG")
	)
	(segment
		(start 106.846878 -45.822616)
		(end 106.846878 -45.823124)
		(width 0.381)
		(layer "B.Cu")
		(net "SG")
	)
	(segment
		(start 17.78 -85.598)
		(end 18.288 -85.09)
		(width 0.381)
		(layer "B.Cu")
		(net "SG")
	)
	(segment
		(start 118.847362 -45.822616)
		(end 118.847362 -45.823124)
		(width 0.381)
		(layer "B.Cu")
		(net "SG")
	)
	(segment
		(start 54.737 -17.399)
		(end 54.61 -17.526)
		(width 0.381)
		(layer "B.Cu")
		(net "SG")
	)
	(segment
		(start 109.3724 -45.593)
		(end 109.3724 -44.6532)
		(width 0.381)
		(layer "B.Cu")
		(net "SG")
	)
	(segment
		(start 113.847118 -45.82287)
		(end 113.846864 -45.82287)
		(width 0.381)
		(layer "B.Cu")
		(net "SG")
	)
	(segment
		(start 107.847638 -54.82336)
		(end 107.84713 -54.82336)
		(width 0.381)
		(layer "B.Cu")
		(net "SG")
	)
	(segment
		(start 5.0546 -76.835)
		(end 4.064 -76.835)
		(width 0.381)
		(layer "B.Cu")
		(net "SG")
	)
	(segment
		(start 122.23115 -46.256194)
		(end 121.412 -46.256194)
		(width 0.381)
		(layer "B.Cu")
		(net "SG")
	)
	(segment
		(start 108.347256 -55.322978)
		(end 107.847638 -54.82336)
		(width 0.381)
		(layer "B.Cu")
		(net "SG")
	)
	(segment
		(start 104.846882 -37.822886)
		(end 104.846882 -37.82314)
		(width 0.381)
		(layer "B.Cu")
		(net "SG")
	)
	(segment
		(start 107.347258 -37.323268)
		(end 106.84764 -37.822886)
		(width 0.381)
		(layer "B.Cu")
		(net "SG")
	)
	(segment
		(start 101.346 -57.15)
		(end 101.346 -58.8645)
		(width 0.381)
		(layer "B.Cu")
		(net "SG")
	)
	(segment
		(start 35.6616 -90.3986)
		(end 35.7886 -90.2716)
		(width 0.381)
		(layer "B.Cu")
		(net "SG")
	)
	(segment
		(start 101.0412 -64.8208)
		(end 102.5398 -64.8208)
		(width 0.381)
		(layer "B.Cu")
		(net "SG")
	)
	(segment
		(start 126.0094 -69.2912)
		(end 125.2474 -69.2912)
		(width 0.3048)
		(layer "B.Cu")
		(net "SG")
	)
	(segment
		(start 117.846856 -39.82339)
		(end 117.846856 -39.823136)
		(width 0.381)
		(layer "B.Cu")
		(net "SG")
	)
	(segment
		(start 103.846884 -49.82337)
		(end 103.846884 -49.823116)
		(width 0.381)
		(layer "B.Cu")
		(net "SG")
	)
	(segment
		(start 26.289 -78.5876)
		(end 26.289 -77.851)
		(width 0.381)
		(layer "B.Cu")
		(net "SG")
	)
	(segment
		(start 110.346998 -43.323256)
		(end 109.8042 -43.866054)
		(width 0.381)
		(layer "B.Cu")
		(net "SG")
	)
	(segment
		(start 106.34726 -45.322998)
		(end 106.846878 -45.822616)
		(width 0.381)
		(layer "B.Cu")
		(net "SG")
	)
	(segment
		(start 113.413794 -44.577)
		(end 113.413794 -45.256196)
		(width 0.381)
		(layer "B.Cu")
		(net "SG")
	)
	(segment
		(start 75.1332 -7.3406)
		(end 74.649838 -6.857238)
		(width 0.381)
		(layer "B.Cu")
		(net "SG")
	)
	(segment
		(start 5.08 -71.8566)
		(end 5.0546 -71.882)
		(width 0.381)
		(layer "B.Cu")
		(net "SG")
	)
	(segment
		(start 99.34702 -52.322984)
		(end 99.846638 -51.823366)
		(width 0.381)
		(layer "B.Cu")
		(net "SG")
	)
	(segment
		(start 100.347018 -38.323266)
		(end 100.84689 -38.823138)
		(width 0.381)
		(layer "B.Cu")
		(net "SG")
	)
	(segment
		(start 34.925 -90.3986)
		(end 35.6616 -90.3986)
		(width 0.381)
		(layer "B.Cu")
		(net "SG")
	)
	(segment
		(start 32.131 -91.5924)
		(end 32.131 -92.075)
		(width 0.381)
		(layer "B.Cu")
		(net "SG")
	)
	(segment
		(start 107.696 -101.3714)
		(end 106.4641 -102.6033)
		(width 0.381)
		(layer "B.Cu")
		(net "SG")
	)
	(segment
		(start 7.366 -71.8566)
		(end 5.08 -71.8566)
		(width 0.381)
		(layer "B.Cu")
		(net "SG")
	)
	(segment
		(start 82.3722 -95.4278)
		(end 80.899 -95.4278)
		(width 0.381)
		(layer "B.Cu")
		(net "SG")
	)
	(segment
		(start 25.146 -88.9)
		(end 25.146 -90.3986)
		(width 0.381)
		(layer "B.Cu")
		(net "SG")
	)
	(segment
		(start 109.728 -24.4094)
		(end 108.585 -24.4094)
		(width 0.381)
		(layer "B.Cu")
		(net "SG")
	)
	(segment
		(start 41.402 -89.0016)
		(end 40.4114 -89.0016)
		(width 0.381)
		(layer "B.Cu")
		(net "SG")
	)
	(segment
		(start 21.7932 -71.9074)
		(end 21.7932 -73.012808)
		(width 0.381)
		(layer "B.Cu")
		(net "SG")
	)
	(segment
		(start 103.9622 -64.8208)
		(end 105.41 -64.8208)
		(width 0.381)
		(layer "B.Cu")
		(net "SG")
	)
	(segment
		(start 110.363 -19.4056)
		(end 110.363 -19.558)
		(width 0.381)
		(layer "B.Cu")
		(net "SG")
	)
	(segment
		(start 106.34726 -40.323262)
		(end 106.846878 -40.82288)
		(width 0.381)
		(layer "B.Cu")
		(net "SG")
	)
	(segment
		(start 115.347242 -43.323256)
		(end 115.347242 -44.224448)
		(width 0.381)
		(layer "B.Cu")
		(net "SG")
	)
	(segment
		(start 104.846882 -38.823646)
		(end 104.846882 -38.823138)
		(width 0.381)
		(layer "B.Cu")
		(net "SG")
	)
	(segment
		(start 99.846892 -52.822856)
		(end 99.34702 -52.322984)
		(width 0.381)
		(layer "B.Cu")
		(net "SG")
	)
	(segment
		(start 30.48 -93.472)
		(end 30.226 -93.472)
		(width 0.381)
		(layer "B.Cu")
		(net "SG")
	)
	(segment
		(start 64.649858 -3.500374)
		(end 64.649858 -7.3406)
		(width 0.381)
		(layer "B.Cu")
		(net "SG")
	)
	(segment
		(start 115.347242 -44.224448)
		(end 115.699794 -44.577)
		(width 0.381)
		(layer "B.Cu")
		(net "SG")
	)
	(segment
		(start 157.0736 -49.980596)
		(end 156.591 -49.497996)
		(width 0.381)
		(layer "B.Cu")
		(net "SG")
	)
	(segment
		(start 137.2616 -17.526)
		(end 136.398 -17.526)
		(width 0.381)
		(layer "B.Cu")
		(net "SG")
	)
	(segment
		(start 5.0546 -71.882)
		(end 5.0546 -73.025)
		(width 0.381)
		(layer "B.Cu")
		(net "SG")
	)
	(segment
		(start 97.917 -44.892976)
		(end 97.917 -44.59478)
		(width 0.381)
		(layer "B.Cu")
		(net "SG")
	)
	(segment
		(start 35.8394 -100.2284)
		(end 36.449 -100.2284)
		(width 0.3048)
		(layer "B.Cu")
		(net "SG")
	)
	(segment
		(start 113.413794 -45.256196)
		(end 113.346992 -45.322998)
		(width 0.381)
		(layer "B.Cu")
		(net "SG")
	)
	(segment
		(start 30.3784 -88.265)
		(end 31.369 -88.265)
		(width 0.381)
		(layer "B.Cu")
		(net "SG")
	)
	(segment
		(start 82.804 -94.996)
		(end 82.3722 -95.4278)
		(width 0.381)
		(layer "B.Cu")
		(net "SG")
	)
	(segment
		(start 113.202974 -56.437784)
		(end 113.15319 -56.388)
		(width 0.381)
		(layer "B.Cu")
		(net "SG")
	)
	(segment
		(start 125.2982 -32.0802)
		(end 124.3076 -32.0802)
		(width 0.381)
		(layer "B.Cu")
		(net "SG")
	)
	(segment
		(start 83.947 -73.025)
		(end 83.5406 -72.6186)
		(width 0.381)
		(layer "B.Cu")
		(net "SG")
	)
	(segment
		(start 105.918 -89.281)
		(end 105.918 -88.1634)
		(width 0.381)
		(layer "B.Cu")
		(net "SG")
	)
	(segment
		(start 119.846598 -54.82336)
		(end 119.34698 -55.322978)
		(width 0.381)
		(layer "B.Cu")
		(net "SG")
	)
	(segment
		(start 91.44 -102.2096)
		(end 91.2368 -102.4128)
		(width 0.3048)
		(layer "B.Cu")
		(net "SG")
	)
	(segment
		(start 119.34698 -55.322978)
		(end 118.847362 -54.82336)
		(width 0.381)
		(layer "B.Cu")
		(net "SG")
	)
	(segment
		(start 105.847642 -50.823368)
		(end 105.847134 -50.823368)
		(width 0.381)
		(layer "B.Cu")
		(net "SG")
	)
	(segment
		(start 111.847376 -45.823378)
		(end 112.346994 -46.322996)
		(width 0.381)
		(layer "B.Cu")
		(net "SG")
	)
	(segment
		(start 115.346988 -47.322994)
		(end 114.84737 -46.823376)
		(width 0.381)
		(layer "B.Cu")
		(net "SG")
	)
	(segment
		(start 125.2474 -69.2912)
		(end 125.095 -69.1388)
		(width 0.3048)
		(layer "B.Cu")
		(net "SG")
	)
	(segment
		(start 44.4119 -86.0552)
		(end 42.3418 -86.0552)
		(width 0.381)
		(layer "B.Cu")
		(net "SG")
	)
	(segment
		(start 89.0524 -84.455)
		(end 90.17 -84.455)
		(width 0.3048)
		(layer "B.Cu")
		(net "SG")
	)
	(segment
		(start 118.847362 -54.82336)
		(end 118.847108 -54.82336)
		(width 0.381)
		(layer "B.Cu")
		(net "SG")
	)
	(segment
		(start 78.5622 -54.4322)
		(end 79.248 -55.118)
		(width 0.381)
		(layer "B.Cu")
		(net "SG")
	)
	(segment
		(start 82.7024 -82.55)
		(end 81.8388 -82.55)
		(width 0.381)
		(layer "B.Cu")
		(net "SG")
	)
	(segment
		(start 115.062 -27.9654)
		(end 115.062 -28.9306)
		(width 0.381)
		(layer "B.Cu")
		(net "SG")
	)
	(segment
		(start 118.346982 -48.322992)
		(end 117.847364 -48.82261)
		(width 0.381)
		(layer "B.Cu")
		(net "SG")
	)
	(segment
		(start 99.8982 -78.5368)
		(end 99.8982 -79.375)
		(width 0.3048)
		(layer "B.Cu")
		(net "SG")
	)
	(segment
		(start 105.84688 -39.822882)
		(end 105.347262 -39.323264)
		(width 0.381)
		(layer "B.Cu")
		(net "SG")
	)
	(segment
		(start 109.560614 -51.5366)
		(end 109.22 -51.5366)
		(width 0.381)
		(layer "B.Cu")
		(net "SG")
	)
	(segment
		(start 117.847364 -48.82261)
		(end 117.847364 -48.823118)
		(width 0.381)
		(layer "B.Cu")
		(net "SG")
	)
	(segment
		(start 107.84713 -41.823132)
		(end 107.84713 -41.823386)
		(width 0.381)
		(layer "B.Cu")
		(net "SG")
	)
	(segment
		(start 151.613108 -48.47971)
		(end 151.816562 -48.276256)
		(width 0.381)
		(layer "B.Cu")
		(net "SG")
	)
	(segment
		(start 101.34727 -45.322998)
		(end 101.846888 -45.822616)
		(width 0.381)
		(layer "B.Cu")
		(net "SG")
	)
	(segment
		(start 100.9142 -82.2706)
		(end 100.9142 -81.4578)
		(width 0.381)
		(layer "B.Cu")
		(net "SG")
	)
	(segment
		(start 163.0934 -27.5844)
		(end 164.338 -28.829)
		(width 0.381)
		(layer "B.Cu")
		(net "SG")
	)
	(segment
		(start 107.84713 -39.823136)
		(end 107.847384 -39.823136)
		(width 0.381)
		(layer "B.Cu")
		(net "SG")
	)
	(segment
		(start 112.346994 -35.323018)
		(end 112.846866 -35.82289)
		(width 0.381)
		(layer "B.Cu")
		(net "SG")
	)
	(segment
		(start 67.133216 -7.3406)
		(end 66.649854 -6.857238)
		(width 0.381)
		(layer "B.Cu")
		(net "SG")
	)
	(segment
		(start 102.84714 -41.823132)
		(end 102.84714 -41.823386)
		(width 0.381)
		(layer "B.Cu")
		(net "SG")
	)
	(segment
		(start 77.649832 -6.8326)
		(end 78.157832 -7.3406)
		(width 0.381)
		(layer "B.Cu")
		(net "SG")
	)
	(segment
		(start 100.84689 -48.823118)
		(end 100.347018 -49.32299)
		(width 0.381)
		(layer "B.Cu")
		(net "SG")
	)
	(segment
		(start 112.776 -62.5094)
		(end 112.776 -63.5)
		(width 0.381)
		(layer "B.Cu")
		(net "SG")
	)
	(segment
		(start 61.326014 -55.7022)
		(end 61.326014 -54.61)
		(width 0.254)
		(layer "B.Cu")
		(net "SG")
	)
	(segment
		(start 71.247 -56.9722)
		(end 70.866 -57.3532)
		(width 0.381)
		(layer "B.Cu")
		(net "SG")
	)
	(segment
		(start 110.850426 -48.82642)
		(end 109.853476 -48.82642)
		(width 0.254)
		(layer "B.Cu")
		(net "SG")
	)
	(segment
		(start 106.84764 -37.822886)
		(end 106.847132 -37.822886)
		(width 0.381)
		(layer "B.Cu")
		(net "SG")
	)
	(segment
		(start 134.0612 -66.3194)
		(end 134.0612 -66.07302)
		(width 0.381)
		(layer "B.Cu")
		(net "SG")
	)
	(segment
		(start 21.1582 -23.1394)
		(end 21.1582 -22.1234)
		(width 0.381)
		(layer "B.Cu")
		(net "SG")
	)
	(segment
		(start 28.067 -92.456)
		(end 27.94 -92.456)
		(width 0.381)
		(layer "B.Cu")
		(net "SG")
	)
	(segment
		(start 146.1262 -50.546)
		(end 146.1262 -51.3588)
		(width 0.381)
		(layer "B.Cu")
		(net "SG")
	)
	(segment
		(start 115.346988 -36.32327)
		(end 115.84686 -35.823398)
		(width 0.381)
		(layer "B.Cu")
		(net "SG")
	)
	(segment
		(start 141.097 -60.4012)
		(end 141.097 -60.0964)
		(width 0.3048)
		(layer "B.Cu")
		(net "SG")
	)
	(segment
		(start 58.64987 -6.93547)
		(end 59.1058 -7.3914)
		(width 0.381)
		(layer "B.Cu")
		(net "SG")
	)
	(segment
		(start 111.6584 -100.711)
		(end 112.522 -100.711)
		(width 0.381)
		(layer "B.Cu")
		(net "SG")
	)
	(segment
		(start 104.347264 -45.322998)
		(end 104.347264 -44.708064)
		(width 0.381)
		(layer "B.Cu")
		(net "SG")
	)
	(segment
		(start 105.847134 -42.823384)
		(end 106.34726 -42.323258)
		(width 0.381)
		(layer "B.Cu")
		(net "SG")
	)
	(segment
		(start 101.846888 -45.822616)
		(end 101.846888 -45.823124)
		(width 0.381)
		(layer "B.Cu")
		(net "SG")
	)
	(segment
		(start 103.347266 -50.322988)
		(end 103.846884 -49.82337)
		(width 0.381)
		(layer "B.Cu")
		(net "SG")
	)
	(segment
		(start 121.073164 -35.272218)
		(end 121.886218 -35.272218)
		(width 0.381)
		(layer "B.Cu")
		(net "SG")
	)
	(segment
		(start 55.88 -16.6624)
		(end 55.88 -17.526)
		(width 0.381)
		(layer "B.Cu")
		(net "SG")
	)
	(segment
		(start 99.846638 -51.823366)
		(end 99.846638 -51.823112)
		(width 0.381)
		(layer "B.Cu")
		(net "SG")
	)
	(segment
		(start 47.879 -76.2)
		(end 48.26 -76.581)
		(width 0.381)
		(layer "B.Cu")
		(net "SG")
	)
	(segment
		(start 111.846614 -41.822878)
		(end 111.346996 -41.32326)
		(width 0.381)
		(layer "B.Cu")
		(net "SG")
	)
	(segment
		(start 102.84714 -35.823398)
		(end 102.347268 -36.32327)
		(width 0.381)
		(layer "B.Cu")
		(net "SG")
	)
	(segment
		(start 146.6088 -16.7132)
		(end 147.447 -16.7132)
		(width 0.381)
		(layer "B.Cu")
		(net "SG")
	)
	(segment
		(start 97.536 -26.15692)
		(end 97.23628 -26.15692)
		(width 0.381)
		(layer "B.Cu")
		(net "SG")
	)
	(segment
		(start 48.64989 -3.500374)
		(end 48.64989 -7.3406)
		(width 0.381)
		(layer "B.Cu")
		(net "SG")
	)
	(segment
		(start 139.3317 -68.0593)
		(end 139.446 -67.945)
		(width 0.381)
		(layer "B.Cu")
		(net "SG")
	)
	(segment
		(start 68.326 -55.7149)
		(end 68.326 -54.61)
		(width 0.381)
		(layer "B.Cu")
		(net "SG")
	)
	(segment
		(start 117.847364 -47.823374)
		(end 118.346982 -48.322992)
		(width 0.381)
		(layer "B.Cu")
		(net "SG")
	)
	(segment
		(start 113.847118 -41.823132)
		(end 113.847372 -41.823132)
		(width 0.381)
		(layer "B.Cu")
		(net "SG")
	)
	(segment
		(start 111.847122 -34.823146)
		(end 112.346994 -35.323018)
		(width 0.381)
		(layer "B.Cu")
		(net "SG")
	)
	(segment
		(start 108.585 -25.4)
		(end 108.6612 -25.4762)
		(width 0.381)
		(layer "B.Cu")
		(net "SG")
	)
	(segment
		(start 107.696 -101.1682)
		(end 107.696 -101.3714)
		(width 0.381)
		(layer "B.Cu")
		(net "SG")
	)
	(segment
		(start 110.346998 -52.322984)
		(end 109.560614 -51.5366)
		(width 0.381)
		(layer "B.Cu")
		(net "SG")
	)
	(segment
		(start 102.5398 -64.8208)
		(end 102.5398 -65.8622)
		(width 0.381)
		(layer "B.Cu")
		(net "SG")
	)
	(segment
		(start 122.301 -46.232064)
		(end 122.25528 -46.232064)
		(width 0.381)
		(layer "B.Cu")
		(net "SG")
	)
	(segment
		(start 111.847122 -55.823358)
		(end 112.411764 -56.388)
		(width 0.381)
		(layer "B.Cu")
		(net "SG")
	)
	(segment
		(start 99.846892 -50.823114)
		(end 99.61626 -51.053746)
		(width 0.381)
		(layer "B.Cu")
		(net "SG")
	)
	(segment
		(start 97.5106 -95.4532)
		(end 97.5106 -94.6404)
		(width 0.381)
		(layer "B.Cu")
		(net "SG")
	)
	(segment
		(start 27.559 -91.5924)
		(end 27.559 -91.84894)
		(width 0.381)
		(layer "B.Cu")
		(net "SG")
	)
	(segment
		(start 91.2368 -102.4128)
		(end 90.5256 -102.4128)
		(width 0.3048)
		(layer "B.Cu")
		(net "SG")
	)
	(segment
		(start 146.3548 -97.9678)
		(end 147.3962 -97.9678)
		(width 0.381)
		(layer "B.Cu")
		(net "SG")
	)
	(segment
		(start 73.166478 -7.3406)
		(end 73.64984 -6.857238)
		(width 0.381)
		(layer "B.Cu")
		(net "SG")
	)
	(segment
		(start 70.866 -56.13654)
		(end 70.36054 -56.642)
		(width 0.381)
		(layer "B.Cu")
		(net "SG")
	)
	(segment
		(start 110.847378 -38.822884)
		(end 110.847124 -38.822884)
		(width 0.381)
		(layer "B.Cu")
		(net "SG")
	)
	(segment
		(start 114.34699 -43.323256)
		(end 113.847372 -42.823638)
		(width 0.381)
		(layer "B.Cu")
		(net "SG")
	)
	(segment
		(start 146.685 -67.818)
		(end 145.8595 -66.9925)
		(width 0.381)
		(layer "B.Cu")
		(net "SG")
	)
	(segment
		(start 27.559 -91.84894)
		(end 27.2415 -92.16644)
		(width 0.381)
		(layer "B.Cu")
		(net "SG")
	)
	(segment
		(start 96.5454 -64.8208)
		(end 98.044 -64.8208)
		(width 0.381)
		(layer "B.Cu")
		(net "SG")
	)
	(segment
		(start 21.1582 -23.1394)
		(end 22.3012 -23.1394)
		(width 0.381)
		(layer "B.Cu")
		(net "SG")
	)
	(segment
		(start 150.343108 -50.8762)
		(end 150.343108 -49.54651)
		(width 0.11938)
		(layer "F.Cu")
		(net "R_SHT3X_I2C_SDA")
	)
	(segment
		(start 150.7236 -50.8762)
		(end 150.343108 -50.8762)
		(width 0.11938)
		(layer "F.Cu")
		(net "R_SHT3X_I2C_SDA")
	)
	(segment
		(start 151.395938 -51.548538)
		(end 150.7236 -50.8762)
		(width 0.11938)
		(layer "F.Cu")
		(net "R_SHT3X_I2C_SDA")
	)
	(segment
		(start 151.395938 -51.922172)
		(end 151.395938 -51.548538)
		(width 0.11938)
		(layer "F.Cu")
		(net "R_SHT3X_I2C_SDA")
	)
	(via
		(at 150.343108 -50.8762)
		(size 0.4572)
		(drill 0.2032)
		(layers "F.Cu" "B.Cu")
		(net "R_SHT3X_I2C_SDA")
	)
	(segment
		(start 154.153108 -51.307492)
		(end 154.153108 -50.9016)
		(width 0.11938)
		(layer "F.Cu")
		(net "R_SHT3X_I2C_SCL")
	)
	(segment
		(start 154.153108 -49.54651)
		(end 154.153108 -50.9016)
		(width 0.11938)
		(layer "F.Cu")
		(net "R_SHT3X_I2C_SCL")
	)
	(segment
		(start 153.538428 -51.922172)
		(end 154.153108 -51.307492)
		(width 0.11938)
		(layer "F.Cu")
		(net "R_SHT3X_I2C_SCL")
	)
	(segment
		(start 152.896062 -51.922172)
		(end 153.538428 -51.922172)
		(width 0.11938)
		(layer "F.Cu")
		(net "R_SHT3X_I2C_SCL")
	)
	(via
		(at 154.153108 -50.9016)
		(size 0.4572)
		(drill 0.2032)
		(layers "F.Cu" "B.Cu")
		(net "R_SHT3X_I2C_SCL")
	)
	(segment
		(start 78.21422 -47.8028)
		(end 77.354176 -48.662844)
		(width 0.14478)
		(layer "F.Cu")
		(net "R_MAC_USB_DP")
	)
	(segment
		(start 76.646532 -48.95596)
		(end 75.503786 -48.95596)
		(width 0.14478)
		(layer "F.Cu")
		(net "R_MAC_USB_DP")
	)
	(segment
		(start 79.2226 -48.133)
		(end 78.8924 -47.8028)
		(width 0.14478)
		(layer "F.Cu")
		(net "R_MAC_USB_DP")
	)
	(segment
		(start 75.463146 -48.9966)
		(end 74.354436 -48.9966)
		(width 0.14478)
		(layer "F.Cu")
		(net "R_MAC_USB_DP")
	)
	(segment
		(start 75.503786 -48.95596)
		(end 75.463146 -48.9966)
		(width 0.14478)
		(layer "F.Cu")
		(net "R_MAC_USB_DP")
	)
	(arc
		(start 77.354176 -48.662844)
		(mid 77.029492 -48.879728)
		(end 76.646532 -48.95596)
		(width 0.14478)
		(layer "F.Cu")
		(net "R_MAC_USB_DP")
	)
	(arc
		(start 78.8924 -47.8028)
		(mid 78.55331 -47.662344)
		(end 78.21422 -47.8028)
		(width 0.14478)
		(layer "F.Cu")
		(net "R_MAC_USB_DP")
	)
	(segment
		(start 77.944726 -47.533306)
		(end 77.084682 -48.39335)
		(width 0.14478)
		(layer "F.Cu")
		(net "R_MAC_USB_DM")
	)
	(segment
		(start 76.646278 -48.57496)
		(end 75.55865 -48.57496)
		(width 0.14478)
		(layer "F.Cu")
		(net "R_MAC_USB_DM")
	)
	(segment
		(start 79.2226 -46.99)
		(end 79.006192 -47.206408)
		(width 0.14478)
		(layer "F.Cu")
		(net "R_MAC_USB_DM")
	)
	(segment
		(start 75.332336 -48.496728)
		(end 74.354436 -48.496728)
		(width 0.14478)
		(layer "F.Cu")
		(net "R_MAC_USB_DM")
	)
	(arc
		(start 75.55865 -48.57496)
		(mid 75.511361 -48.567107)
		(end 75.469242 -48.544226)
		(width 0.14478)
		(layer "F.Cu")
		(net "R_MAC_USB_DM")
	)
	(arc
		(start 79.006192 -47.206408)
		(mid 78.926436 -47.274517)
		(end 78.837028 -47.329344)
		(width 0.14478)
		(layer "F.Cu")
		(net "R_MAC_USB_DM")
	)
	(arc
		(start 78.837028 -47.329344)
		(mid 78.361518 -47.302877)
		(end 77.944726 -47.533306)
		(width 0.14478)
		(layer "F.Cu")
		(net "R_MAC_USB_DM")
	)
	(arc
		(start 77.084682 -48.39335)
		(mid 76.883541 -48.527748)
		(end 76.646278 -48.57496)
		(width 0.14478)
		(layer "F.Cu")
		(net "R_MAC_USB_DM")
	)
	(arc
		(start 75.469242 -48.544226)
		(mid 75.404788 -48.508933)
		(end 75.332336 -48.496728)
		(width 0.14478)
		(layer "F.Cu")
		(net "R_MAC_USB_DM")
	)
	(segment
		(start 128.778 -47.879)
		(end 130.5052 -47.879)
		(width 0.11938)
		(layer "F.Cu")
		(net "R_MAC_UART_TX_FPGA_RX")
	)
	(segment
		(start 128.778 -47.879)
		(end 128.016 -48.641)
		(width 0.11938)
		(layer "F.Cu")
		(net "R_MAC_UART_TX_FPGA_RX")
	)
	(segment
		(start 130.5052 -47.879)
		(end 132.52196 -49.89576)
		(width 0.11938)
		(layer "F.Cu")
		(net "R_MAC_UART_TX_FPGA_RX")
	)
	(segment
		(start 128.016 -49.149)
		(end 126.373382 -50.791618)
		(width 0.11938)
		(layer "F.Cu")
		(net "R_MAC_UART_TX_FPGA_RX")
	)
	(segment
		(start 132.52196 -49.89576)
		(end 132.52196 -59.11596)
		(width 0.11938)
		(layer "F.Cu")
		(net "R_MAC_UART_TX_FPGA_RX")
	)
	(segment
		(start 153.67 -63.5)
		(end 154.813 -64.643)
		(width 0.11938)
		(layer "F.Cu")
		(net "R_MAC_UART_TX_FPGA_RX")
	)
	(segment
		(start 128.016 -48.641)
		(end 128.016 -49.149)
		(width 0.11938)
		(layer "F.Cu")
		(net "R_MAC_UART_TX_FPGA_RX")
	)
	(segment
		(start 136.906 -63.5)
		(end 153.67 -63.5)
		(width 0.11938)
		(layer "F.Cu")
		(net "R_MAC_UART_TX_FPGA_RX")
	)
	(segment
		(start 125.747018 -50.791618)
		(end 125.1204 -50.165)
		(width 0.11938)
		(layer "F.Cu")
		(net "R_MAC_UART_TX_FPGA_RX")
	)
	(segment
		(start 132.52196 -59.11596)
		(end 136.906 -63.5)
		(width 0.11938)
		(layer "F.Cu")
		(net "R_MAC_UART_TX_FPGA_RX")
	)
	(segment
		(start 126.373382 -50.791618)
		(end 125.747018 -50.791618)
		(width 0.11938)
		(layer "F.Cu")
		(net "R_MAC_UART_TX_FPGA_RX")
	)
	(via
		(at 135.382 -25.273)
		(size 0.4572)
		(drill 0.2032)
		(layers "F.Cu" "B.Cu")
		(net "R_MAC_UART_TX_FPGA_RX")
	)
	(via
		(at 154.813 -64.643)
		(size 0.508)
		(drill 0.254)
		(layers "F.Cu" "B.Cu")
		(net "R_MAC_UART_TX_FPGA_RX")
	)
	(via
		(at 88.646 -20.955)
		(size 0.4572)
		(drill 0.2032)
		(layers "F.Cu" "B.Cu")
		(net "R_MAC_UART_TX_FPGA_RX")
	)
	(via
		(at 128.778 -47.879)
		(size 0.508)
		(drill 0.254)
		(layers "F.Cu" "B.Cu")
		(net "R_MAC_UART_TX_FPGA_RX")
	)
	(segment
		(start 154.813 -69.3674)
		(end 154.813 -64.643)
		(width 0.11938)
		(layer "B.Cu")
		(net "R_MAC_UART_TX_FPGA_RX")
	)
	(segment
		(start 95.25 -16.51)
		(end 90.17 -21.59)
		(width 0.11938)
		(layer "B.Cu")
		(net "R_MAC_UART_TX_FPGA_RX")
	)
	(segment
		(start 89.281 -21.59)
		(end 88.646 -20.955)
		(width 0.11938)
		(layer "B.Cu")
		(net "R_MAC_UART_TX_FPGA_RX")
	)
	(segment
		(start 153.3144 -70.866)
		(end 154.813 -69.3674)
		(width 0.11938)
		(layer "B.Cu")
		(net "R_MAC_UART_TX_FPGA_RX")
	)
	(segment
		(start 123.19 -16.51)
		(end 95.25 -16.51)
		(width 0.11938)
		(layer "B.Cu")
		(net "R_MAC_UART_TX_FPGA_RX")
	)
	(segment
		(start 129.921 -23.241)
		(end 123.19 -16.51)
		(width 0.11938)
		(layer "B.Cu")
		(net "R_MAC_UART_TX_FPGA_RX")
	)
	(segment
		(start 133.53542 -23.42642)
		(end 130.119882 -23.42642)
		(width 0.11938)
		(layer "B.Cu")
		(net "R_MAC_UART_TX_FPGA_RX")
	)
	(segment
		(start 90.17 -21.59)
		(end 89.281 -21.59)
		(width 0.11938)
		(layer "B.Cu")
		(net "R_MAC_UART_TX_FPGA_RX")
	)
	(segment
		(start 130.119882 -23.42642)
		(end 129.934462 -23.241)
		(width 0.11938)
		(layer "B.Cu")
		(net "R_MAC_UART_TX_FPGA_RX")
	)
	(segment
		(start 129.934462 -23.241)
		(end 129.921 -23.241)
		(width 0.11938)
		(layer "B.Cu")
		(net "R_MAC_UART_TX_FPGA_RX")
	)
	(segment
		(start 135.382 -25.273)
		(end 133.53542 -23.42642)
		(width 0.11938)
		(layer "B.Cu")
		(net "R_MAC_UART_TX_FPGA_RX")
	)
	(segment
		(start 136.6901 -28.659328)
		(end 136.5631 -28.786328)
		(width 0.127)
		(layer "In2.Cu")
		(net "R_MAC_UART_TX_FPGA_RX")
	)
	(segment
		(start 128.778 -45.165518)
		(end 128.778 -47.879)
		(width 0.127)
		(layer "In2.Cu")
		(net "R_MAC_UART_TX_FPGA_RX")
	)
	(segment
		(start 135.382 -29.21)
		(end 132.334 -32.258)
		(width 0.127)
		(layer "In2.Cu")
		(net "R_MAC_UART_TX_FPGA_RX")
	)
	(segment
		(start 137.11682 -27.389328)
		(end 136.98982 -27.516328)
		(width 0.127)
		(layer "In2.Cu")
		(net "R_MAC_UART_TX_FPGA_RX")
	)
	(segment
		(start 135.382 -27.643328)
		(end 135.382 -28.024328)
		(width 0.127)
		(layer "In2.Cu")
		(net "R_MAC_UART_TX_FPGA_RX")
	)
	(segment
		(start 67.555618 -23.734522)
		(end 69.270118 -22.020022)
		(width 0.127)
		(layer "In2.Cu")
		(net "R_MAC_UART_TX_FPGA_RX")
	)
	(segment
		(start 79.954628 -24.62784)
		(end 84.071968 -20.5105)
		(width 0.127)
		(layer "In2.Cu")
		(net "R_MAC_UART_TX_FPGA_RX")
	)
	(segment
		(start 136.5631 -28.151328)
		(end 136.6901 -28.278328)
		(width 0.127)
		(layer "In2.Cu")
		(net "R_MAC_UART_TX_FPGA_RX")
	)
	(segment
		(start 135.382 -25.273)
		(end 135.382 -26.754328)
		(width 0.127)
		(layer "In2.Cu")
		(net "R_MAC_UART_TX_FPGA_RX")
	)
	(segment
		(start 132.334 -32.258)
		(end 132.334 -41.609518)
		(width 0.127)
		(layer "In2.Cu")
		(net "R_MAC_UART_TX_FPGA_RX")
	)
	(segment
		(start 84.071968 -20.5105)
		(end 88.2015 -20.5105)
		(width 0.127)
		(layer "In2.Cu")
		(net "R_MAC_UART_TX_FPGA_RX")
	)
	(segment
		(start 135.509 -26.881328)
		(end 136.98982 -26.881328)
		(width 0.127)
		(layer "In2.Cu")
		(net "R_MAC_UART_TX_FPGA_RX")
	)
	(segment
		(start 132.334 -41.609518)
		(end 128.778 -45.165518)
		(width 0.127)
		(layer "In2.Cu")
		(net "R_MAC_UART_TX_FPGA_RX")
	)
	(segment
		(start 135.382 -26.754328)
		(end 135.509 -26.881328)
		(width 0.127)
		(layer "In2.Cu")
		(net "R_MAC_UART_TX_FPGA_RX")
	)
	(segment
		(start 135.509 -27.516328)
		(end 135.382 -27.643328)
		(width 0.127)
		(layer "In2.Cu")
		(net "R_MAC_UART_TX_FPGA_RX")
	)
	(segment
		(start 69.270118 -22.020022)
		(end 73.836022 -22.020022)
		(width 0.127)
		(layer "In2.Cu")
		(net "R_MAC_UART_TX_FPGA_RX")
	)
	(segment
		(start 135.382 -28.024328)
		(end 135.509 -28.151328)
		(width 0.127)
		(layer "In2.Cu")
		(net "R_MAC_UART_TX_FPGA_RX")
	)
	(segment
		(start 137.11682 -27.008328)
		(end 137.11682 -27.389328)
		(width 0.127)
		(layer "In2.Cu")
		(net "R_MAC_UART_TX_FPGA_RX")
	)
	(segment
		(start 135.382 -28.913328)
		(end 135.382 -29.21)
		(width 0.127)
		(layer "In2.Cu")
		(net "R_MAC_UART_TX_FPGA_RX")
	)
	(segment
		(start 136.98982 -26.881328)
		(end 137.11682 -27.008328)
		(width 0.127)
		(layer "In2.Cu")
		(net "R_MAC_UART_TX_FPGA_RX")
	)
	(segment
		(start 136.5631 -28.786328)
		(end 135.509 -28.786328)
		(width 0.127)
		(layer "In2.Cu")
		(net "R_MAC_UART_TX_FPGA_RX")
	)
	(segment
		(start 135.509 -28.786328)
		(end 135.382 -28.913328)
		(width 0.127)
		(layer "In2.Cu")
		(net "R_MAC_UART_TX_FPGA_RX")
	)
	(segment
		(start 73.836022 -22.020022)
		(end 76.44384 -24.62784)
		(width 0.127)
		(layer "In2.Cu")
		(net "R_MAC_UART_TX_FPGA_RX")
	)
	(segment
		(start 76.44384 -24.62784)
		(end 79.954628 -24.62784)
		(width 0.127)
		(layer "In2.Cu")
		(net "R_MAC_UART_TX_FPGA_RX")
	)
	(segment
		(start 135.509 -28.151328)
		(end 136.5631 -28.151328)
		(width 0.127)
		(layer "In2.Cu")
		(net "R_MAC_UART_TX_FPGA_RX")
	)
	(segment
		(start 88.2015 -20.5105)
		(end 88.646 -20.955)
		(width 0.127)
		(layer "In2.Cu")
		(net "R_MAC_UART_TX_FPGA_RX")
	)
	(segment
		(start 136.6901 -28.278328)
		(end 136.6901 -28.659328)
		(width 0.127)
		(layer "In2.Cu")
		(net "R_MAC_UART_TX_FPGA_RX")
	)
	(segment
		(start 136.98982 -27.516328)
		(end 135.509 -27.516328)
		(width 0.127)
		(layer "In2.Cu")
		(net "R_MAC_UART_TX_FPGA_RX")
	)
	(segment
		(start 130.79222 -56.888888)
		(end 130.79222 -57.277508)
		(width 0.11938)
		(layer "F.Cu")
		(net "R_MAC_UART_RX_FPGA_TX")
	)
	(segment
		(start 131.93268 -57.396888)
		(end 132.05206 -57.516268)
		(width 0.11938)
		(layer "F.Cu")
		(net "R_MAC_UART_RX_FPGA_TX")
	)
	(segment
		(start 128.524 -49.149)
		(end 128.778 -48.895)
		(width 0.11938)
		(layer "F.Cu")
		(net "R_MAC_UART_RX_FPGA_TX")
	)
	(segment
		(start 130.9116 -57.396888)
		(end 131.93268 -57.396888)
		(width 0.11938)
		(layer "F.Cu")
		(net "R_MAC_UART_RX_FPGA_TX")
	)
	(segment
		(start 130.9116 -56.769508)
		(end 130.79222 -56.888888)
		(width 0.11938)
		(layer "F.Cu")
		(net "R_MAC_UART_RX_FPGA_TX")
	)
	(segment
		(start 130.9116 -55.514748)
		(end 130.79222 -55.634128)
		(width 0.11938)
		(layer "F.Cu")
		(net "R_MAC_UART_RX_FPGA_TX")
	)
	(segment
		(start 132.05206 -50.43424)
		(end 132.05206 -55.395368)
		(width 0.11938)
		(layer "F.Cu")
		(net "R_MAC_UART_RX_FPGA_TX")
	)
	(segment
		(start 130.79222 -55.634128)
		(end 130.79222 -56.022748)
		(width 0.11938)
		(layer "F.Cu")
		(net "R_MAC_UART_RX_FPGA_TX")
	)
	(segment
		(start 132.05206 -55.395368)
		(end 131.93268 -55.514748)
		(width 0.11938)
		(layer "F.Cu")
		(net "R_MAC_UART_RX_FPGA_TX")
	)
	(segment
		(start 132.05206 -58.771028)
		(end 132.05206 -59.280806)
		(width 0.11938)
		(layer "F.Cu")
		(net "R_MAC_UART_RX_FPGA_TX")
	)
	(segment
		(start 132.05206 -57.516268)
		(end 132.05206 -57.904888)
		(width 0.11938)
		(layer "F.Cu")
		(net "R_MAC_UART_RX_FPGA_TX")
	)
	(segment
		(start 130.9116 -58.651648)
		(end 131.93268 -58.651648)
		(width 0.11938)
		(layer "F.Cu")
		(net "R_MAC_UART_RX_FPGA_TX")
	)
	(segment
		(start 152.721818 -63.948818)
		(end 153.416 -64.643)
		(width 0.11938)
		(layer "F.Cu")
		(net "R_MAC_UART_RX_FPGA_TX")
	)
	(segment
		(start 132.05206 -56.650128)
		(end 131.93268 -56.769508)
		(width 0.11938)
		(layer "F.Cu")
		(net "R_MAC_UART_RX_FPGA_TX")
	)
	(segment
		(start 128.524 -49.53)
		(end 128.524 -49.149)
		(width 0.11938)
		(layer "F.Cu")
		(net "R_MAC_UART_RX_FPGA_TX")
	)
	(segment
		(start 131.93268 -56.769508)
		(end 130.9116 -56.769508)
		(width 0.11938)
		(layer "F.Cu")
		(net "R_MAC_UART_RX_FPGA_TX")
	)
	(segment
		(start 126.619 -51.435)
		(end 128.524 -49.53)
		(width 0.11938)
		(layer "F.Cu")
		(net "R_MAC_UART_RX_FPGA_TX")
	)
	(segment
		(start 130.9116 -56.142128)
		(end 131.93268 -56.142128)
		(width 0.11938)
		(layer "F.Cu")
		(net "R_MAC_UART_RX_FPGA_TX")
	)
	(segment
		(start 131.93268 -58.651648)
		(end 132.05206 -58.771028)
		(width 0.11938)
		(layer "F.Cu")
		(net "R_MAC_UART_RX_FPGA_TX")
	)
	(segment
		(start 132.05206 -59.280806)
		(end 136.720072 -63.948818)
		(width 0.11938)
		(layer "F.Cu")
		(net "R_MAC_UART_RX_FPGA_TX")
	)
	(segment
		(start 130.79222 -58.532268)
		(end 130.9116 -58.651648)
		(width 0.11938)
		(layer "F.Cu")
		(net "R_MAC_UART_RX_FPGA_TX")
	)
	(segment
		(start 131.93268 -58.024268)
		(end 130.9116 -58.024268)
		(width 0.11938)
		(layer "F.Cu")
		(net "R_MAC_UART_RX_FPGA_TX")
	)
	(segment
		(start 130.79222 -58.143648)
		(end 130.79222 -58.532268)
		(width 0.11938)
		(layer "F.Cu")
		(net "R_MAC_UART_RX_FPGA_TX")
	)
	(segment
		(start 131.93268 -55.514748)
		(end 130.9116 -55.514748)
		(width 0.11938)
		(layer "F.Cu")
		(net "R_MAC_UART_RX_FPGA_TX")
	)
	(segment
		(start 130.9116 -58.024268)
		(end 130.79222 -58.143648)
		(width 0.11938)
		(layer "F.Cu")
		(net "R_MAC_UART_RX_FPGA_TX")
	)
	(segment
		(start 132.05206 -56.261508)
		(end 132.05206 -56.650128)
		(width 0.11938)
		(layer "F.Cu")
		(net "R_MAC_UART_RX_FPGA_TX")
	)
	(segment
		(start 130.79222 -57.277508)
		(end 130.9116 -57.396888)
		(width 0.11938)
		(layer "F.Cu")
		(net "R_MAC_UART_RX_FPGA_TX")
	)
	(segment
		(start 130.79222 -56.022748)
		(end 130.9116 -56.142128)
		(width 0.11938)
		(layer "F.Cu")
		(net "R_MAC_UART_RX_FPGA_TX")
	)
	(segment
		(start 132.05206 -57.904888)
		(end 131.93268 -58.024268)
		(width 0.11938)
		(layer "F.Cu")
		(net "R_MAC_UART_RX_FPGA_TX")
	)
	(segment
		(start 125.1204 -51.435)
		(end 126.619 -51.435)
		(width 0.11938)
		(layer "F.Cu")
		(net "R_MAC_UART_RX_FPGA_TX")
	)
	(segment
		(start 131.93268 -56.142128)
		(end 132.05206 -56.261508)
		(width 0.11938)
		(layer "F.Cu")
		(net "R_MAC_UART_RX_FPGA_TX")
	)
	(segment
		(start 130.51282 -48.895)
		(end 132.05206 -50.43424)
		(width 0.11938)
		(layer "F.Cu")
		(net "R_MAC_UART_RX_FPGA_TX")
	)
	(segment
		(start 128.778 -48.895)
		(end 130.51282 -48.895)
		(width 0.11938)
		(layer "F.Cu")
		(net "R_MAC_UART_RX_FPGA_TX")
	)
	(segment
		(start 136.720072 -63.948818)
		(end 152.721818 -63.948818)
		(width 0.11938)
		(layer "F.Cu")
		(net "R_MAC_UART_RX_FPGA_TX")
	)
	(via
		(at 153.416 -64.643)
		(size 0.508)
		(drill 0.254)
		(layers "F.Cu" "B.Cu")
		(net "R_MAC_UART_RX_FPGA_TX")
	)
	(via
		(at 135.382 -24.13)
		(size 0.4572)
		(drill 0.2032)
		(layers "F.Cu" "B.Cu")
		(net "R_MAC_UART_RX_FPGA_TX")
	)
	(via
		(at 89.916 -20.955)
		(size 0.508)
		(drill 0.254)
		(layers "F.Cu" "B.Cu")
		(net "R_MAC_UART_RX_FPGA_TX")
	)
	(via
		(at 128.778 -48.895)
		(size 0.508)
		(drill 0.254)
		(layers "F.Cu" "B.Cu")
		(net "R_MAC_UART_RX_FPGA_TX")
	)
	(segment
		(start 123.317 -16.002)
		(end 94.869 -16.002)
		(width 0.11938)
		(layer "B.Cu")
		(net "R_MAC_UART_RX_FPGA_TX")
	)
	(segment
		(start 153.3144 -64.8716)
		(end 153.3144 -66.421)
		(width 0.11938)
		(layer "B.Cu")
		(net "R_MAC_UART_RX_FPGA_TX")
	)
	(segment
		(start 94.869 -16.002)
		(end 89.916 -20.955)
		(width 0.11938)
		(layer "B.Cu")
		(net "R_MAC_UART_RX_FPGA_TX")
	)
	(segment
		(start 126.238 -51.435)
		(end 125.1204 -51.435)
		(width 0.11938)
		(layer "B.Cu")
		(net "R_MAC_UART_RX_FPGA_TX")
	)
	(segment
		(start 128.778 -48.895)
		(end 126.238 -51.435)
		(width 0.11938)
		(layer "B.Cu")
		(net "R_MAC_UART_RX_FPGA_TX")
	)
	(segment
		(start 130.302 -22.987)
		(end 123.317 -16.002)
		(width 0.11938)
		(layer "B.Cu")
		(net "R_MAC_UART_RX_FPGA_TX")
	)
	(segment
		(start 153.416 -64.643)
		(end 153.416 -64.77)
		(width 0.11938)
		(layer "B.Cu")
		(net "R_MAC_UART_RX_FPGA_TX")
	)
	(segment
		(start 135.382 -24.13)
		(end 134.239 -22.987)
		(width 0.11938)
		(layer "B.Cu")
		(net "R_MAC_UART_RX_FPGA_TX")
	)
	(segment
		(start 134.239 -22.987)
		(end 130.302 -22.987)
		(width 0.11938)
		(layer "B.Cu")
		(net "R_MAC_UART_RX_FPGA_TX")
	)
	(segment
		(start 153.416 -64.77)
		(end 153.3144 -64.8716)
		(width 0.11938)
		(layer "B.Cu")
		(net "R_MAC_UART_RX_FPGA_TX")
	)
	(segment
		(start 131.826 -41.398952)
		(end 128.2065 -45.018452)
		(width 0.127)
		(layer "In2.Cu")
		(net "R_MAC_UART_RX_FPGA_TX")
	)
	(segment
		(start 89.535 -20.955)
		(end 89.916 -20.955)
		(width 0.127)
		(layer "In2.Cu")
		(net "R_MAC_UART_RX_FPGA_TX")
	)
	(segment
		(start 135.382 -24.13)
		(end 134.8359 -24.6761)
		(width 0.127)
		(layer "In2.Cu")
		(net "R_MAC_UART_RX_FPGA_TX")
	)
	(segment
		(start 64.581278 -23.734522)
		(end 66.803778 -21.512022)
		(width 0.127)
		(layer "In2.Cu")
		(net "R_MAC_UART_RX_FPGA_TX")
	)
	(segment
		(start 64.507618 -23.734522)
		(end 64.581278 -23.734522)
		(width 0.127)
		(layer "In2.Cu")
		(net "R_MAC_UART_RX_FPGA_TX")
	)
	(segment
		(start 134.8359 -24.6761)
		(end 134.8359 -28.8671)
		(width 0.127)
		(layer "In2.Cu")
		(net "R_MAC_UART_RX_FPGA_TX")
	)
	(segment
		(start 128.2065 -48.3235)
		(end 128.778 -48.895)
		(width 0.127)
		(layer "In2.Cu")
		(net "R_MAC_UART_RX_FPGA_TX")
	)
	(segment
		(start 79.802482 -24.06142)
		(end 83.861402 -20.0025)
		(width 0.127)
		(layer "In2.Cu")
		(net "R_MAC_UART_RX_FPGA_TX")
	)
	(segment
		(start 88.5825 -20.0025)
		(end 89.535 -20.955)
		(width 0.127)
		(layer "In2.Cu")
		(net "R_MAC_UART_RX_FPGA_TX")
	)
	(segment
		(start 66.803778 -21.512022)
		(end 74.217022 -21.512022)
		(width 0.127)
		(layer "In2.Cu")
		(net "R_MAC_UART_RX_FPGA_TX")
	)
	(segment
		(start 83.861402 -20.0025)
		(end 88.5825 -20.0025)
		(width 0.127)
		(layer "In2.Cu")
		(net "R_MAC_UART_RX_FPGA_TX")
	)
	(segment
		(start 74.217022 -21.512022)
		(end 76.76642 -24.06142)
		(width 0.127)
		(layer "In2.Cu")
		(net "R_MAC_UART_RX_FPGA_TX")
	)
	(segment
		(start 128.2065 -45.018452)
		(end 128.2065 -48.3235)
		(width 0.127)
		(layer "In2.Cu")
		(net "R_MAC_UART_RX_FPGA_TX")
	)
	(segment
		(start 134.8359 -28.8671)
		(end 131.826 -31.877)
		(width 0.127)
		(layer "In2.Cu")
		(net "R_MAC_UART_RX_FPGA_TX")
	)
	(segment
		(start 76.76642 -24.06142)
		(end 79.802482 -24.06142)
		(width 0.127)
		(layer "In2.Cu")
		(net "R_MAC_UART_RX_FPGA_TX")
	)
	(segment
		(start 131.826 -31.877)
		(end 131.826 -41.398952)
		(width 0.127)
		(layer "In2.Cu")
		(net "R_MAC_UART_RX_FPGA_TX")
	)
	(segment
		(start 78.636368 -45.2374)
		(end 78.158594 -45.2374)
		(width 0.09906)
		(layer "F.Cu")
		(net "R_MAC_PPS_OUTP")
	)
	(segment
		(start 71.837042 -44.899072)
		(end 71.717916 -44.899072)
		(width 0.09906)
		(layer "F.Cu")
		(net "R_MAC_PPS_OUTP")
	)
	(segment
		(start 76.324968 -43.688)
		(end 73.33234 -43.688)
		(width 0.09906)
		(layer "F.Cu")
		(net "R_MAC_PPS_OUTP")
	)
	(segment
		(start 77.808074 -45.092366)
		(end 76.459842 -43.744134)
		(width 0.09906)
		(layer "F.Cu")
		(net "R_MAC_PPS_OUTP")
	)
	(segment
		(start 71.616824 -44.940982)
		(end 71.603108 -44.954698)
		(width 0.09906)
		(layer "F.Cu")
		(net "R_MAC_PPS_OUTP")
	)
	(segment
		(start 79.3242 -45.72)
		(end 78.986888 -45.382688)
		(width 0.09906)
		(layer "F.Cu")
		(net "R_MAC_PPS_OUTP")
	)
	(segment
		(start 71.502016 -44.996608)
		(end 70.354444 -44.996608)
		(width 0.09906)
		(layer "F.Cu")
		(net "R_MAC_PPS_OUTP")
	)
	(segment
		(start 73.197466 -43.744134)
		(end 72.187562 -44.754038)
		(width 0.09906)
		(layer "F.Cu")
		(net "R_MAC_PPS_OUTP")
	)
	(arc
		(start 71.717916 -44.899072)
		(mid 71.663192 -44.909957)
		(end 71.616824 -44.940982)
		(width 0.09906)
		(layer "F.Cu")
		(net "R_MAC_PPS_OUTP")
	)
	(arc
		(start 71.603108 -44.954698)
		(mid 71.556727 -44.985689)
		(end 71.502016 -44.996608)
		(width 0.09906)
		(layer "F.Cu")
		(net "R_MAC_PPS_OUTP")
	)
	(arc
		(start 78.158594 -45.2374)
		(mid 77.9689 -45.199761)
		(end 77.808074 -45.092366)
		(width 0.09906)
		(layer "F.Cu")
		(net "R_MAC_PPS_OUTP")
	)
	(arc
		(start 76.459842 -43.744134)
		(mid 76.398005 -43.702596)
		(end 76.324968 -43.688)
		(width 0.09906)
		(layer "F.Cu")
		(net "R_MAC_PPS_OUTP")
	)
	(arc
		(start 73.33234 -43.688)
		(mid 73.259327 -43.702653)
		(end 73.197466 -43.744134)
		(width 0.09906)
		(layer "F.Cu")
		(net "R_MAC_PPS_OUTP")
	)
	(arc
		(start 78.986888 -45.382688)
		(mid 78.826082 -45.275178)
		(end 78.636368 -45.2374)
		(width 0.09906)
		(layer "F.Cu")
		(net "R_MAC_PPS_OUTP")
	)
	(arc
		(start 72.187562 -44.754038)
		(mid 72.026727 -44.861411)
		(end 71.837042 -44.899072)
		(width 0.09906)
		(layer "F.Cu")
		(net "R_MAC_PPS_OUTP")
	)
	(segment
		(start 76.324968 -43.3832)
		(end 73.33234 -43.3832)
		(width 0.09906)
		(layer "F.Cu")
		(net "R_MAC_PPS_OUTN")
	)
	(segment
		(start 78.636368 -44.9326)
		(end 78.158594 -44.9326)
		(width 0.09906)
		(layer "F.Cu")
		(net "R_MAC_PPS_OUTN")
	)
	(segment
		(start 78.02372 -44.87672)
		(end 76.675488 -43.528488)
		(width 0.09906)
		(layer "F.Cu")
		(net "R_MAC_PPS_OUTN")
	)
	(segment
		(start 71.616824 -44.552362)
		(end 71.603108 -44.538646)
		(width 0.09906)
		(layer "F.Cu")
		(net "R_MAC_PPS_OUTN")
	)
	(segment
		(start 72.98182 -43.528488)
		(end 71.971916 -44.538392)
		(width 0.09906)
		(layer "F.Cu")
		(net "R_MAC_PPS_OUTN")
	)
	(segment
		(start 71.502016 -44.496736)
		(end 70.354444 -44.496736)
		(width 0.09906)
		(layer "F.Cu")
		(net "R_MAC_PPS_OUTN")
	)
	(segment
		(start 71.837042 -44.594272)
		(end 71.717916 -44.594272)
		(width 0.09906)
		(layer "F.Cu")
		(net "R_MAC_PPS_OUTN")
	)
	(segment
		(start 79.3242 -44.45)
		(end 78.986888 -44.787312)
		(width 0.09906)
		(layer "F.Cu")
		(net "R_MAC_PPS_OUTN")
	)
	(arc
		(start 71.717916 -44.594272)
		(mid 71.663192 -44.583387)
		(end 71.616824 -44.552362)
		(width 0.09906)
		(layer "F.Cu")
		(net "R_MAC_PPS_OUTN")
	)
	(arc
		(start 71.971916 -44.538392)
		(mid 71.910035 -44.579739)
		(end 71.837042 -44.594272)
		(width 0.09906)
		(layer "F.Cu")
		(net "R_MAC_PPS_OUTN")
	)
	(arc
		(start 78.158594 -44.9326)
		(mid 78.085596 -44.91808)
		(end 78.02372 -44.87672)
		(width 0.09906)
		(layer "F.Cu")
		(net "R_MAC_PPS_OUTN")
	)
	(arc
		(start 73.33234 -43.3832)
		(mid 73.142617 -43.420956)
		(end 72.98182 -43.528488)
		(width 0.09906)
		(layer "F.Cu")
		(net "R_MAC_PPS_OUTN")
	)
	(arc
		(start 71.603108 -44.538646)
		(mid 71.556727 -44.507655)
		(end 71.502016 -44.496736)
		(width 0.09906)
		(layer "F.Cu")
		(net "R_MAC_PPS_OUTN")
	)
	(arc
		(start 78.986888 -44.787312)
		(mid 78.826082 -44.894822)
		(end 78.636368 -44.9326)
		(width 0.09906)
		(layer "F.Cu")
		(net "R_MAC_PPS_OUTN")
	)
	(arc
		(start 76.675488 -43.528488)
		(mid 76.514682 -43.420978)
		(end 76.324968 -43.3832)
		(width 0.09906)
		(layer "F.Cu")
		(net "R_MAC_PPS_OUTN")
	)
	(segment
		(start 71.590154 -52.107846)
		(end 71.983854 -52.501292)
		(width 0.09906)
		(layer "F.Cu")
		(net "R_MAC_PPS_IN1P")
	)
	(segment
		(start 71.538338 -49.548542)
		(end 71.636382 -49.425606)
		(width 0.09906)
		(layer "F.Cu")
		(net "R_MAC_PPS_IN1P")
	)
	(segment
		(start 71.3994 -51.021742)
		(end 71.3994 -51.646582)
		(width 0.09906)
		(layer "F.Cu")
		(net "R_MAC_PPS_IN1P")
	)
	(segment
		(start 71.4502 -50.038)
		(end 71.450454 -49.799494)
		(width 0.09906)
		(layer "F.Cu")
		(net "R_MAC_PPS_IN1P")
	)
	(segment
		(start 80.112362 -53.239162)
		(end 80.4672 -53.594)
		(width 0.09906)
		(layer "F.Cu")
		(net "R_MAC_PPS_IN1P")
	)
	(segment
		(start 71.581772 -48.899064)
		(end 71.505572 -48.899064)
		(width 0.09906)
		(layer "F.Cu")
		(net "R_MAC_PPS_IN1P")
	)
	(segment
		(start 71.1708 -50.4698)
		(end 71.342504 -50.29835)
		(width 0.09906)
		(layer "F.Cu")
		(net "R_MAC_PPS_IN1P")
	)
	(segment
		(start 73.456546 -53.1114)
		(end 79.804006 -53.1114)
		(width 0.09906)
		(layer "F.Cu")
		(net "R_MAC_PPS_IN1P")
	)
	(segment
		(start 71.7296 -49.2252)
		(end 71.7296 -49.046892)
		(width 0.09906)
		(layer "F.Cu")
		(net "R_MAC_PPS_IN1P")
	)
	(segment
		(start 71.289672 -48.9966)
		(end 70.354444 -48.9966)
		(width 0.09906)
		(layer "F.Cu")
		(net "R_MAC_PPS_IN1P")
	)
	(segment
		(start 71.40448 -48.940974)
		(end 71.390764 -48.95469)
		(width 0.09906)
		(layer "F.Cu")
		(net "R_MAC_PPS_IN1P")
	)
	(via
		(at 71.1708 -50.4698)
		(size 0.4572)
		(drill 0.2032)
		(layers "F.Cu" "B.Cu")
		(net "R_MAC_PPS_IN1P")
	)
	(arc
		(start 71.3994 -51.646582)
		(mid 71.448881 -51.896192)
		(end 71.590154 -52.107846)
		(width 0.09906)
		(layer "F.Cu")
		(net "R_MAC_PPS_IN1P")
	)
	(arc
		(start 71.1708 -50.4698)
		(mid 71.340005 -50.723033)
		(end 71.3994 -51.021742)
		(width 0.09906)
		(layer "F.Cu")
		(net "R_MAC_PPS_IN1P")
	)
	(arc
		(start 71.390764 -48.95469)
		(mid 71.344383 -48.985681)
		(end 71.289672 -48.9966)
		(width 0.09906)
		(layer "F.Cu")
		(net "R_MAC_PPS_IN1P")
	)
	(arc
		(start 79.804006 -53.1114)
		(mid 79.970901 -53.144598)
		(end 80.112362 -53.239162)
		(width 0.09906)
		(layer "F.Cu")
		(net "R_MAC_PPS_IN1P")
	)
	(arc
		(start 71.342504 -50.29835)
		(mid 71.422235 -50.178885)
		(end 71.4502 -50.038)
		(width 0.09906)
		(layer "F.Cu")
		(net "R_MAC_PPS_IN1P")
	)
	(arc
		(start 71.983854 -52.501292)
		(mid 72.65953 -52.952794)
		(end 73.456546 -53.1114)
		(width 0.09906)
		(layer "F.Cu")
		(net "R_MAC_PPS_IN1P")
	)
	(arc
		(start 71.636382 -49.425606)
		(mid 71.706563 -49.336357)
		(end 71.7296 -49.2252)
		(width 0.09906)
		(layer "F.Cu")
		(net "R_MAC_PPS_IN1P")
	)
	(arc
		(start 71.505572 -48.899064)
		(mid 71.450848 -48.909949)
		(end 71.40448 -48.940974)
		(width 0.09906)
		(layer "F.Cu")
		(net "R_MAC_PPS_IN1P")
	)
	(arc
		(start 71.450454 -49.799494)
		(mid 71.473133 -49.666568)
		(end 71.538338 -49.548542)
		(width 0.09906)
		(layer "F.Cu")
		(net "R_MAC_PPS_IN1P")
	)
	(arc
		(start 71.7296 -49.046892)
		(mid 71.686302 -48.942362)
		(end 71.581772 -48.899064)
		(width 0.09906)
		(layer "F.Cu")
		(net "R_MAC_PPS_IN1P")
	)
	(segment
		(start 71.395844 -50.244756)
		(end 71.1708 -50.4698)
		(width 0.09906)
		(layer "B.Cu")
		(net "R_MAC_PPS_IN1P")
	)
	(segment
		(start 71.0311 -49.403)
		(end 71.344028 -49.715928)
		(width 0.09906)
		(layer "B.Cu")
		(net "R_MAC_PPS_IN1P")
	)
	(segment
		(start 71.4248 -49.911)
		(end 71.4248 -50.174652)
		(width 0.09906)
		(layer "B.Cu")
		(net "R_MAC_PPS_IN1P")
	)
	(arc
		(start 71.344028 -49.715928)
		(mid 71.40383 -49.805428)
		(end 71.4248 -49.911)
		(width 0.09906)
		(layer "B.Cu")
		(net "R_MAC_PPS_IN1P")
	)
	(arc
		(start 71.4248 -50.174652)
		(mid 71.417274 -50.212575)
		(end 71.395844 -50.244756)
		(width 0.09906)
		(layer "B.Cu")
		(net "R_MAC_PPS_IN1P")
	)
	(segment
		(start 71.776844 -49.738534)
		(end 71.85787 -49.637188)
		(width 0.09906)
		(layer "F.Cu")
		(net "R_MAC_PPS_IN1N")
	)
	(segment
		(start 72.034654 -49.2252)
		(end 72.0344 -49.2252)
		(width 0.09906)
		(layer "F.Cu")
		(net "R_MAC_PPS_IN1N")
	)
	(segment
		(start 71.755 -50.038254)
		(end 71.755254 -49.800002)
		(width 0.09906)
		(layer "F.Cu")
		(net "R_MAC_PPS_IN1N")
	)
	(segment
		(start 71.7042 -51.054)
		(end 71.7042 -51.646836)
		(width 0.09906)
		(layer "F.Cu")
		(net "R_MAC_PPS_IN1N")
	)
	(segment
		(start 72.0344 -49.2252)
		(end 72.0344 -49.046892)
		(width 0.09906)
		(layer "F.Cu")
		(net "R_MAC_PPS_IN1N")
	)
	(segment
		(start 71.581772 -48.594264)
		(end 71.4629 -48.594264)
		(width 0.09906)
		(layer "F.Cu")
		(net "R_MAC_PPS_IN1N")
	)
	(segment
		(start 71.8058 -51.8922)
		(end 72.1995 -52.285646)
		(width 0.09906)
		(layer "F.Cu")
		(net "R_MAC_PPS_IN1N")
	)
	(segment
		(start 80.112616 -52.678584)
		(end 80.4672 -52.324)
		(width 0.09906)
		(layer "F.Cu")
		(net "R_MAC_PPS_IN1N")
	)
	(segment
		(start 71.9836 -50.4698)
		(end 71.898764 -50.38471)
		(width 0.09906)
		(layer "F.Cu")
		(net "R_MAC_PPS_IN1N")
	)
	(segment
		(start 71.9836 -50.4698)
		(end 71.919846 -50.533808)
		(width 0.09906)
		(layer "F.Cu")
		(net "R_MAC_PPS_IN1N")
	)
	(segment
		(start 73.4568 -52.8066)
		(end 79.803752 -52.8066)
		(width 0.09906)
		(layer "F.Cu")
		(net "R_MAC_PPS_IN1N")
	)
	(segment
		(start 71.361808 -48.552354)
		(end 71.348092 -48.538638)
		(width 0.09906)
		(layer "F.Cu")
		(net "R_MAC_PPS_IN1N")
	)
	(segment
		(start 71.247 -48.496728)
		(end 70.354444 -48.496728)
		(width 0.09906)
		(layer "F.Cu")
		(net "R_MAC_PPS_IN1N")
	)
	(via
		(at 71.9836 -50.4698)
		(size 0.4572)
		(drill 0.2032)
		(layers "F.Cu" "B.Cu")
		(net "R_MAC_PPS_IN1N")
	)
	(arc
		(start 72.1995 -52.285646)
		(mid 72.776339 -52.671171)
		(end 73.4568 -52.8066)
		(width 0.09906)
		(layer "F.Cu")
		(net "R_MAC_PPS_IN1N")
	)
	(arc
		(start 71.898764 -50.38471)
		(mid 71.792441 -50.22577)
		(end 71.755 -50.038254)
		(width 0.09906)
		(layer "F.Cu")
		(net "R_MAC_PPS_IN1N")
	)
	(arc
		(start 71.7042 -51.646836)
		(mid 71.730611 -51.779613)
		(end 71.8058 -51.8922)
		(width 0.09906)
		(layer "F.Cu")
		(net "R_MAC_PPS_IN1N")
	)
	(arc
		(start 71.348092 -48.538638)
		(mid 71.301711 -48.507647)
		(end 71.247 -48.496728)
		(width 0.09906)
		(layer "F.Cu")
		(net "R_MAC_PPS_IN1N")
	)
	(arc
		(start 72.0344 -49.046892)
		(mid 71.901828 -48.726836)
		(end 71.581772 -48.594264)
		(width 0.09906)
		(layer "F.Cu")
		(net "R_MAC_PPS_IN1N")
	)
	(arc
		(start 71.755254 -49.800002)
		(mid 71.760847 -49.76744)
		(end 71.776844 -49.738534)
		(width 0.09906)
		(layer "F.Cu")
		(net "R_MAC_PPS_IN1N")
	)
	(arc
		(start 71.85787 -49.637188)
		(mid 71.98984 -49.449899)
		(end 72.034654 -49.2252)
		(width 0.09906)
		(layer "F.Cu")
		(net "R_MAC_PPS_IN1N")
	)
	(arc
		(start 71.919846 -50.533808)
		(mid 71.760291 -50.772459)
		(end 71.7042 -51.054)
		(width 0.09906)
		(layer "F.Cu")
		(net "R_MAC_PPS_IN1N")
	)
	(arc
		(start 79.803752 -52.8066)
		(mid 79.970925 -52.773329)
		(end 80.112616 -52.678584)
		(width 0.09906)
		(layer "F.Cu")
		(net "R_MAC_PPS_IN1N")
	)
	(arc
		(start 71.4629 -48.594264)
		(mid 71.408176 -48.583379)
		(end 71.361808 -48.552354)
		(width 0.09906)
		(layer "F.Cu")
		(net "R_MAC_PPS_IN1N")
	)
	(segment
		(start 72.0979 -49.403)
		(end 71.828406 -49.672494)
		(width 0.09906)
		(layer "B.Cu")
		(net "R_MAC_PPS_IN1N")
	)
	(segment
		(start 71.758556 -50.244756)
		(end 71.9836 -50.4698)
		(width 0.09906)
		(layer "B.Cu")
		(net "R_MAC_PPS_IN1N")
	)
	(segment
		(start 71.7296 -49.911)
		(end 71.7296 -50.174652)
		(width 0.09906)
		(layer "B.Cu")
		(net "R_MAC_PPS_IN1N")
	)
	(arc
		(start 71.7296 -50.174652)
		(mid 71.737126 -50.212575)
		(end 71.758556 -50.244756)
		(width 0.09906)
		(layer "B.Cu")
		(net "R_MAC_PPS_IN1N")
	)
	(arc
		(start 71.828406 -49.672494)
		(mid 71.755289 -49.781921)
		(end 71.7296 -49.911)
		(width 0.09906)
		(layer "B.Cu")
		(net "R_MAC_PPS_IN1N")
	)
	(segment
		(start 72.482964 -47.405036)
		(end 72.263 -47.625)
		(width 0.09906)
		(layer "F.Cu")
		(net "R_MAC_PPS_IN0P")
	)
	(segment
		(start 71.931784 -47.356014)
		(end 71.931784 -47.355252)
		(width 0.09906)
		(layer "F.Cu")
		(net "R_MAC_PPS_IN0P")
	)
	(segment
		(start 72.8218 -49.144682)
		(end 72.8218 -47.48784)
		(width 0.09906)
		(layer "F.Cu")
		(net "R_MAC_PPS_IN0P")
	)
	(segment
		(start 80.4672 -51.181)
		(end 80.112362 -50.826162)
		(width 0.09906)
		(layer "F.Cu")
		(net "R_MAC_PPS_IN0P")
	)
	(segment
		(start 72.263 -47.625)
		(end 72.027288 -47.389288)
		(width 0.09906)
		(layer "F.Cu")
		(net "R_MAC_PPS_IN0P")
	)
	(segment
		(start 71.932292 -47.356268)
		(end 71.932038 -47.356268)
		(width 0.09906)
		(layer "F.Cu")
		(net "R_MAC_PPS_IN0P")
	)
	(segment
		(start 79.804006 -50.6984)
		(end 74.24801 -50.6984)
		(width 0.09906)
		(layer "F.Cu")
		(net "R_MAC_PPS_IN0P")
	)
	(segment
		(start 71.67626 -47.728886)
		(end 71.650606 -47.75454)
		(width 0.09906)
		(layer "F.Cu")
		(net "R_MAC_PPS_IN0P")
	)
	(segment
		(start 71.932038 -47.356268)
		(end 71.931784 -47.356014)
		(width 0.09906)
		(layer "F.Cu")
		(net "R_MAC_PPS_IN0P")
	)
	(segment
		(start 71.20128 -47.940976)
		(end 71.187564 -47.954692)
		(width 0.09906)
		(layer "F.Cu")
		(net "R_MAC_PPS_IN0P")
	)
	(segment
		(start 71.086472 -47.996602)
		(end 70.354444 -47.996602)
		(width 0.09906)
		(layer "F.Cu")
		(net "R_MAC_PPS_IN0P")
	)
	(segment
		(start 72.70496 -47.371)
		(end 72.56526 -47.371)
		(width 0.09906)
		(layer "F.Cu")
		(net "R_MAC_PPS_IN0P")
	)
	(segment
		(start 73.6346 -50.4444)
		(end 73.165716 -49.975516)
		(width 0.09906)
		(layer "F.Cu")
		(net "R_MAC_PPS_IN0P")
	)
	(via
		(at 72.263 -47.625)
		(size 0.4572)
		(drill 0.2032)
		(layers "F.Cu" "B.Cu")
		(net "R_MAC_PPS_IN0P")
	)
	(arc
		(start 74.24801 -50.6984)
		(mid 73.916027 -50.63244)
		(end 73.6346 -50.4444)
		(width 0.09906)
		(layer "F.Cu")
		(net "R_MAC_PPS_IN0P")
	)
	(arc
		(start 71.853552 -47.425102)
		(mid 71.784531 -47.588443)
		(end 71.67626 -47.728886)
		(width 0.09906)
		(layer "F.Cu")
		(net "R_MAC_PPS_IN0P")
	)
	(arc
		(start 71.302626 -47.899066)
		(mid 71.24779 -47.909956)
		(end 71.20128 -47.940976)
		(width 0.09906)
		(layer "F.Cu")
		(net "R_MAC_PPS_IN0P")
	)
	(arc
		(start 72.8218 -47.48784)
		(mid 72.787578 -47.405222)
		(end 72.70496 -47.371)
		(width 0.09906)
		(layer "F.Cu")
		(net "R_MAC_PPS_IN0P")
	)
	(arc
		(start 72.027288 -47.389288)
		(mid 71.983589 -47.361836)
		(end 71.932292 -47.356268)
		(width 0.09906)
		(layer "F.Cu")
		(net "R_MAC_PPS_IN0P")
	)
	(arc
		(start 72.56526 -47.371)
		(mid 72.520727 -47.37984)
		(end 72.482964 -47.405036)
		(width 0.09906)
		(layer "F.Cu")
		(net "R_MAC_PPS_IN0P")
	)
	(arc
		(start 80.112362 -50.826162)
		(mid 79.970887 -50.731631)
		(end 79.804006 -50.6984)
		(width 0.09906)
		(layer "F.Cu")
		(net "R_MAC_PPS_IN0P")
	)
	(arc
		(start 71.931784 -47.355252)
		(mid 71.882646 -47.378956)
		(end 71.853552 -47.425102)
		(width 0.09906)
		(layer "F.Cu")
		(net "R_MAC_PPS_IN0P")
	)
	(arc
		(start 71.650606 -47.75454)
		(mid 71.49094 -47.861281)
		(end 71.302626 -47.899066)
		(width 0.09906)
		(layer "F.Cu")
		(net "R_MAC_PPS_IN0P")
	)
	(arc
		(start 73.165716 -49.975516)
		(mid 72.91115 -49.594297)
		(end 72.8218 -49.144682)
		(width 0.09906)
		(layer "F.Cu")
		(net "R_MAC_PPS_IN0P")
	)
	(arc
		(start 71.187564 -47.954692)
		(mid 71.141183 -47.985683)
		(end 71.086472 -47.996602)
		(width 0.09906)
		(layer "F.Cu")
		(net "R_MAC_PPS_IN0P")
	)
	(segment
		(start 71.967852 -47.371)
		(end 71.501 -47.371)
		(width 0.09906)
		(layer "B.Cu")
		(net "R_MAC_PPS_IN0P")
	)
	(segment
		(start 71.284084 -47.460916)
		(end 70.993 -47.752)
		(width 0.09906)
		(layer "B.Cu")
		(net "R_MAC_PPS_IN0P")
	)
	(segment
		(start 72.263 -47.625)
		(end 72.037956 -47.399956)
		(width 0.09906)
		(layer "B.Cu")
		(net "R_MAC_PPS_IN0P")
	)
	(arc
		(start 72.037956 -47.399956)
		(mid 72.005778 -47.378518)
		(end 71.967852 -47.371)
		(width 0.09906)
		(layer "B.Cu")
		(net "R_MAC_PPS_IN0P")
	)
	(arc
		(start 71.501 -47.371)
		(mid 71.383595 -47.394371)
		(end 71.284084 -47.460916)
		(width 0.09906)
		(layer "B.Cu")
		(net "R_MAC_PPS_IN0P")
	)
	(segment
		(start 80.4672 -49.911)
		(end 80.112616 -50.265584)
		(width 0.09906)
		(layer "F.Cu")
		(net "R_MAC_PPS_IN0N")
	)
	(segment
		(start 71.0692 -47.49673)
		(end 70.354444 -47.49673)
		(width 0.09906)
		(layer "F.Cu")
		(net "R_MAC_PPS_IN0N")
	)
	(segment
		(start 73.1266 -49.144682)
		(end 73.1266 -47.48784)
		(width 0.09906)
		(layer "F.Cu")
		(net "R_MAC_PPS_IN0N")
	)
	(segment
		(start 71.460614 -47.51324)
		(end 71.43496 -47.538894)
		(width 0.09906)
		(layer "F.Cu")
		(net "R_MAC_PPS_IN0N")
	)
	(segment
		(start 73.850246 -50.228754)
		(end 73.381362 -49.75987)
		(width 0.09906)
		(layer "F.Cu")
		(net "R_MAC_PPS_IN0N")
	)
	(segment
		(start 71.301102 -47.594266)
		(end 71.26859 -47.594266)
		(width 0.09906)
		(layer "F.Cu")
		(net "R_MAC_PPS_IN0N")
	)
	(segment
		(start 72.48779 -47.03699)
		(end 72.263 -46.8122)
		(width 0.09906)
		(layer "F.Cu")
		(net "R_MAC_PPS_IN0N")
	)
	(segment
		(start 71.195692 -47.56404)
		(end 71.170546 -47.538894)
		(width 0.09906)
		(layer "F.Cu")
		(net "R_MAC_PPS_IN0N")
	)
	(segment
		(start 72.263 -46.8122)
		(end 72.14108 -46.93412)
		(width 0.09906)
		(layer "F.Cu")
		(net "R_MAC_PPS_IN0N")
	)
	(segment
		(start 72.70496 -47.0662)
		(end 72.558148 -47.0662)
		(width 0.09906)
		(layer "F.Cu")
		(net "R_MAC_PPS_IN0N")
	)
	(segment
		(start 79.803752 -50.3936)
		(end 74.24801 -50.3936)
		(width 0.09906)
		(layer "F.Cu")
		(net "R_MAC_PPS_IN0N")
	)
	(via
		(at 72.263 -46.8122)
		(size 0.4572)
		(drill 0.2032)
		(layers "F.Cu" "B.Cu")
		(net "R_MAC_PPS_IN0N")
	)
	(arc
		(start 73.1266 -47.48784)
		(mid 73.003105 -47.189695)
		(end 72.70496 -47.0662)
		(width 0.09906)
		(layer "F.Cu")
		(net "R_MAC_PPS_IN0N")
	)
	(arc
		(start 71.26859 -47.594266)
		(mid 71.229126 -47.586416)
		(end 71.195692 -47.56404)
		(width 0.09906)
		(layer "F.Cu")
		(net "R_MAC_PPS_IN0N")
	)
	(arc
		(start 80.112616 -50.265584)
		(mid 79.970922 -50.360324)
		(end 79.803752 -50.3936)
		(width 0.09906)
		(layer "F.Cu")
		(net "R_MAC_PPS_IN0N")
	)
	(arc
		(start 71.170546 -47.538894)
		(mid 71.124077 -47.507688)
		(end 71.0692 -47.49673)
		(width 0.09906)
		(layer "F.Cu")
		(net "R_MAC_PPS_IN0N")
	)
	(arc
		(start 74.24801 -50.3936)
		(mid 74.032723 -50.350759)
		(end 73.850246 -50.228754)
		(width 0.09906)
		(layer "F.Cu")
		(net "R_MAC_PPS_IN0N")
	)
	(arc
		(start 71.89978 -47.051722)
		(mid 71.6859 -47.145789)
		(end 71.559928 -47.342552)
		(width 0.09906)
		(layer "F.Cu")
		(net "R_MAC_PPS_IN0N")
	)
	(arc
		(start 73.381362 -49.75987)
		(mid 73.192822 -49.477605)
		(end 73.1266 -49.144682)
		(width 0.09906)
		(layer "F.Cu")
		(net "R_MAC_PPS_IN0N")
	)
	(arc
		(start 72.14108 -46.93412)
		(mid 72.030277 -47.013115)
		(end 71.89978 -47.051722)
		(width 0.09906)
		(layer "F.Cu")
		(net "R_MAC_PPS_IN0N")
	)
	(arc
		(start 71.559928 -47.342552)
		(mid 71.521348 -47.43434)
		(end 71.460614 -47.51324)
		(width 0.09906)
		(layer "F.Cu")
		(net "R_MAC_PPS_IN0N")
	)
	(arc
		(start 71.43496 -47.538894)
		(mid 71.373545 -47.579901)
		(end 71.301102 -47.594266)
		(width 0.09906)
		(layer "F.Cu")
		(net "R_MAC_PPS_IN0N")
	)
	(arc
		(start 72.558148 -47.0662)
		(mid 72.520059 -47.058606)
		(end 72.48779 -47.03699)
		(width 0.09906)
		(layer "F.Cu")
		(net "R_MAC_PPS_IN0N")
	)
	(segment
		(start 72.263 -46.8122)
		(end 72.037956 -47.037244)
		(width 0.09906)
		(layer "B.Cu")
		(net "R_MAC_PPS_IN0N")
	)
	(segment
		(start 71.967852 -47.0662)
		(end 71.501 -47.0662)
		(width 0.09906)
		(layer "B.Cu")
		(net "R_MAC_PPS_IN0N")
	)
	(segment
		(start 71.284084 -46.976284)
		(end 70.993 -46.6852)
		(width 0.09906)
		(layer "B.Cu")
		(net "R_MAC_PPS_IN0N")
	)
	(arc
		(start 71.501 -47.0662)
		(mid 71.383595 -47.042829)
		(end 71.284084 -46.976284)
		(width 0.09906)
		(layer "B.Cu")
		(net "R_MAC_PPS_IN0N")
	)
	(arc
		(start 72.037956 -47.037244)
		(mid 72.005778 -47.058682)
		(end 71.967852 -47.0662)
		(width 0.09906)
		(layer "B.Cu")
		(net "R_MAC_PPS_IN0N")
	)
	(segment
		(start 126.238 -39.116)
		(end 126.238 -40.2844)
		(width 0.11938)
		(layer "F.Cu")
		(net "R_MAC_BITEOUT")
	)
	(segment
		(start 126.238 -40.2844)
		(end 125.1204 -41.402)
		(width 0.11938)
		(layer "F.Cu")
		(net "R_MAC_BITEOUT")
	)
	(segment
		(start 114.554 -19.812)
		(end 114.554 -21.971)
		(width 0.127)
		(layer "In2.Cu")
		(net "R_MAC_BITEOUT")
	)
	(segment
		(start 126.8857 -32.370522)
		(end 127.28448 -32.769302)
		(width 0.127)
		(layer "In2.Cu")
		(net "R_MAC_BITEOUT")
	)
	(segment
		(start 106.9848 -19.1008)
		(end 108.1532 -19.1008)
		(width 0.127)
		(layer "In2.Cu")
		(net "R_MAC_BITEOUT")
	)
	(segment
		(start 126.238 -29.555186)
		(end 126.8857 -30.202886)
		(width 0.127)
		(layer "In2.Cu")
		(net "R_MAC_BITEOUT")
	)
	(segment
		(start 79.901034 -25.4)
		(end 84.282534 -21.0185)
		(width 0.127)
		(layer "In2.Cu")
		(net "R_MAC_BITEOUT")
	)
	(segment
		(start 93.8149 -20.066)
		(end 96.012 -17.8689)
		(width 0.127)
		(layer "In2.Cu")
		(net "R_MAC_BITEOUT")
	)
	(segment
		(start 105.36936 -18.415)
		(end 106.299 -18.415)
		(width 0.127)
		(layer "In2.Cu")
		(net "R_MAC_BITEOUT")
	)
	(segment
		(start 127.13208 -38.22192)
		(end 126.238 -39.116)
		(width 0.127)
		(layer "In2.Cu")
		(net "R_MAC_BITEOUT")
	)
	(segment
		(start 127.28448 -36.247832)
		(end 127.13208 -36.400232)
		(width 0.127)
		(layer "In2.Cu")
		(net "R_MAC_BITEOUT")
	)
	(segment
		(start 108.71454 -18.53946)
		(end 113.28146 -18.53946)
		(width 0.127)
		(layer "In2.Cu")
		(net "R_MAC_BITEOUT")
	)
	(segment
		(start 104.82326 -17.8689)
		(end 105.36936 -18.415)
		(width 0.127)
		(layer "In2.Cu")
		(net "R_MAC_BITEOUT")
	)
	(segment
		(start 88.057482 -21.59)
		(end 90.297 -21.59)
		(width 0.127)
		(layer "In2.Cu")
		(net "R_MAC_BITEOUT")
	)
	(segment
		(start 123.763532 -25.2857)
		(end 126.238 -27.760168)
		(width 0.127)
		(layer "In2.Cu")
		(net "R_MAC_BITEOUT")
	)
	(segment
		(start 127.13208 -36.400232)
		(end 127.13208 -38.22192)
		(width 0.127)
		(layer "In2.Cu")
		(net "R_MAC_BITEOUT")
	)
	(segment
		(start 127.28448 -32.769302)
		(end 127.28448 -36.247832)
		(width 0.127)
		(layer "In2.Cu")
		(net "R_MAC_BITEOUT")
	)
	(segment
		(start 119.126 -24.003)
		(end 120.4087 -25.2857)
		(width 0.127)
		(layer "In2.Cu")
		(net "R_MAC_BITEOUT")
	)
	(segment
		(start 70.578218 -23.734522)
		(end 74.280522 -23.734522)
		(width 0.127)
		(layer "In2.Cu")
		(net "R_MAC_BITEOUT")
	)
	(segment
		(start 126.238 -27.760168)
		(end 126.238 -29.555186)
		(width 0.127)
		(layer "In2.Cu")
		(net "R_MAC_BITEOUT")
	)
	(segment
		(start 75.946 -25.4)
		(end 79.901034 -25.4)
		(width 0.127)
		(layer "In2.Cu")
		(net "R_MAC_BITEOUT")
	)
	(segment
		(start 120.4087 -25.2857)
		(end 123.763532 -25.2857)
		(width 0.127)
		(layer "In2.Cu")
		(net "R_MAC_BITEOUT")
	)
	(segment
		(start 113.28146 -18.53946)
		(end 114.554 -19.812)
		(width 0.127)
		(layer "In2.Cu")
		(net "R_MAC_BITEOUT")
	)
	(segment
		(start 84.282534 -21.0185)
		(end 87.485982 -21.0185)
		(width 0.127)
		(layer "In2.Cu")
		(net "R_MAC_BITEOUT")
	)
	(segment
		(start 96.012 -17.8689)
		(end 104.82326 -17.8689)
		(width 0.127)
		(layer "In2.Cu")
		(net "R_MAC_BITEOUT")
	)
	(segment
		(start 91.821 -20.066)
		(end 93.8149 -20.066)
		(width 0.127)
		(layer "In2.Cu")
		(net "R_MAC_BITEOUT")
	)
	(segment
		(start 87.485982 -21.0185)
		(end 88.057482 -21.59)
		(width 0.127)
		(layer "In2.Cu")
		(net "R_MAC_BITEOUT")
	)
	(segment
		(start 126.8857 -30.202886)
		(end 126.8857 -32.370522)
		(width 0.127)
		(layer "In2.Cu")
		(net "R_MAC_BITEOUT")
	)
	(segment
		(start 106.299 -18.415)
		(end 106.9848 -19.1008)
		(width 0.127)
		(layer "In2.Cu")
		(net "R_MAC_BITEOUT")
	)
	(segment
		(start 74.280522 -23.734522)
		(end 75.946 -25.4)
		(width 0.127)
		(layer "In2.Cu")
		(net "R_MAC_BITEOUT")
	)
	(segment
		(start 116.586 -24.003)
		(end 119.126 -24.003)
		(width 0.127)
		(layer "In2.Cu")
		(net "R_MAC_BITEOUT")
	)
	(segment
		(start 108.1532 -19.1008)
		(end 108.71454 -18.53946)
		(width 0.127)
		(layer "In2.Cu")
		(net "R_MAC_BITEOUT")
	)
	(segment
		(start 114.554 -21.971)
		(end 116.586 -24.003)
		(width 0.127)
		(layer "In2.Cu")
		(net "R_MAC_BITEOUT")
	)
	(segment
		(start 90.297 -21.59)
		(end 91.821 -20.066)
		(width 0.127)
		(layer "In2.Cu")
		(net "R_MAC_BITEOUT")
	)
	(via
		(at 126.50724 -47.117)
		(size 0.508)
		(drill 0.254)
		(layers "F.Cu" "B.Cu")
		(net "R_MAC_10MHZ_RF_OUT")
	)
	(segment
		(start 125.1204 -47.117)
		(end 126.50724 -47.117)
		(width 0.11938)
		(layer "B.Cu")
		(net "R_MAC_10MHZ_RF_OUT")
	)
	(segment
		(start 126.5555 -45.23232)
		(end 126.5555 -47.06874)
		(width 0.127)
		(layer "In2.Cu")
		(net "R_MAC_10MHZ_RF_OUT")
	)
	(segment
		(start 130.683 -31.30804)
		(end 130.683 -35.767518)
		(width 0.127)
		(layer "In2.Cu")
		(net "R_MAC_10MHZ_RF_OUT")
	)
	(segment
		(start 129.921 -23.749)
		(end 131.445 -25.273)
		(width 0.127)
		(layer "In2.Cu")
		(net "R_MAC_10MHZ_RF_OUT")
	)
	(segment
		(start 82.115406 -16.9545)
		(end 92.615004 -16.9545)
		(width 0.127)
		(layer "In2.Cu")
		(net "R_MAC_10MHZ_RF_OUT")
	)
	(segment
		(start 126.5555 -47.06874)
		(end 126.50724 -47.117)
		(width 0.127)
		(layer "In2.Cu")
		(net "R_MAC_10MHZ_RF_OUT")
	)
	(segment
		(start 130.683 -35.767518)
		(end 130.1115 -36.339018)
		(width 0.127)
		(layer "In2.Cu")
		(net "R_MAC_10MHZ_RF_OUT")
	)
	(segment
		(start 63.964566 -16.891)
		(end 73.66 -16.891)
		(width 0.127)
		(layer "In2.Cu")
		(net "R_MAC_10MHZ_RF_OUT")
	)
	(segment
		(start 131.445 -25.273)
		(end 131.445 -30.54604)
		(width 0.127)
		(layer "In2.Cu")
		(net "R_MAC_10MHZ_RF_OUT")
	)
	(segment
		(start 131.445 -30.54604)
		(end 130.683 -31.30804)
		(width 0.127)
		(layer "In2.Cu")
		(net "R_MAC_10MHZ_RF_OUT")
	)
	(segment
		(start 47.244 -20.734274)
		(end 47.244 -19.558)
		(width 0.127)
		(layer "In2.Cu")
		(net "R_MAC_10MHZ_RF_OUT")
	)
	(segment
		(start 129.921 -22.311868)
		(end 129.921 -23.749)
		(width 0.127)
		(layer "In2.Cu")
		(net "R_MAC_10MHZ_RF_OUT")
	)
	(segment
		(start 122.430032 -14.8209)
		(end 129.921 -22.311868)
		(width 0.127)
		(layer "In2.Cu")
		(net "R_MAC_10MHZ_RF_OUT")
	)
	(segment
		(start 32.021018 -26.426922)
		(end 36.50996 -21.93798)
		(width 0.127)
		(layer "In2.Cu")
		(net "R_MAC_10MHZ_RF_OUT")
	)
	(segment
		(start 94.748604 -14.8209)
		(end 122.430032 -14.8209)
		(width 0.127)
		(layer "In2.Cu")
		(net "R_MAC_10MHZ_RF_OUT")
	)
	(segment
		(start 82.026506 -17.0434)
		(end 82.115406 -16.9545)
		(width 0.127)
		(layer "In2.Cu")
		(net "R_MAC_10MHZ_RF_OUT")
	)
	(segment
		(start 130.1115 -41.67632)
		(end 126.5555 -45.23232)
		(width 0.127)
		(layer "In2.Cu")
		(net "R_MAC_10MHZ_RF_OUT")
	)
	(segment
		(start 92.615004 -16.9545)
		(end 94.748604 -14.8209)
		(width 0.127)
		(layer "In2.Cu")
		(net "R_MAC_10MHZ_RF_OUT")
	)
	(segment
		(start 73.66 -16.891)
		(end 73.8124 -17.0434)
		(width 0.127)
		(layer "In2.Cu")
		(net "R_MAC_10MHZ_RF_OUT")
	)
	(segment
		(start 58.039 -15.367)
		(end 62.440566 -15.367)
		(width 0.127)
		(layer "In2.Cu")
		(net "R_MAC_10MHZ_RF_OUT")
	)
	(segment
		(start 130.1115 -36.339018)
		(end 130.1115 -41.67632)
		(width 0.127)
		(layer "In2.Cu")
		(net "R_MAC_10MHZ_RF_OUT")
	)
	(segment
		(start 73.8124 -17.0434)
		(end 82.026506 -17.0434)
		(width 0.127)
		(layer "In2.Cu")
		(net "R_MAC_10MHZ_RF_OUT")
	)
	(segment
		(start 47.244 -19.558)
		(end 48.9458 -17.8562)
		(width 0.127)
		(layer "In2.Cu")
		(net "R_MAC_10MHZ_RF_OUT")
	)
	(segment
		(start 52.21986 -17.8562)
		(end 54.05628 -16.01978)
		(width 0.127)
		(layer "In2.Cu")
		(net "R_MAC_10MHZ_RF_OUT")
	)
	(segment
		(start 46.040294 -21.93798)
		(end 47.244 -20.734274)
		(width 0.127)
		(layer "In2.Cu")
		(net "R_MAC_10MHZ_RF_OUT")
	)
	(segment
		(start 57.38622 -16.01978)
		(end 58.039 -15.367)
		(width 0.127)
		(layer "In2.Cu")
		(net "R_MAC_10MHZ_RF_OUT")
	)
	(segment
		(start 48.9458 -17.8562)
		(end 52.21986 -17.8562)
		(width 0.127)
		(layer "In2.Cu")
		(net "R_MAC_10MHZ_RF_OUT")
	)
	(segment
		(start 62.440566 -15.367)
		(end 63.964566 -16.891)
		(width 0.127)
		(layer "In2.Cu")
		(net "R_MAC_10MHZ_RF_OUT")
	)
	(segment
		(start 36.50996 -21.93798)
		(end 46.040294 -21.93798)
		(width 0.127)
		(layer "In2.Cu")
		(net "R_MAC_10MHZ_RF_OUT")
	)
	(segment
		(start 54.05628 -16.01978)
		(end 57.38622 -16.01978)
		(width 0.127)
		(layer "In2.Cu")
		(net "R_MAC_10MHZ_RF_OUT")
	)
	(segment
		(start 18.5674 -67.2084)
		(end 18.9484 -67.5894)
		(width 0.11938)
		(layer "F.Cu")
		(net "R_ICP10100_I2C_SDA")
	)
	(segment
		(start 18.9484 -67.5894)
		(end 19.277838 -67.5894)
		(width 0.11938)
		(layer "F.Cu")
		(net "R_ICP10100_I2C_SDA")
	)
	(segment
		(start 17.9324 -67.6656)
		(end 18.3896 -67.2084)
		(width 0.11938)
		(layer "F.Cu")
		(net "R_ICP10100_I2C_SDA")
	)
	(segment
		(start 17.385792 -67.6656)
		(end 17.9324 -67.6656)
		(width 0.11938)
		(layer "F.Cu")
		(net "R_ICP10100_I2C_SDA")
	)
	(segment
		(start 18.3896 -67.2084)
		(end 18.5674 -67.2084)
		(width 0.11938)
		(layer "F.Cu")
		(net "R_ICP10100_I2C_SDA")
	)
	(via
		(at 18.3896 -67.2084)
		(size 0.508)
		(drill 0.254)
		(layers "F.Cu" "B.Cu")
		(net "R_ICP10100_I2C_SDA")
	)
	(segment
		(start 18.1356 -70.3834)
		(end 18.8468 -69.6722)
		(width 0.11938)
		(layer "F.Cu")
		(net "R_ICP10100_I2C_SCL")
	)
	(segment
		(start 19.2532 -69.6722)
		(end 19.2532 -69.4436)
		(width 0.11938)
		(layer "F.Cu")
		(net "R_ICP10100_I2C_SCL")
	)
	(segment
		(start 18.8468 -69.6722)
		(end 19.2532 -69.6722)
		(width 0.11938)
		(layer "F.Cu")
		(net "R_ICP10100_I2C_SCL")
	)
	(segment
		(start 19.802856 -68.893944)
		(end 19.802856 -68.364354)
		(width 0.11938)
		(layer "F.Cu")
		(net "R_ICP10100_I2C_SCL")
	)
	(segment
		(start 18.1356 -70.866)
		(end 18.1356 -70.3834)
		(width 0.11938)
		(layer "F.Cu")
		(net "R_ICP10100_I2C_SCL")
	)
	(segment
		(start 19.2532 -69.4436)
		(end 19.802856 -68.893944)
		(width 0.11938)
		(layer "F.Cu")
		(net "R_ICP10100_I2C_SCL")
	)
	(via
		(at 19.2532 -69.6722)
		(size 0.4572)
		(drill 0.2032)
		(layers "F.Cu" "B.Cu")
		(net "R_ICP10100_I2C_SCL")
	)
	(segment
		(start 81.915 -58.928)
		(end 81.3816 -58.3946)
		(width 0.11938)
		(layer "F.Cu")
		(net "R_BNO080_RST_N")
	)
	(segment
		(start 81.3816 -58.3946)
		(end 81.3054 -58.3946)
		(width 0.11938)
		(layer "F.Cu")
		(net "R_BNO080_RST_N")
	)
	(segment
		(start 81.3054 -60.6806)
		(end 81.3054 -59.5376)
		(width 0.11938)
		(layer "F.Cu")
		(net "R_BNO080_RST_N")
	)
	(segment
		(start 84.543392 -58.525664)
		(end 83.587336 -58.525664)
		(width 0.11938)
		(layer "F.Cu")
		(net "R_BNO080_RST_N")
	)
	(segment
		(start 83.185 -58.928)
		(end 81.915 -58.928)
		(width 0.11938)
		(layer "F.Cu")
		(net "R_BNO080_RST_N")
	)
	(segment
		(start 81.3054 -58.3946)
		(end 81.3054 -59.5376)
		(width 0.11938)
		(layer "F.Cu")
		(net "R_BNO080_RST_N")
	)
	(segment
		(start 83.587336 -58.525664)
		(end 83.185 -58.928)
		(width 0.11938)
		(layer "F.Cu")
		(net "R_BNO080_RST_N")
	)
	(via
		(at 83.185 -58.928)
		(size 0.4572)
		(drill 0.2032)
		(layers "F.Cu" "B.Cu")
		(net "R_BNO080_RST_N")
	)
	(segment
		(start 82.9183 -64.920114)
		(end 82.169 -65.669414)
		(width 0.127)
		(layer "In2.Cu")
		(net "R_BNO080_RST_N")
	)
	(segment
		(start 82.677 -60.452)
		(end 82.677 -64.226186)
		(width 0.127)
		(layer "In2.Cu")
		(net "R_BNO080_RST_N")
	)
	(segment
		(start 82.677 -64.226186)
		(end 82.9183 -64.467486)
		(width 0.127)
		(layer "In2.Cu")
		(net "R_BNO080_RST_N")
	)
	(segment
		(start 82.169 -65.669414)
		(end 82.169 -66.802)
		(width 0.127)
		(layer "In2.Cu")
		(net "R_BNO080_RST_N")
	)
	(segment
		(start 83.185 -58.928)
		(end 83.185 -59.944)
		(width 0.127)
		(layer "In2.Cu")
		(net "R_BNO080_RST_N")
	)
	(segment
		(start 83.185 -59.944)
		(end 82.677 -60.452)
		(width 0.127)
		(layer "In2.Cu")
		(net "R_BNO080_RST_N")
	)
	(segment
		(start 82.9183 -64.467486)
		(end 82.9183 -64.920114)
		(width 0.127)
		(layer "In2.Cu")
		(net "R_BNO080_RST_N")
	)
	(segment
		(start 82.677 -57.785)
		(end 83.43646 -57.02554)
		(width 0.11938)
		(layer "F.Cu")
		(net "R_BNO080_INT_N")
	)
	(segment
		(start 82.296 -57.785)
		(end 82.677 -57.785)
		(width 0.11938)
		(layer "F.Cu")
		(net "R_BNO080_INT_N")
	)
	(segment
		(start 81.3054 -57.2516)
		(end 81.8388 -57.785)
		(width 0.11938)
		(layer "F.Cu")
		(net "R_BNO080_INT_N")
	)
	(segment
		(start 81.8388 -57.785)
		(end 82.296 -57.785)
		(width 0.11938)
		(layer "F.Cu")
		(net "R_BNO080_INT_N")
	)
	(segment
		(start 83.43646 -57.02554)
		(end 84.543392 -57.02554)
		(width 0.11938)
		(layer "F.Cu")
		(net "R_BNO080_INT_N")
	)
	(via
		(at 82.296 -57.785)
		(size 0.508)
		(drill 0.254)
		(layers "F.Cu" "B.Cu")
		(net "R_BNO080_INT_N")
	)
	(segment
		(start 84.074 -66.167)
		(end 83.947 -66.294)
		(width 0.127)
		(layer "In2.Cu")
		(net "R_BNO080_INT_N")
	)
	(segment
		(start 83.185 -57.785)
		(end 84.074 -58.674)
		(width 0.127)
		(layer "In2.Cu")
		(net "R_BNO080_INT_N")
	)
	(segment
		(start 82.296 -57.785)
		(end 83.185 -57.785)
		(width 0.127)
		(layer "In2.Cu")
		(net "R_BNO080_INT_N")
	)
	(segment
		(start 83.82 -64.897)
		(end 84.074 -65.151)
		(width 0.127)
		(layer "In2.Cu")
		(net "R_BNO080_INT_N")
	)
	(segment
		(start 84.074 -61.595)
		(end 83.82 -61.849)
		(width 0.127)
		(layer "In2.Cu")
		(net "R_BNO080_INT_N")
	)
	(segment
		(start 83.82 -61.849)
		(end 83.82 -64.897)
		(width 0.127)
		(layer "In2.Cu")
		(net "R_BNO080_INT_N")
	)
	(segment
		(start 84.074 -65.151)
		(end 84.074 -66.167)
		(width 0.127)
		(layer "In2.Cu")
		(net "R_BNO080_INT_N")
	)
	(segment
		(start 83.947 -66.294)
		(end 83.947 -67.31)
		(width 0.127)
		(layer "In2.Cu")
		(net "R_BNO080_INT_N")
	)
	(segment
		(start 84.074 -58.674)
		(end 84.074 -61.595)
		(width 0.127)
		(layer "In2.Cu")
		(net "R_BNO080_INT_N")
	)
	(segment
		(start 84.709 -63.2714)
		(end 84.4804 -63.0428)
		(width 0.11938)
		(layer "F.Cu")
		(net "R_BNO080_BOOT_N")
	)
	(segment
		(start 84.4804 -63.0428)
		(end 84.4804 -62.6364)
		(width 0.11938)
		(layer "F.Cu")
		(net "R_BNO080_BOOT_N")
	)
	(segment
		(start 84.7598 -62.6364)
		(end 85.856064 -61.540136)
		(width 0.11938)
		(layer "F.Cu")
		(net "R_BNO080_BOOT_N")
	)
	(segment
		(start 85.856064 -61.540136)
		(end 85.856064 -61.088016)
		(width 0.11938)
		(layer "F.Cu")
		(net "R_BNO080_BOOT_N")
	)
	(segment
		(start 84.709 -63.7794)
		(end 84.709 -63.2714)
		(width 0.11938)
		(layer "F.Cu")
		(net "R_BNO080_BOOT_N")
	)
	(segment
		(start 84.4804 -62.6364)
		(end 84.7598 -62.6364)
		(width 0.11938)
		(layer "F.Cu")
		(net "R_BNO080_BOOT_N")
	)
	(via
		(at 84.4804 -62.6364)
		(size 0.4572)
		(drill 0.2032)
		(layers "F.Cu" "B.Cu")
		(net "R_BNO080_BOOT_N")
	)
	(segment
		(start 84.709 -63.2714)
		(end 84.709 -63.7794)
		(width 0.11938)
		(layer "B.Cu")
		(net "R_BNO080_BOOT_N")
	)
	(segment
		(start 84.4804 -63.0428)
		(end 84.709 -63.2714)
		(width 0.11938)
		(layer "B.Cu")
		(net "R_BNO080_BOOT_N")
	)
	(segment
		(start 84.4804 -62.6364)
		(end 84.4804 -63.0428)
		(width 0.11938)
		(layer "B.Cu")
		(net "R_BNO080_BOOT_N")
	)
	(segment
		(start 84.4804 -62.8904)
		(end 84.4804 -62.6364)
		(width 0.127)
		(layer "In2.Cu")
		(net "R_BNO080_BOOT_N")
	)
	(segment
		(start 85.725 -67.31)
		(end 85.344 -66.929)
		(width 0.127)
		(layer "In2.Cu")
		(net "R_BNO080_BOOT_N")
	)
	(segment
		(start 85.344 -66.929)
		(end 85.344 -63.754)
		(width 0.127)
		(layer "In2.Cu")
		(net "R_BNO080_BOOT_N")
	)
	(segment
		(start 85.344 -63.754)
		(end 84.4804 -62.8904)
		(width 0.127)
		(layer "In2.Cu")
		(net "R_BNO080_BOOT_N")
	)
	(via
		(at 129.032 -28.067)
		(size 0.508)
		(drill 0.254)
		(layers "F.Cu" "B.Cu")
		(net "PCIE_CONN_TMS")
	)
	(via
		(at 54.56174 -20.01774)
		(size 0.4572)
		(drill 0.2032)
		(layers "F.Cu" "B.Cu")
		(net "PCIE_CONN_TMS")
	)
	(via
		(at 52.90693 -13.335)
		(size 0.762)
		(drill 0.381)
		(layers "F.Cu" "B.Cu")
		(net "PCIE_CONN_TMS")
	)
	(segment
		(start 132.341366 -36.1442)
		(end 132.341366 -58.965084)
		(width 0.11938)
		(layer "B.Cu")
		(net "PCIE_CONN_TMS")
	)
	(segment
		(start 129.777744 -28.812744)
		(end 130.052826 -29.087826)
		(width 0.11938)
		(layer "B.Cu")
		(net "PCIE_CONN_TMS")
	)
	(segment
		(start 130.9497 -34.752534)
		(end 132.341366 -36.1442)
		(width 0.11938)
		(layer "B.Cu")
		(net "PCIE_CONN_TMS")
	)
	(segment
		(start 131.06908 -34.342832)
		(end 130.9497 -34.462212)
		(width 0.11938)
		(layer "B.Cu")
		(net "PCIE_CONN_TMS")
	)
	(segment
		(start 131.06908 -33.715452)
		(end 132.26542 -33.715452)
		(width 0.11938)
		(layer "B.Cu")
		(net "PCIE_CONN_TMS")
	)
	(segment
		(start 52.649882 -6.151118)
		(end 51.943 -6.858)
		(width 0.11938)
		(layer "B.Cu")
		(net "PCIE_CONN_TMS")
	)
	(segment
		(start 132.3848 -33.834832)
		(end 132.3848 -34.223452)
		(width 0.11938)
		(layer "B.Cu")
		(net "PCIE_CONN_TMS")
	)
	(segment
		(start 131.06908 -31.205932)
		(end 132.26542 -31.205932)
		(width 0.11938)
		(layer "B.Cu")
		(net "PCIE_CONN_TMS")
	)
	(segment
		(start 132.3848 -31.713932)
		(end 132.26542 -31.833312)
		(width 0.11938)
		(layer "B.Cu")
		(net "PCIE_CONN_TMS")
	)
	(segment
		(start 137.13714 -62.574678)
		(end 137.13714 -66.684652)
		(width 0.11938)
		(layer "B.Cu")
		(net "PCIE_CONN_TMS")
	)
	(segment
		(start 134.880096 -60.317634)
		(end 137.13714 -62.574678)
		(width 0.11938)
		(layer "B.Cu")
		(net "PCIE_CONN_TMS")
	)
	(segment
		(start 130.919982 -28.557982)
		(end 131.195064 -28.833064)
		(width 0.11938)
		(layer "B.Cu")
		(net "PCIE_CONN_TMS")
	)
	(segment
		(start 129.032 -28.067)
		(end 129.16535 -28.20035)
		(width 0.11938)
		(layer "B.Cu")
		(net "PCIE_CONN_TMS")
	)
	(segment
		(start 132.26542 -31.833312)
		(end 131.06908 -31.833312)
		(width 0.11938)
		(layer "B.Cu")
		(net "PCIE_CONN_TMS")
	)
	(segment
		(start 135.89 -71.755)
		(end 137.033 -72.898)
		(width 0.11938)
		(layer "B.Cu")
		(net "PCIE_CONN_TMS")
	)
	(segment
		(start 129.16535 -28.20035)
		(end 129.334006 -28.20035)
		(width 0.11938)
		(layer "B.Cu")
		(net "PCIE_CONN_TMS")
	)
	(segment
		(start 130.052826 -29.087826)
		(end 130.221482 -29.087826)
		(width 0.11938)
		(layer "B.Cu")
		(net "PCIE_CONN_TMS")
	)
	(segment
		(start 131.06908 -33.088072)
		(end 130.9497 -33.207452)
		(width 0.11938)
		(layer "B.Cu")
		(net "PCIE_CONN_TMS")
	)
	(segment
		(start 132.341366 -58.965084)
		(end 133.693916 -60.317634)
		(width 0.11938)
		(layer "B.Cu")
		(net "PCIE_CONN_TMS")
	)
	(segment
		(start 132.26542 -33.088072)
		(end 131.06908 -33.088072)
		(width 0.11938)
		(layer "B.Cu")
		(net "PCIE_CONN_TMS")
	)
	(segment
		(start 132.26542 -33.715452)
		(end 132.3848 -33.834832)
		(width 0.11938)
		(layer "B.Cu")
		(net "PCIE_CONN_TMS")
	)
	(segment
		(start 137.13714 -66.684652)
		(end 135.89 -67.931792)
		(width 0.11938)
		(layer "B.Cu")
		(net "PCIE_CONN_TMS")
	)
	(segment
		(start 52.649882 -3.500374)
		(end 52.649882 -6.151118)
		(width 0.11938)
		(layer "B.Cu")
		(net "PCIE_CONN_TMS")
	)
	(segment
		(start 132.3848 -34.223452)
		(end 132.26542 -34.342832)
		(width 0.11938)
		(layer "B.Cu")
		(net "PCIE_CONN_TMS")
	)
	(segment
		(start 131.06908 -31.833312)
		(end 130.9497 -31.952692)
		(width 0.11938)
		(layer "B.Cu")
		(net "PCIE_CONN_TMS")
	)
	(segment
		(start 130.66522 -29.70022)
		(end 130.9497 -29.9847)
		(width 0.11938)
		(layer "B.Cu")
		(net "PCIE_CONN_TMS")
	)
	(segment
		(start 130.9497 -33.207452)
		(end 130.9497 -33.596072)
		(width 0.11938)
		(layer "B.Cu")
		(net "PCIE_CONN_TMS")
	)
	(segment
		(start 131.195064 -28.833064)
		(end 131.195064 -29.00172)
		(width 0.11938)
		(layer "B.Cu")
		(net "PCIE_CONN_TMS")
	)
	(segment
		(start 130.9497 -31.952692)
		(end 130.9497 -32.341312)
		(width 0.11938)
		(layer "B.Cu")
		(net "PCIE_CONN_TMS")
	)
	(segment
		(start 52.90693 -13.335)
		(end 52.90693 -14.44117)
		(width 0.11938)
		(layer "B.Cu")
		(net "PCIE_CONN_TMS")
	)
	(segment
		(start 51.943 -6.858)
		(end 51.943 -10.714228)
		(width 0.11938)
		(layer "B.Cu")
		(net "PCIE_CONN_TMS")
	)
	(segment
		(start 129.334006 -28.20035)
		(end 129.86385 -27.670506)
		(width 0.11938)
		(layer "B.Cu")
		(net "PCIE_CONN_TMS")
	)
	(segment
		(start 130.221482 -29.087826)
		(end 130.751326 -28.557982)
		(width 0.11938)
		(layer "B.Cu")
		(net "PCIE_CONN_TMS")
	)
	(segment
		(start 131.06908 -32.460692)
		(end 132.26542 -32.460692)
		(width 0.11938)
		(layer "B.Cu")
		(net "PCIE_CONN_TMS")
	)
	(segment
		(start 130.9497 -29.9847)
		(end 130.9497 -31.086552)
		(width 0.11938)
		(layer "B.Cu")
		(net "PCIE_CONN_TMS")
	)
	(segment
		(start 132.26542 -32.460692)
		(end 132.3848 -32.580072)
		(width 0.11938)
		(layer "B.Cu")
		(net "PCIE_CONN_TMS")
	)
	(segment
		(start 130.9497 -32.341312)
		(end 131.06908 -32.460692)
		(width 0.11938)
		(layer "B.Cu")
		(net "PCIE_CONN_TMS")
	)
	(segment
		(start 53.35524 -17.16024)
		(end 54.56174 -18.36674)
		(width 0.11938)
		(layer "B.Cu")
		(net "PCIE_CONN_TMS")
	)
	(segment
		(start 130.9497 -34.462212)
		(end 130.9497 -34.752534)
		(width 0.11938)
		(layer "B.Cu")
		(net "PCIE_CONN_TMS")
	)
	(segment
		(start 129.86385 -27.670506)
		(end 130.032506 -27.670506)
		(width 0.11938)
		(layer "B.Cu")
		(net "PCIE_CONN_TMS")
	)
	(segment
		(start 130.751326 -28.557982)
		(end 130.919982 -28.557982)
		(width 0.11938)
		(layer "B.Cu")
		(net "PCIE_CONN_TMS")
	)
	(segment
		(start 52.90693 -11.678158)
		(end 52.90693 -13.335)
		(width 0.11938)
		(layer "B.Cu")
		(net "PCIE_CONN_TMS")
	)
	(segment
		(start 132.26542 -34.342832)
		(end 131.06908 -34.342832)
		(width 0.11938)
		(layer "B.Cu")
		(net "PCIE_CONN_TMS")
	)
	(segment
		(start 137.033 -72.898)
		(end 138.5316 -72.898)
		(width 0.11938)
		(layer "B.Cu")
		(net "PCIE_CONN_TMS")
	)
	(segment
		(start 130.66522 -29.531564)
		(end 130.66522 -29.70022)
		(width 0.11938)
		(layer "B.Cu")
		(net "PCIE_CONN_TMS")
	)
	(segment
		(start 131.195064 -29.00172)
		(end 130.66522 -29.531564)
		(width 0.11938)
		(layer "B.Cu")
		(net "PCIE_CONN_TMS")
	)
	(segment
		(start 130.307588 -27.945588)
		(end 130.307588 -28.114244)
		(width 0.11938)
		(layer "B.Cu")
		(net "PCIE_CONN_TMS")
	)
	(segment
		(start 132.3848 -32.968692)
		(end 132.26542 -33.088072)
		(width 0.11938)
		(layer "B.Cu")
		(net "PCIE_CONN_TMS")
	)
	(segment
		(start 54.56174 -18.36674)
		(end 54.56174 -20.01774)
		(width 0.11938)
		(layer "B.Cu")
		(net "PCIE_CONN_TMS")
	)
	(segment
		(start 132.3848 -32.580072)
		(end 132.3848 -32.968692)
		(width 0.11938)
		(layer "B.Cu")
		(net "PCIE_CONN_TMS")
	)
	(segment
		(start 130.307588 -28.114244)
		(end 129.777744 -28.644088)
		(width 0.11938)
		(layer "B.Cu")
		(net "PCIE_CONN_TMS")
	)
	(segment
		(start 51.943 -10.714228)
		(end 52.90693 -11.678158)
		(width 0.11938)
		(layer "B.Cu")
		(net "PCIE_CONN_TMS")
	)
	(segment
		(start 132.26542 -31.205932)
		(end 132.3848 -31.325312)
		(width 0.11938)
		(layer "B.Cu")
		(net "PCIE_CONN_TMS")
	)
	(segment
		(start 129.777744 -28.644088)
		(end 129.777744 -28.812744)
		(width 0.11938)
		(layer "B.Cu")
		(net "PCIE_CONN_TMS")
	)
	(segment
		(start 130.032506 -27.670506)
		(end 130.307588 -27.945588)
		(width 0.11938)
		(layer "B.Cu")
		(net "PCIE_CONN_TMS")
	)
	(segment
		(start 53.35524 -14.88948)
		(end 53.35524 -17.16024)
		(width 0.11938)
		(layer "B.Cu")
		(net "PCIE_CONN_TMS")
	)
	(segment
		(start 133.693916 -60.317634)
		(end 134.880096 -60.317634)
		(width 0.11938)
		(layer "B.Cu")
		(net "PCIE_CONN_TMS")
	)
	(segment
		(start 130.9497 -33.596072)
		(end 131.06908 -33.715452)
		(width 0.11938)
		(layer "B.Cu")
		(net "PCIE_CONN_TMS")
	)
	(segment
		(start 132.3848 -31.325312)
		(end 132.3848 -31.713932)
		(width 0.11938)
		(layer "B.Cu")
		(net "PCIE_CONN_TMS")
	)
	(segment
		(start 135.89 -67.931792)
		(end 135.89 -71.755)
		(width 0.11938)
		(layer "B.Cu")
		(net "PCIE_CONN_TMS")
	)
	(segment
		(start 130.9497 -31.086552)
		(end 131.06908 -31.205932)
		(width 0.11938)
		(layer "B.Cu")
		(net "PCIE_CONN_TMS")
	)
	(segment
		(start 52.90693 -14.44117)
		(end 53.35524 -14.88948)
		(width 0.11938)
		(layer "B.Cu")
		(net "PCIE_CONN_TMS")
	)
	(segment
		(start 114.755168 -18.309336)
		(end 115.273836 -17.790668)
		(width 0.127)
		(layer "In2.Cu")
		(net "PCIE_CONN_TMS")
	)
	(segment
		(start 114.824764 -17.341596)
		(end 114.306096 -17.860264)
		(width 0.127)
		(layer "In2.Cu")
		(net "PCIE_CONN_TMS")
	)
	(segment
		(start 77.978 -20.496022)
		(end 60.910978 -20.496022)
		(width 0.127)
		(layer "In2.Cu")
		(net "PCIE_CONN_TMS")
	)
	(segment
		(start 60.910978 -20.496022)
		(end 60.1091 -21.2979)
		(width 0.127)
		(layer "In2.Cu")
		(net "PCIE_CONN_TMS")
	)
	(segment
		(start 116.6114 -21.082)
		(end 115.57 -20.0406)
		(width 0.127)
		(layer "In2.Cu")
		(net "PCIE_CONN_TMS")
	)
	(segment
		(start 115.57 -19.304)
		(end 114.755168 -18.489168)
		(width 0.127)
		(layer "In2.Cu")
		(net "PCIE_CONN_TMS")
	)
	(segment
		(start 55.00116 -21.2979)
		(end 54.56174 -20.85848)
		(width 0.127)
		(layer "In2.Cu")
		(net "PCIE_CONN_TMS")
	)
	(segment
		(start 115.273836 -17.610836)
		(end 115.004596 -17.341596)
		(width 0.127)
		(layer "In2.Cu")
		(net "PCIE_CONN_TMS")
	)
	(segment
		(start 115.57 -20.0406)
		(end 115.57 -19.304)
		(width 0.127)
		(layer "In2.Cu")
		(net "PCIE_CONN_TMS")
	)
	(segment
		(start 82.95767 -18.9865)
		(end 82.28457 -19.6596)
		(width 0.127)
		(layer "In2.Cu")
		(net "PCIE_CONN_TMS")
	)
	(segment
		(start 113.57864 -17.31264)
		(end 105.704132 -17.31264)
		(width 0.127)
		(layer "In2.Cu")
		(net "PCIE_CONN_TMS")
	)
	(segment
		(start 105.704132 -17.31264)
		(end 105.244392 -16.8529)
		(width 0.127)
		(layer "In2.Cu")
		(net "PCIE_CONN_TMS")
	)
	(segment
		(start 124.353066 -24.1935)
		(end 120.9675 -24.1935)
		(width 0.127)
		(layer "In2.Cu")
		(net "PCIE_CONN_TMS")
	)
	(segment
		(start 114.755168 -18.489168)
		(end 114.755168 -18.309336)
		(width 0.127)
		(layer "In2.Cu")
		(net "PCIE_CONN_TMS")
	)
	(segment
		(start 114.126264 -17.860264)
		(end 113.57864 -17.31264)
		(width 0.127)
		(layer "In2.Cu")
		(net "PCIE_CONN_TMS")
	)
	(segment
		(start 129.032 -28.067)
		(end 128.226566 -28.067)
		(width 0.127)
		(layer "In2.Cu")
		(net "PCIE_CONN_TMS")
	)
	(segment
		(start 115.273836 -17.790668)
		(end 115.273836 -17.610836)
		(width 0.127)
		(layer "In2.Cu")
		(net "PCIE_CONN_TMS")
	)
	(segment
		(start 82.28457 -19.6596)
		(end 78.814422 -19.6596)
		(width 0.127)
		(layer "In2.Cu")
		(net "PCIE_CONN_TMS")
	)
	(segment
		(start 117.856 -21.082)
		(end 116.6114 -21.082)
		(width 0.127)
		(layer "In2.Cu")
		(net "PCIE_CONN_TMS")
	)
	(segment
		(start 128.226566 -28.067)
		(end 124.353066 -24.1935)
		(width 0.127)
		(layer "In2.Cu")
		(net "PCIE_CONN_TMS")
	)
	(segment
		(start 78.814422 -19.6596)
		(end 77.978 -20.496022)
		(width 0.127)
		(layer "In2.Cu")
		(net "PCIE_CONN_TMS")
	)
	(segment
		(start 95.590868 -16.8529)
		(end 93.457268 -18.9865)
		(width 0.127)
		(layer "In2.Cu")
		(net "PCIE_CONN_TMS")
	)
	(segment
		(start 120.9675 -24.1935)
		(end 117.856 -21.082)
		(width 0.127)
		(layer "In2.Cu")
		(net "PCIE_CONN_TMS")
	)
	(segment
		(start 115.004596 -17.341596)
		(end 114.824764 -17.341596)
		(width 0.127)
		(layer "In2.Cu")
		(net "PCIE_CONN_TMS")
	)
	(segment
		(start 105.244392 -16.8529)
		(end 95.590868 -16.8529)
		(width 0.127)
		(layer "In2.Cu")
		(net "PCIE_CONN_TMS")
	)
	(segment
		(start 114.306096 -17.860264)
		(end 114.126264 -17.860264)
		(width 0.127)
		(layer "In2.Cu")
		(net "PCIE_CONN_TMS")
	)
	(segment
		(start 93.457268 -18.9865)
		(end 82.95767 -18.9865)
		(width 0.127)
		(layer "In2.Cu")
		(net "PCIE_CONN_TMS")
	)
	(segment
		(start 54.56174 -20.85848)
		(end 54.56174 -20.01774)
		(width 0.127)
		(layer "In2.Cu")
		(net "PCIE_CONN_TMS")
	)
	(segment
		(start 60.1091 -21.2979)
		(end 55.00116 -21.2979)
		(width 0.127)
		(layer "In2.Cu")
		(net "PCIE_CONN_TMS")
	)
	(via
		(at 52.87264 -18.79346)
		(size 0.508)
		(drill 0.254)
		(layers "F.Cu" "B.Cu")
		(net "PCIE_CONN_TDO")
	)
	(via
		(at 132.715 -29.083)
		(size 0.508)
		(drill 0.254)
		(layers "F.Cu" "B.Cu")
		(net "PCIE_CONN_TDO")
	)
	(via
		(at 51.14798 -10.922)
		(size 0.762)
		(drill 0.381)
		(layers "F.Cu" "B.Cu")
		(net "PCIE_CONN_TDO")
	)
	(via
		(at 130.3528 -16.764)
		(size 0.508)
		(drill 0.254)
		(layers "F.Cu" "B.Cu")
		(net "PCIE_CONN_TDO")
	)
	(segment
		(start 140.6779 -72.136)
		(end 140.8684 -71.9455)
		(width 0.11938)
		(layer "B.Cu")
		(net "PCIE_CONN_TDO")
	)
	(segment
		(start 51.14798 -8.47598)
		(end 50.673 -8.001)
		(width 0.11938)
		(layer "B.Cu")
		(net "PCIE_CONN_TDO")
	)
	(segment
		(start 51.14798 -10.922)
		(end 51.14798 -8.47598)
		(width 0.11938)
		(layer "B.Cu")
		(net "PCIE_CONN_TDO")
	)
	(segment
		(start 136.94664 -72.136)
		(end 140.6779 -72.136)
		(width 0.11938)
		(layer "B.Cu")
		(net "PCIE_CONN_TDO")
	)
	(segment
		(start 133.876034 -59.878214)
		(end 135.062214 -59.878214)
		(width 0.11938)
		(layer "B.Cu")
		(net "PCIE_CONN_TDO")
	)
	(segment
		(start 137.57656 -66.86677)
		(end 137.541 -66.90233)
		(width 0.11938)
		(layer "B.Cu")
		(net "PCIE_CONN_TDO")
	)
	(segment
		(start 136.32942 -68.127118)
		(end 136.32942 -71.51878)
		(width 0.11938)
		(layer "B.Cu")
		(net "PCIE_CONN_TDO")
	)
	(segment
		(start 52.08524 -11.85926)
		(end 51.14798 -10.922)
		(width 0.11938)
		(layer "B.Cu")
		(net "PCIE_CONN_TDO")
	)
	(segment
		(start 50.673 -6.818884)
		(end 51.649884 -5.842)
		(width 0.11938)
		(layer "B.Cu")
		(net "PCIE_CONN_TDO")
	)
	(segment
		(start 140.8684 -71.9455)
		(end 140.8684 -71.501)
		(width 0.11938)
		(layer "B.Cu")
		(net "PCIE_CONN_TDO")
	)
	(segment
		(start 51.649884 -5.842)
		(end 51.649884 -3.500374)
		(width 0.11938)
		(layer "B.Cu")
		(net "PCIE_CONN_TDO")
	)
	(segment
		(start 137.541 -66.90233)
		(end 137.541 -66.915538)
		(width 0.11938)
		(layer "B.Cu")
		(net "PCIE_CONN_TDO")
	)
	(segment
		(start 52.87264 -18.79346)
		(end 52.87264 -16.74368)
		(width 0.11938)
		(layer "B.Cu")
		(net "PCIE_CONN_TDO")
	)
	(segment
		(start 132.715 -29.083)
		(end 132.842 -29.21)
		(width 0.11938)
		(layer "B.Cu")
		(net "PCIE_CONN_TDO")
	)
	(segment
		(start 137.57656 -62.39256)
		(end 137.57656 -66.86677)
		(width 0.11938)
		(layer "B.Cu")
		(net "PCIE_CONN_TDO")
	)
	(segment
		(start 52.08524 -15.95628)
		(end 52.08524 -11.85926)
		(width 0.11938)
		(layer "B.Cu")
		(net "PCIE_CONN_TDO")
	)
	(segment
		(start 52.87264 -16.74368)
		(end 52.08524 -15.95628)
		(width 0.11938)
		(layer "B.Cu")
		(net "PCIE_CONN_TDO")
	)
	(segment
		(start 132.842 -58.84418)
		(end 133.876034 -59.878214)
		(width 0.11938)
		(layer "B.Cu")
		(net "PCIE_CONN_TDO")
	)
	(segment
		(start 137.541 -66.915538)
		(end 136.32942 -68.127118)
		(width 0.11938)
		(layer "B.Cu")
		(net "PCIE_CONN_TDO")
	)
	(segment
		(start 135.062214 -59.878214)
		(end 137.57656 -62.39256)
		(width 0.11938)
		(layer "B.Cu")
		(net "PCIE_CONN_TDO")
	)
	(segment
		(start 50.673 -8.001)
		(end 50.673 -6.818884)
		(width 0.11938)
		(layer "B.Cu")
		(net "PCIE_CONN_TDO")
	)
	(segment
		(start 136.32942 -71.51878)
		(end 136.94664 -72.136)
		(width 0.11938)
		(layer "B.Cu")
		(net "PCIE_CONN_TDO")
	)
	(segment
		(start 132.842 -29.21)
		(end 132.842 -58.84418)
		(width 0.11938)
		(layer "B.Cu")
		(net "PCIE_CONN_TDO")
	)
	(segment
		(start 132.715 -27.304238)
		(end 132.842 -27.431238)
		(width 0.127)
		(layer "In2.Cu")
		(net "PCIE_CONN_TDO")
	)
	(segment
		(start 133.223 -27.558238)
		(end 133.223 -27.939238)
		(width 0.127)
		(layer "In2.Cu")
		(net "PCIE_CONN_TDO")
	)
	(segment
		(start 133.096 -26.796238)
		(end 132.842 -26.796238)
		(width 0.127)
		(layer "In2.Cu")
		(net "PCIE_CONN_TDO")
	)
	(segment
		(start 132.715 -28.193238)
		(end 132.715 -29.083)
		(width 0.127)
		(layer "In2.Cu")
		(net "PCIE_CONN_TDO")
	)
	(segment
		(start 132.715 -26.923238)
		(end 132.715 -27.304238)
		(width 0.127)
		(layer "In2.Cu")
		(net "PCIE_CONN_TDO")
	)
	(segment
		(start 132.842 -26.796238)
		(end 132.715 -26.923238)
		(width 0.127)
		(layer "In2.Cu")
		(net "PCIE_CONN_TDO")
	)
	(segment
		(start 133.223 -26.669238)
		(end 133.096 -26.796238)
		(width 0.127)
		(layer "In2.Cu")
		(net "PCIE_CONN_TDO")
	)
	(segment
		(start 132.842 -28.066238)
		(end 132.715 -28.193238)
		(width 0.127)
		(layer "In2.Cu")
		(net "PCIE_CONN_TDO")
	)
	(segment
		(start 132.842 -26.161238)
		(end 133.096 -26.161238)
		(width 0.127)
		(layer "In2.Cu")
		(net "PCIE_CONN_TDO")
	)
	(segment
		(start 132.715 -26.034238)
		(end 132.842 -26.161238)
		(width 0.127)
		(layer "In2.Cu")
		(net "PCIE_CONN_TDO")
	)
	(segment
		(start 133.096 -26.161238)
		(end 133.223 -26.288238)
		(width 0.127)
		(layer "In2.Cu")
		(net "PCIE_CONN_TDO")
	)
	(segment
		(start 133.096 -28.066238)
		(end 132.842 -28.066238)
		(width 0.127)
		(layer "In2.Cu")
		(net "PCIE_CONN_TDO")
	)
	(segment
		(start 133.223 -27.939238)
		(end 133.096 -28.066238)
		(width 0.127)
		(layer "In2.Cu")
		(net "PCIE_CONN_TDO")
	)
	(segment
		(start 130.3528 -16.764)
		(end 132.715 -19.1262)
		(width 0.127)
		(layer "In2.Cu")
		(net "PCIE_CONN_TDO")
	)
	(segment
		(start 132.842 -27.431238)
		(end 133.096 -27.431238)
		(width 0.127)
		(layer "In2.Cu")
		(net "PCIE_CONN_TDO")
	)
	(segment
		(start 132.715 -19.1262)
		(end 132.715 -26.034238)
		(width 0.127)
		(layer "In2.Cu")
		(net "PCIE_CONN_TDO")
	)
	(segment
		(start 133.096 -27.431238)
		(end 133.223 -27.558238)
		(width 0.127)
		(layer "In2.Cu")
		(net "PCIE_CONN_TDO")
	)
	(segment
		(start 133.223 -26.288238)
		(end 133.223 -26.669238)
		(width 0.127)
		(layer "In2.Cu")
		(net "PCIE_CONN_TDO")
	)
	(segment
		(start 123.7488 -17.8816)
		(end 129.2352 -17.8816)
		(width 0.127)
		(layer "In7.Cu")
		(net "PCIE_CONN_TDO")
	)
	(segment
		(start 52.87264 -18.79346)
		(end 52.87264 -18.24736)
		(width 0.127)
		(layer "In7.Cu")
		(net "PCIE_CONN_TDO")
	)
	(segment
		(start 79.723996 -15.24254)
		(end 84.26704 -15.24254)
		(width 0.127)
		(layer "In7.Cu")
		(net "PCIE_CONN_TDO")
	)
	(segment
		(start 52.87264 -18.24736)
		(end 54.9656 -16.1544)
		(width 0.127)
		(layer "In7.Cu")
		(net "PCIE_CONN_TDO")
	)
	(segment
		(start 73.3044 -14.1224)
		(end 77.359256 -14.1224)
		(width 0.127)
		(layer "In7.Cu")
		(net "PCIE_CONN_TDO")
	)
	(segment
		(start 71.882 -12.7)
		(end 73.3044 -14.1224)
		(width 0.127)
		(layer "In7.Cu")
		(net "PCIE_CONN_TDO")
	)
	(segment
		(start 84.26704 -15.24254)
		(end 85.8901 -16.8656)
		(width 0.127)
		(layer "In7.Cu")
		(net "PCIE_CONN_TDO")
	)
	(segment
		(start 56.769 -16.1544)
		(end 58.801 -14.1224)
		(width 0.127)
		(layer "In7.Cu")
		(net "PCIE_CONN_TDO")
	)
	(segment
		(start 92.2528 -16.3322)
		(end 92.99956 -15.58544)
		(width 0.127)
		(layer "In7.Cu")
		(net "PCIE_CONN_TDO")
	)
	(segment
		(start 79.188056 -14.7066)
		(end 79.723996 -15.24254)
		(width 0.127)
		(layer "In7.Cu")
		(net "PCIE_CONN_TDO")
	)
	(segment
		(start 65.8114 -12.7)
		(end 71.882 -12.7)
		(width 0.127)
		(layer "In7.Cu")
		(net "PCIE_CONN_TDO")
	)
	(segment
		(start 54.9656 -16.1544)
		(end 56.769 -16.1544)
		(width 0.127)
		(layer "In7.Cu")
		(net "PCIE_CONN_TDO")
	)
	(segment
		(start 88.5444 -16.8656)
		(end 89.0778 -16.3322)
		(width 0.127)
		(layer "In7.Cu")
		(net "PCIE_CONN_TDO")
	)
	(segment
		(start 121.45264 -15.58544)
		(end 123.7488 -17.8816)
		(width 0.127)
		(layer "In7.Cu")
		(net "PCIE_CONN_TDO")
	)
	(segment
		(start 85.8901 -16.8656)
		(end 88.5444 -16.8656)
		(width 0.127)
		(layer "In7.Cu")
		(net "PCIE_CONN_TDO")
	)
	(segment
		(start 77.359256 -14.1224)
		(end 77.943456 -14.7066)
		(width 0.127)
		(layer "In7.Cu")
		(net "PCIE_CONN_TDO")
	)
	(segment
		(start 129.2352 -17.8816)
		(end 130.3528 -16.764)
		(width 0.127)
		(layer "In7.Cu")
		(net "PCIE_CONN_TDO")
	)
	(segment
		(start 89.0778 -16.3322)
		(end 92.2528 -16.3322)
		(width 0.127)
		(layer "In7.Cu")
		(net "PCIE_CONN_TDO")
	)
	(segment
		(start 64.389 -14.1224)
		(end 65.8114 -12.7)
		(width 0.127)
		(layer "In7.Cu")
		(net "PCIE_CONN_TDO")
	)
	(segment
		(start 92.99956 -15.58544)
		(end 121.45264 -15.58544)
		(width 0.127)
		(layer "In7.Cu")
		(net "PCIE_CONN_TDO")
	)
	(segment
		(start 58.801 -14.1224)
		(end 64.389 -14.1224)
		(width 0.127)
		(layer "In7.Cu")
		(net "PCIE_CONN_TDO")
	)
	(segment
		(start 77.943456 -14.7066)
		(end 79.188056 -14.7066)
		(width 0.127)
		(layer "In7.Cu")
		(net "PCIE_CONN_TDO")
	)
	(via
		(at 129.032 -29.337)
		(size 0.508)
		(drill 0.254)
		(layers "F.Cu" "B.Cu")
		(net "PCIE_CONN_TDI")
	)
	(via
		(at 51.562 -19.05)
		(size 0.4572)
		(drill 0.2032)
		(layers "F.Cu" "B.Cu")
		(net "PCIE_CONN_TDI")
	)
	(via
		(at 50.292 -12.573)
		(size 0.762)
		(drill 0.381)
		(layers "F.Cu" "B.Cu")
		(net "PCIE_CONN_TDI")
	)
	(segment
		(start 131.901946 -36.3982)
		(end 130.3909 -34.887154)
		(width 0.11938)
		(layer "B.Cu")
		(net "PCIE_CONN_TDI")
	)
	(segment
		(start 136.69772 -62.756796)
		(end 134.697978 -60.757054)
		(width 0.11938)
		(layer "B.Cu")
		(net "PCIE_CONN_TDI")
	)
	(segment
		(start 140.8684 -77.851)
		(end 140.8684 -78.66126)
		(width 0.11938)
		(layer "B.Cu")
		(net "PCIE_CONN_TDI")
	)
	(segment
		(start 50.665126 -18.153126)
		(end 50.665126 -12.946126)
		(width 0.11938)
		(layer "B.Cu")
		(net "PCIE_CONN_TDI")
	)
	(segment
		(start 50.089308 -8.596884)
		(end 50.089308 -6.656578)
		(width 0.11938)
		(layer "B.Cu")
		(net "PCIE_CONN_TDI")
	)
	(segment
		(start 51.562 -19.05)
		(end 50.665126 -18.153126)
		(width 0.11938)
		(layer "B.Cu")
		(net "PCIE_CONN_TDI")
	)
	(segment
		(start 50.292 -12.573)
		(end 49.784 -12.065)
		(width 0.11938)
		(layer "B.Cu")
		(net "PCIE_CONN_TDI")
	)
	(segment
		(start 130.3909 -30.6959)
		(end 129.032 -29.337)
		(width 0.11938)
		(layer "B.Cu")
		(net "PCIE_CONN_TDI")
	)
	(segment
		(start 137.39622 -79.07782)
		(end 135.5852 -77.2668)
		(width 0.11938)
		(layer "B.Cu")
		(net "PCIE_CONN_TDI")
	)
	(segment
		(start 130.3909 -34.887154)
		(end 130.3909 -30.6959)
		(width 0.11938)
		(layer "B.Cu")
		(net "PCIE_CONN_TDI")
	)
	(segment
		(start 50.089308 -6.656578)
		(end 50.649886 -6.096)
		(width 0.11938)
		(layer "B.Cu")
		(net "PCIE_CONN_TDI")
	)
	(segment
		(start 134.62 -68.453254)
		(end 136.69772 -66.375534)
		(width 0.11938)
		(layer "B.Cu")
		(net "PCIE_CONN_TDI")
	)
	(segment
		(start 50.649886 -6.096)
		(end 50.649886 -3.500374)
		(width 0.11938)
		(layer "B.Cu")
		(net "PCIE_CONN_TDI")
	)
	(segment
		(start 140.8684 -78.66126)
		(end 140.45184 -79.07782)
		(width 0.11938)
		(layer "B.Cu")
		(net "PCIE_CONN_TDI")
	)
	(segment
		(start 49.784 -12.065)
		(end 49.784 -8.902192)
		(width 0.11938)
		(layer "B.Cu")
		(net "PCIE_CONN_TDI")
	)
	(segment
		(start 50.665126 -12.946126)
		(end 50.292 -12.573)
		(width 0.11938)
		(layer "B.Cu")
		(net "PCIE_CONN_TDI")
	)
	(segment
		(start 134.697978 -60.757054)
		(end 133.511798 -60.757054)
		(width 0.11938)
		(layer "B.Cu")
		(net "PCIE_CONN_TDI")
	)
	(segment
		(start 140.45184 -79.07782)
		(end 137.39622 -79.07782)
		(width 0.11938)
		(layer "B.Cu")
		(net "PCIE_CONN_TDI")
	)
	(segment
		(start 49.784 -8.902192)
		(end 50.089308 -8.596884)
		(width 0.11938)
		(layer "B.Cu")
		(net "PCIE_CONN_TDI")
	)
	(segment
		(start 135.5852 -77.2668)
		(end 135.5852 -72.0852)
		(width 0.11938)
		(layer "B.Cu")
		(net "PCIE_CONN_TDI")
	)
	(segment
		(start 134.62 -71.12)
		(end 134.62 -68.453254)
		(width 0.11938)
		(layer "B.Cu")
		(net "PCIE_CONN_TDI")
	)
	(segment
		(start 133.511798 -60.757054)
		(end 131.901946 -59.147202)
		(width 0.11938)
		(layer "B.Cu")
		(net "PCIE_CONN_TDI")
	)
	(segment
		(start 135.5852 -72.0852)
		(end 134.62 -71.12)
		(width 0.11938)
		(layer "B.Cu")
		(net "PCIE_CONN_TDI")
	)
	(segment
		(start 131.901946 -59.147202)
		(end 131.901946 -36.3982)
		(width 0.11938)
		(layer "B.Cu")
		(net "PCIE_CONN_TDI")
	)
	(segment
		(start 136.69772 -66.375534)
		(end 136.69772 -62.756796)
		(width 0.11938)
		(layer "B.Cu")
		(net "PCIE_CONN_TDI")
	)
	(segment
		(start 95.801434 -17.3609)
		(end 105.033826 -17.3609)
		(width 0.127)
		(layer "In2.Cu")
		(net "PCIE_CONN_TDI")
	)
	(segment
		(start 61.164978 -21.004022)
		(end 78.360778 -21.004022)
		(width 0.127)
		(layer "In2.Cu")
		(net "PCIE_CONN_TDI")
	)
	(segment
		(start 51.963066 -21.971)
		(end 60.198 -21.971)
		(width 0.127)
		(layer "In2.Cu")
		(net "PCIE_CONN_TDI")
	)
	(segment
		(start 116.349018 -22.6695)
		(end 118.5545 -22.6695)
		(width 0.127)
		(layer "In2.Cu")
		(net "PCIE_CONN_TDI")
	)
	(segment
		(start 118.5545 -22.6695)
		(end 120.65 -24.765)
		(width 0.127)
		(layer "In2.Cu")
		(net "PCIE_CONN_TDI")
	)
	(segment
		(start 128.778 -29.337)
		(end 129.032 -29.337)
		(width 0.127)
		(layer "In2.Cu")
		(net "PCIE_CONN_TDI")
	)
	(segment
		(start 60.198 -21.971)
		(end 61.164978 -21.004022)
		(width 0.127)
		(layer "In2.Cu")
		(net "PCIE_CONN_TDI")
	)
	(segment
		(start 82.495136 -20.1676)
		(end 83.168236 -19.4945)
		(width 0.127)
		(layer "In2.Cu")
		(net "PCIE_CONN_TDI")
	)
	(segment
		(start 115.062 -21.382482)
		(end 116.349018 -22.6695)
		(width 0.127)
		(layer "In2.Cu")
		(net "PCIE_CONN_TDI")
	)
	(segment
		(start 115.062 -19.601434)
		(end 115.062 -21.382482)
		(width 0.127)
		(layer "In2.Cu")
		(net "PCIE_CONN_TDI")
	)
	(segment
		(start 124.206 -24.765)
		(end 128.778 -29.337)
		(width 0.127)
		(layer "In2.Cu")
		(net "PCIE_CONN_TDI")
	)
	(segment
		(start 83.168236 -19.4945)
		(end 93.667834 -19.4945)
		(width 0.127)
		(layer "In2.Cu")
		(net "PCIE_CONN_TDI")
	)
	(segment
		(start 93.667834 -19.4945)
		(end 95.801434 -17.3609)
		(width 0.127)
		(layer "In2.Cu")
		(net "PCIE_CONN_TDI")
	)
	(segment
		(start 51.562 -19.05)
		(end 51.562 -21.569934)
		(width 0.127)
		(layer "In2.Cu")
		(net "PCIE_CONN_TDI")
	)
	(segment
		(start 120.65 -24.765)
		(end 124.206 -24.765)
		(width 0.127)
		(layer "In2.Cu")
		(net "PCIE_CONN_TDI")
	)
	(segment
		(start 51.562 -21.569934)
		(end 51.963066 -21.971)
		(width 0.127)
		(layer "In2.Cu")
		(net "PCIE_CONN_TDI")
	)
	(segment
		(start 78.360778 -21.004022)
		(end 79.1972 -20.1676)
		(width 0.127)
		(layer "In2.Cu")
		(net "PCIE_CONN_TDI")
	)
	(segment
		(start 105.033826 -17.3609)
		(end 105.579926 -17.907)
		(width 0.127)
		(layer "In2.Cu")
		(net "PCIE_CONN_TDI")
	)
	(segment
		(start 79.1972 -20.1676)
		(end 82.495136 -20.1676)
		(width 0.127)
		(layer "In2.Cu")
		(net "PCIE_CONN_TDI")
	)
	(segment
		(start 105.579926 -17.907)
		(end 113.367566 -17.907)
		(width 0.127)
		(layer "In2.Cu")
		(net "PCIE_CONN_TDI")
	)
	(segment
		(start 113.367566 -17.907)
		(end 115.062 -19.601434)
		(width 0.127)
		(layer "In2.Cu")
		(net "PCIE_CONN_TDI")
	)
	(via
		(at 129.032 -26.797)
		(size 0.508)
		(drill 0.254)
		(layers "F.Cu" "B.Cu")
		(net "PCIE_CONN_TCK")
	)
	(via
		(at 52.80152 -19.99996)
		(size 0.4572)
		(drill 0.2032)
		(layers "F.Cu" "B.Cu")
		(net "PCIE_CONN_TCK")
	)
	(via
		(at 48.8696 -11.629644)
		(size 0.762)
		(drill 0.381)
		(layers "F.Cu" "B.Cu")
		(net "PCIE_CONN_TCK")
	)
	(segment
		(start 49.395126 -17.754092)
		(end 49.395126 -14.88948)
		(width 0.11938)
		(layer "B.Cu")
		(net "PCIE_CONN_TCK")
	)
	(segment
		(start 131.826 -26.797)
		(end 129.032 -26.797)
		(width 0.11938)
		(layer "B.Cu")
		(net "PCIE_CONN_TCK")
	)
	(segment
		(start 52.80152 -19.99996)
		(end 50.86096 -19.99996)
		(width 0.11938)
		(layer "B.Cu")
		(net "PCIE_CONN_TCK")
	)
	(segment
		(start 49.395126 -14.88948)
		(end 48.70831 -14.202664)
		(width 0.11938)
		(layer "B.Cu")
		(net "PCIE_CONN_TCK")
	)
	(segment
		(start 133.35 -28.321)
		(end 131.826 -26.797)
		(width 0.11938)
		(layer "B.Cu")
		(net "PCIE_CONN_TCK")
	)
	(segment
		(start 134.112 -59.309)
		(end 133.35 -58.547)
		(width 0.11938)
		(layer "B.Cu")
		(net "PCIE_CONN_TCK")
	)
	(segment
		(start 133.35 -58.547)
		(end 133.35 -28.321)
		(width 0.11938)
		(layer "B.Cu")
		(net "PCIE_CONN_TCK")
	)
	(segment
		(start 50.731928 -19.870928)
		(end 50.731928 -19.090894)
		(width 0.11938)
		(layer "B.Cu")
		(net "PCIE_CONN_TCK")
	)
	(segment
		(start 50.86096 -19.99996)
		(end 50.731928 -19.870928)
		(width 0.11938)
		(layer "B.Cu")
		(net "PCIE_CONN_TCK")
	)
	(segment
		(start 50.731928 -19.090894)
		(end 49.395126 -17.754092)
		(width 0.11938)
		(layer "B.Cu")
		(net "PCIE_CONN_TCK")
	)
	(segment
		(start 135.29818 -59.309)
		(end 134.112 -59.309)
		(width 0.11938)
		(layer "B.Cu")
		(net "PCIE_CONN_TCK")
	)
	(segment
		(start 140.8684 -65.913)
		(end 140.8684 -64.87922)
		(width 0.11938)
		(layer "B.Cu")
		(net "PCIE_CONN_TCK")
	)
	(segment
		(start 140.8684 -64.87922)
		(end 135.29818 -59.309)
		(width 0.11938)
		(layer "B.Cu")
		(net "PCIE_CONN_TCK")
	)
	(segment
		(start 48.70831 -11.790934)
		(end 48.8696 -11.629644)
		(width 0.11938)
		(layer "B.Cu")
		(net "PCIE_CONN_TCK")
	)
	(segment
		(start 49.649888 -8.414512)
		(end 49.649888 -3.500374)
		(width 0.11938)
		(layer "B.Cu")
		(net "PCIE_CONN_TCK")
	)
	(segment
		(start 49.34458 -11.154664)
		(end 49.34458 -8.71982)
		(width 0.11938)
		(layer "B.Cu")
		(net "PCIE_CONN_TCK")
	)
	(segment
		(start 48.70831 -14.202664)
		(end 48.70831 -11.790934)
		(width 0.11938)
		(layer "B.Cu")
		(net "PCIE_CONN_TCK")
	)
	(segment
		(start 48.8696 -11.629644)
		(end 49.34458 -11.154664)
		(width 0.11938)
		(layer "B.Cu")
		(net "PCIE_CONN_TCK")
	)
	(segment
		(start 49.34458 -8.71982)
		(end 49.649888 -8.414512)
		(width 0.11938)
		(layer "B.Cu")
		(net "PCIE_CONN_TCK")
	)
	(segment
		(start 95.380302 -16.3449)
		(end 105.454958 -16.3449)
		(width 0.127)
		(layer "In2.Cu")
		(net "PCIE_CONN_TCK")
	)
	(segment
		(start 54.42966 -19.33702)
		(end 56.339994 -19.33702)
		(width 0.127)
		(layer "In2.Cu")
		(net "PCIE_CONN_TCK")
	)
	(segment
		(start 124.392436 -22.106636)
		(end 124.661676 -22.375876)
		(width 0.127)
		(layer "In2.Cu")
		(net "PCIE_CONN_TCK")
	)
	(segment
		(start 59.107832 -19.988022)
		(end 77.6224 -19.988022)
		(width 0.127)
		(layer "In2.Cu")
		(net "PCIE_CONN_TCK")
	)
	(segment
		(start 124.212604 -22.106636)
		(end 124.392436 -22.106636)
		(width 0.127)
		(layer "In2.Cu")
		(net "PCIE_CONN_TCK")
	)
	(segment
		(start 120.8532 -18.134584)
		(end 120.7262 -18.261584)
		(width 0.127)
		(layer "In2.Cu")
		(net "PCIE_CONN_TCK")
	)
	(segment
		(start 77.6224 -19.988022)
		(end 78.535022 -19.0754)
		(width 0.127)
		(layer "In2.Cu")
		(net "PCIE_CONN_TCK")
	)
	(segment
		(start 126.008892 -23.902924)
		(end 126.188724 -23.902924)
		(width 0.127)
		(layer "In2.Cu")
		(net "PCIE_CONN_TCK")
	)
	(segment
		(start 105.454958 -16.3449)
		(end 105.914698 -16.80464)
		(width 0.127)
		(layer "In2.Cu")
		(net "PCIE_CONN_TCK")
	)
	(segment
		(start 125.933962 -25.05583)
		(end 127.675132 -26.797)
		(width 0.127)
		(layer "In2.Cu")
		(net "PCIE_CONN_TCK")
	)
	(segment
		(start 125.55982 -23.27402)
		(end 125.55982 -23.453852)
		(width 0.127)
		(layer "In2.Cu")
		(net "PCIE_CONN_TCK")
	)
	(segment
		(start 124.661676 -22.375876)
		(end 124.661676 -22.555708)
		(width 0.127)
		(layer "In2.Cu")
		(net "PCIE_CONN_TCK")
	)
	(segment
		(start 124.137674 -23.07971)
		(end 124.137674 -23.259542)
		(width 0.127)
		(layer "In2.Cu")
		(net "PCIE_CONN_TCK")
	)
	(segment
		(start 125.48489 -24.426926)
		(end 126.008892 -23.902924)
		(width 0.127)
		(layer "In2.Cu")
		(net "PCIE_CONN_TCK")
	)
	(segment
		(start 125.305058 -24.426926)
		(end 125.48489 -24.426926)
		(width 0.127)
		(layer "In2.Cu")
		(net "PCIE_CONN_TCK")
	)
	(segment
		(start 125.035818 -24.157686)
		(end 125.305058 -24.426926)
		(width 0.127)
		(layer "In2.Cu")
		(net "PCIE_CONN_TCK")
	)
	(segment
		(start 116.078 -19.7358)
		(end 116.9162 -20.574)
		(width 0.127)
		(layer "In2.Cu")
		(net "PCIE_CONN_TCK")
	)
	(segment
		(start 116.078 -17.499584)
		(end 116.205 -17.626584)
		(width 0.127)
		(layer "In2.Cu")
		(net "PCIE_CONN_TCK")
	)
	(segment
		(start 124.406914 -23.528782)
		(end 124.586746 -23.528782)
		(width 0.127)
		(layer "In2.Cu")
		(net "PCIE_CONN_TCK")
	)
	(segment
		(start 82.747104 -18.4785)
		(end 93.246702 -18.4785)
		(width 0.127)
		(layer "In2.Cu")
		(net "PCIE_CONN_TCK")
	)
	(segment
		(start 120.8532 -17.753584)
		(end 120.8532 -18.134584)
		(width 0.127)
		(layer "In2.Cu")
		(net "PCIE_CONN_TCK")
	)
	(segment
		(start 118.066566 -20.574)
		(end 119.590566 -22.098)
		(width 0.127)
		(layer "In2.Cu")
		(net "PCIE_CONN_TCK")
	)
	(segment
		(start 123.688602 -22.630638)
		(end 124.212604 -22.106636)
		(width 0.127)
		(layer "In2.Cu")
		(net "PCIE_CONN_TCK")
	)
	(segment
		(start 116.078 -17.170146)
		(end 116.078 -17.499584)
		(width 0.127)
		(layer "In2.Cu")
		(net "PCIE_CONN_TCK")
	)
	(segment
		(start 124.586746 -23.528782)
		(end 125.110748 -23.00478)
		(width 0.127)
		(layer "In2.Cu")
		(net "PCIE_CONN_TCK")
	)
	(segment
		(start 123.50877 -22.630638)
		(end 123.688602 -22.630638)
		(width 0.127)
		(layer "In2.Cu")
		(net "PCIE_CONN_TCK")
	)
	(segment
		(start 125.29058 -23.00478)
		(end 125.55982 -23.27402)
		(width 0.127)
		(layer "In2.Cu")
		(net "PCIE_CONN_TCK")
	)
	(segment
		(start 125.933962 -24.875998)
		(end 125.933962 -25.05583)
		(width 0.127)
		(layer "In2.Cu")
		(net "PCIE_CONN_TCK")
	)
	(segment
		(start 53.11902 -20.31746)
		(end 53.44922 -20.31746)
		(width 0.127)
		(layer "In2.Cu")
		(net "PCIE_CONN_TCK")
	)
	(segment
		(start 116.9162 -20.574)
		(end 118.066566 -20.574)
		(width 0.127)
		(layer "In2.Cu")
		(net "PCIE_CONN_TCK")
	)
	(segment
		(start 53.44922 -20.31746)
		(end 54.42966 -19.33702)
		(width 0.127)
		(layer "In2.Cu")
		(net "PCIE_CONN_TCK")
	)
	(segment
		(start 125.035818 -23.977854)
		(end 125.035818 -24.157686)
		(width 0.127)
		(layer "In2.Cu")
		(net "PCIE_CONN_TCK")
	)
	(segment
		(start 93.246702 -18.4785)
		(end 95.380302 -16.3449)
		(width 0.127)
		(layer "In2.Cu")
		(net "PCIE_CONN_TCK")
	)
	(segment
		(start 119.590566 -22.098)
		(end 122.976132 -22.098)
		(width 0.127)
		(layer "In2.Cu")
		(net "PCIE_CONN_TCK")
	)
	(segment
		(start 124.137674 -23.259542)
		(end 124.406914 -23.528782)
		(width 0.127)
		(layer "In2.Cu")
		(net "PCIE_CONN_TCK")
	)
	(segment
		(start 82.150204 -19.0754)
		(end 82.747104 -18.4785)
		(width 0.127)
		(layer "In2.Cu")
		(net "PCIE_CONN_TCK")
	)
	(segment
		(start 120.7262 -18.261584)
		(end 116.205 -18.261584)
		(width 0.127)
		(layer "In2.Cu")
		(net "PCIE_CONN_TCK")
	)
	(segment
		(start 58.308494 -20.78736)
		(end 59.107832 -19.988022)
		(width 0.127)
		(layer "In2.Cu")
		(net "PCIE_CONN_TCK")
	)
	(segment
		(start 125.55982 -23.453852)
		(end 125.035818 -23.977854)
		(width 0.127)
		(layer "In2.Cu")
		(net "PCIE_CONN_TCK")
	)
	(segment
		(start 105.914698 -16.80464)
		(end 115.712494 -16.80464)
		(width 0.127)
		(layer "In2.Cu")
		(net "PCIE_CONN_TCK")
	)
	(segment
		(start 124.661676 -22.555708)
		(end 124.137674 -23.07971)
		(width 0.127)
		(layer "In2.Cu")
		(net "PCIE_CONN_TCK")
	)
	(segment
		(start 116.205 -18.261584)
		(end 116.078 -18.388584)
		(width 0.127)
		(layer "In2.Cu")
		(net "PCIE_CONN_TCK")
	)
	(segment
		(start 57.790334 -20.78736)
		(end 58.308494 -20.78736)
		(width 0.127)
		(layer "In2.Cu")
		(net "PCIE_CONN_TCK")
	)
	(segment
		(start 125.110748 -23.00478)
		(end 125.29058 -23.00478)
		(width 0.127)
		(layer "In2.Cu")
		(net "PCIE_CONN_TCK")
	)
	(segment
		(start 127.675132 -26.797)
		(end 129.032 -26.797)
		(width 0.127)
		(layer "In2.Cu")
		(net "PCIE_CONN_TCK")
	)
	(segment
		(start 115.712494 -16.80464)
		(end 116.078 -17.170146)
		(width 0.127)
		(layer "In2.Cu")
		(net "PCIE_CONN_TCK")
	)
	(segment
		(start 56.339994 -19.33702)
		(end 57.790334 -20.78736)
		(width 0.127)
		(layer "In2.Cu")
		(net "PCIE_CONN_TCK")
	)
	(segment
		(start 126.457964 -24.172164)
		(end 126.457964 -24.351996)
		(width 0.127)
		(layer "In2.Cu")
		(net "PCIE_CONN_TCK")
	)
	(segment
		(start 116.205 -17.626584)
		(end 120.7262 -17.626584)
		(width 0.127)
		(layer "In2.Cu")
		(net "PCIE_CONN_TCK")
	)
	(segment
		(start 52.80152 -19.99996)
		(end 53.11902 -20.31746)
		(width 0.127)
		(layer "In2.Cu")
		(net "PCIE_CONN_TCK")
	)
	(segment
		(start 116.078 -18.388584)
		(end 116.078 -19.7358)
		(width 0.127)
		(layer "In2.Cu")
		(net "PCIE_CONN_TCK")
	)
	(segment
		(start 122.976132 -22.098)
		(end 123.50877 -22.630638)
		(width 0.127)
		(layer "In2.Cu")
		(net "PCIE_CONN_TCK")
	)
	(segment
		(start 78.535022 -19.0754)
		(end 82.150204 -19.0754)
		(width 0.127)
		(layer "In2.Cu")
		(net "PCIE_CONN_TCK")
	)
	(segment
		(start 126.188724 -23.902924)
		(end 126.457964 -24.172164)
		(width 0.127)
		(layer "In2.Cu")
		(net "PCIE_CONN_TCK")
	)
	(segment
		(start 126.457964 -24.351996)
		(end 125.933962 -24.875998)
		(width 0.127)
		(layer "In2.Cu")
		(net "PCIE_CONN_TCK")
	)
	(segment
		(start 120.7262 -17.626584)
		(end 120.8532 -17.753584)
		(width 0.127)
		(layer "In2.Cu")
		(net "PCIE_CONN_TCK")
	)
	(segment
		(start 68.2752 -14.51102)
		(end 68.2752 -13.8938)
		(width 0.11938)
		(layer "F.Cu")
		(net "PCIE_CONN_PERST_N")
	)
	(segment
		(start 66.8782 -14.7066)
		(end 66.9798 -14.8082)
		(width 0.11938)
		(layer "F.Cu")
		(net "PCIE_CONN_PERST_N")
	)
	(segment
		(start 69.13118 -15.367)
		(end 68.2752 -14.51102)
		(width 0.11938)
		(layer "F.Cu")
		(net "PCIE_CONN_PERST_N")
	)
	(segment
		(start 67.6402 -13.2588)
		(end 66.8782 -13.2588)
		(width 0.11938)
		(layer "F.Cu")
		(net "PCIE_CONN_PERST_N")
	)
	(segment
		(start 66.8782 -13.2588)
		(end 66.8782 -14.7066)
		(width 0.11938)
		(layer "F.Cu")
		(net "PCIE_CONN_PERST_N")
	)
	(segment
		(start 68.2752 -13.8938)
		(end 67.6402 -13.2588)
		(width 0.11938)
		(layer "F.Cu")
		(net "PCIE_CONN_PERST_N")
	)
	(segment
		(start 66.9798 -14.8082)
		(end 66.9798 -15.367)
		(width 0.11938)
		(layer "F.Cu")
		(net "PCIE_CONN_PERST_N")
	)
	(segment
		(start 66.9798 -15.367)
		(end 66.9798 -16.637)
		(width 0.11938)
		(layer "F.Cu")
		(net "PCIE_CONN_PERST_N")
	)
	(segment
		(start 69.9516 -15.367)
		(end 69.13118 -15.367)
		(width 0.11938)
		(layer "F.Cu")
		(net "PCIE_CONN_PERST_N")
	)
	(via
		(at 66.8782 -13.2588)
		(size 0.4572)
		(drill 0.2032)
		(layers "F.Cu" "B.Cu")
		(net "PCIE_CONN_PERST_N")
	)
	(segment
		(start 55.649876 -10.183876)
		(end 55.649876 -3.500374)
		(width 0.11938)
		(layer "B.Cu")
		(net "PCIE_CONN_PERST_N")
	)
	(segment
		(start 58.313828 -12.425172)
		(end 57.064656 -11.176)
		(width 0.11938)
		(layer "B.Cu")
		(net "PCIE_CONN_PERST_N")
	)
	(segment
		(start 57.064656 -11.176)
		(end 56.642 -11.176)
		(width 0.11938)
		(layer "B.Cu")
		(net "PCIE_CONN_PERST_N")
	)
	(segment
		(start 56.642 -11.176)
		(end 55.649876 -10.183876)
		(width 0.11938)
		(layer "B.Cu")
		(net "PCIE_CONN_PERST_N")
	)
	(segment
		(start 66.2432 -13.2588)
		(end 66.0654 -13.081)
		(width 0.127)
		(layer "In2.Cu")
		(net "PCIE_CONN_PERST_N")
	)
	(segment
		(start 66.0654 -13.081)
		(end 61.722 -13.081)
		(width 0.127)
		(layer "In2.Cu")
		(net "PCIE_CONN_PERST_N")
	)
	(segment
		(start 66.8782 -13.2588)
		(end 66.2432 -13.2588)
		(width 0.127)
		(layer "In2.Cu")
		(net "PCIE_CONN_PERST_N")
	)
	(segment
		(start 61.066172 -12.425172)
		(end 58.313828 -12.425172)
		(width 0.127)
		(layer "In2.Cu")
		(net "PCIE_CONN_PERST_N")
	)
	(segment
		(start 61.722 -13.081)
		(end 61.066172 -12.425172)
		(width 0.127)
		(layer "In2.Cu")
		(net "PCIE_CONN_PERST_N")
	)
	(segment
		(start 23.5585 -24.8285)
		(end 23.4315 -24.8285)
		(width 0.11938)
		(layer "F.Cu")
		(net "PCA9546_I2C_SDA")
	)
	(segment
		(start 23.114 -41.91)
		(end 23.114 -37.592)
		(width 0.11938)
		(layer "F.Cu")
		(net "PCA9546_I2C_SDA")
	)
	(segment
		(start 122.428 -21.209)
		(end 122.62612 -21.40712)
		(width 0.11938)
		(layer "F.Cu")
		(net "PCA9546_I2C_SDA")
	)
	(segment
		(start 23.68931 -37.01669)
		(end 23.68931 -36.721796)
		(width 0.11938)
		(layer "F.Cu")
		(net "PCA9546_I2C_SDA")
	)
	(segment
		(start 122.62612 -21.40712)
		(end 124.0917 -21.40712)
		(width 0.11938)
		(layer "F.Cu")
		(net "PCA9546_I2C_SDA")
	)
	(segment
		(start 23.114 -37.592)
		(end 23.68931 -37.01669)
		(width 0.11938)
		(layer "F.Cu")
		(net "PCA9546_I2C_SDA")
	)
	(segment
		(start 23.876 -36.535106)
		(end 23.876 -34.163)
		(width 0.11938)
		(layer "F.Cu")
		(net "PCA9546_I2C_SDA")
	)
	(segment
		(start 24.638 -33.401)
		(end 24.638 -25.908)
		(width 0.11938)
		(layer "F.Cu")
		(net "PCA9546_I2C_SDA")
	)
	(segment
		(start 22.4155 -42.6085)
		(end 23.114 -41.91)
		(width 0.11938)
		(layer "F.Cu")
		(net "PCA9546_I2C_SDA")
	)
	(segment
		(start 23.876 -34.163)
		(end 24.638 -33.401)
		(width 0.11938)
		(layer "F.Cu")
		(net "PCA9546_I2C_SDA")
	)
	(segment
		(start 24.638 -25.908)
		(end 23.5585 -24.8285)
		(width 0.11938)
		(layer "F.Cu")
		(net "PCA9546_I2C_SDA")
	)
	(segment
		(start 22.4155 -45.0215)
		(end 22.4155 -42.6085)
		(width 0.11938)
		(layer "F.Cu")
		(net "PCA9546_I2C_SDA")
	)
	(segment
		(start 23.68931 -36.721796)
		(end 23.876 -36.535106)
		(width 0.11938)
		(layer "F.Cu")
		(net "PCA9546_I2C_SDA")
	)
	(via
		(at 87.757 -22.098)
		(size 0.508)
		(drill 0.254)
		(layers "F.Cu" "B.Cu")
		(net "PCA9546_I2C_SDA")
	)
	(via
		(at 23.4315 -24.8285)
		(size 0.508)
		(drill 0.254)
		(layers "F.Cu" "B.Cu")
		(net "PCA9546_I2C_SDA")
	)
	(via
		(at 122.428 -21.209)
		(size 0.508)
		(drill 0.254)
		(layers "F.Cu" "B.Cu")
		(net "PCA9546_I2C_SDA")
	)
	(via
		(at 22.4155 -45.0215)
		(size 0.508)
		(drill 0.254)
		(layers "F.Cu" "B.Cu")
		(net "PCA9546_I2C_SDA")
	)
	(segment
		(start 120.59158 -17.40408)
		(end 120.316498 -17.128998)
		(width 0.11938)
		(layer "B.Cu")
		(net "PCA9546_I2C_SDA")
	)
	(segment
		(start 121.361962 -18.745962)
		(end 121.361962 -18.577306)
		(width 0.11938)
		(layer "B.Cu")
		(net "PCA9546_I2C_SDA")
	)
	(segment
		(start 121.528586 -18.242026)
		(end 121.253504 -17.966944)
		(width 0.11938)
		(layer "B.Cu")
		(net "PCA9546_I2C_SDA")
	)
	(segment
		(start 17.1704 -41.517062)
		(end 17.1704 -40.6146)
		(width 0.11938)
		(layer "B.Cu")
		(net "PCA9546_I2C_SDA")
	)
	(segment
		(start 20.973796 -45.77969)
		(end 17.58442 -42.390314)
		(width 0.11938)
		(layer "B.Cu")
		(net "PCA9546_I2C_SDA")
	)
	(segment
		(start 17.58442 -42.390314)
		(end 17.58442 -41.931082)
		(width 0.11938)
		(layer "B.Cu")
		(net "PCA9546_I2C_SDA")
	)
	(segment
		(start 121.361962 -18.577306)
		(end 121.528586 -18.410682)
		(width 0.11938)
		(layer "B.Cu")
		(net "PCA9546_I2C_SDA")
	)
	(segment
		(start 122.428 -19.812)
		(end 121.361962 -18.745962)
		(width 0.11938)
		(layer "B.Cu")
		(net "PCA9546_I2C_SDA")
	)
	(segment
		(start 88.138 -22.479)
		(end 87.757 -22.098)
		(width 0.11938)
		(layer "B.Cu")
		(net "PCA9546_I2C_SDA")
	)
	(segment
		(start 122.428 -21.209)
		(end 122.428 -19.812)
		(width 0.11938)
		(layer "B.Cu")
		(net "PCA9546_I2C_SDA")
	)
	(segment
		(start 120.030748 -17.246092)
		(end 119.862092 -17.246092)
		(width 0.11938)
		(layer "B.Cu")
		(net "PCA9546_I2C_SDA")
	)
	(segment
		(start 119.862092 -17.246092)
		(end 119.634 -17.018)
		(width 0.11938)
		(layer "B.Cu")
		(net "PCA9546_I2C_SDA")
	)
	(segment
		(start 120.749568 -18.133568)
		(end 120.474486 -17.858486)
		(width 0.11938)
		(layer "B.Cu")
		(net "PCA9546_I2C_SDA")
	)
	(segment
		(start 17.58442 -41.931082)
		(end 17.1704 -41.517062)
		(width 0.11938)
		(layer "B.Cu")
		(net "PCA9546_I2C_SDA")
	)
	(segment
		(start 121.253504 -17.966944)
		(end 121.084848 -17.966944)
		(width 0.11938)
		(layer "B.Cu")
		(net "PCA9546_I2C_SDA")
	)
	(segment
		(start 120.59158 -17.572736)
		(end 120.59158 -17.40408)
		(width 0.11938)
		(layer "B.Cu")
		(net "PCA9546_I2C_SDA")
	)
	(segment
		(start 22.4155 -45.0215)
		(end 21.65731 -45.77969)
		(width 0.11938)
		(layer "B.Cu")
		(net "PCA9546_I2C_SDA")
	)
	(segment
		(start 121.084848 -17.966944)
		(end 120.918224 -18.133568)
		(width 0.11938)
		(layer "B.Cu")
		(net "PCA9546_I2C_SDA")
	)
	(segment
		(start 120.474486 -17.858486)
		(end 120.474486 -17.68983)
		(width 0.11938)
		(layer "B.Cu")
		(net "PCA9546_I2C_SDA")
	)
	(segment
		(start 121.528586 -18.410682)
		(end 121.528586 -18.242026)
		(width 0.11938)
		(layer "B.Cu")
		(net "PCA9546_I2C_SDA")
	)
	(segment
		(start 90.17 -22.479)
		(end 88.138 -22.479)
		(width 0.11938)
		(layer "B.Cu")
		(net "PCA9546_I2C_SDA")
	)
	(segment
		(start 120.147842 -17.128998)
		(end 120.030748 -17.246092)
		(width 0.11938)
		(layer "B.Cu")
		(net "PCA9546_I2C_SDA")
	)
	(segment
		(start 120.474486 -17.68983)
		(end 120.59158 -17.572736)
		(width 0.11938)
		(layer "B.Cu")
		(net "PCA9546_I2C_SDA")
	)
	(segment
		(start 120.918224 -18.133568)
		(end 120.749568 -18.133568)
		(width 0.11938)
		(layer "B.Cu")
		(net "PCA9546_I2C_SDA")
	)
	(segment
		(start 21.65731 -45.77969)
		(end 20.973796 -45.77969)
		(width 0.11938)
		(layer "B.Cu")
		(net "PCA9546_I2C_SDA")
	)
	(segment
		(start 95.631 -17.018)
		(end 90.17 -22.479)
		(width 0.11938)
		(layer "B.Cu")
		(net "PCA9546_I2C_SDA")
	)
	(segment
		(start 120.316498 -17.128998)
		(end 120.147842 -17.128998)
		(width 0.11938)
		(layer "B.Cu")
		(net "PCA9546_I2C_SDA")
	)
	(segment
		(start 119.634 -17.018)
		(end 95.631 -17.018)
		(width 0.11938)
		(layer "B.Cu")
		(net "PCA9546_I2C_SDA")
	)
	(segment
		(start 24.003 -24.257)
		(end 23.4315 -24.8285)
		(width 0.127)
		(layer "In2.Cu")
		(net "PCA9546_I2C_SDA")
	)
	(segment
		(start 32.385 -31.496)
		(end 25.146 -24.257)
		(width 0.127)
		(layer "In2.Cu")
		(net "PCA9546_I2C_SDA")
	)
	(segment
		(start 25.146 -24.257)
		(end 24.003 -24.257)
		(width 0.127)
		(layer "In2.Cu")
		(net "PCA9546_I2C_SDA")
	)
	(segment
		(start 87.757 -22.098)
		(end 87.1855 -21.5265)
		(width 0.127)
		(layer "In2.Cu")
		(net "PCA9546_I2C_SDA")
	)
	(segment
		(start 87.1855 -21.5265)
		(end 84.4931 -21.5265)
		(width 0.127)
		(layer "In2.Cu")
		(net "PCA9546_I2C_SDA")
	)
	(segment
		(start 84.4931 -21.5265)
		(end 74.5236 -31.496)
		(width 0.127)
		(layer "In2.Cu")
		(net "PCA9546_I2C_SDA")
	)
	(segment
		(start 74.5236 -31.496)
		(end 32.385 -31.496)
		(width 0.127)
		(layer "In2.Cu")
		(net "PCA9546_I2C_SDA")
	)
	(segment
		(start 24.257 -40.853106)
		(end 24.57069 -41.166796)
		(width 0.11938)
		(layer "F.Cu")
		(net "PCA9546_I2C_SCL")
	)
	(segment
		(start 24.57069 -41.166796)
		(end 24.57069 -41.637204)
		(width 0.11938)
		(layer "F.Cu")
		(net "PCA9546_I2C_SCL")
	)
	(segment
		(start 121.767092 -19.456908)
		(end 124.0917 -19.456908)
		(width 0.11938)
		(layer "F.Cu")
		(net "PCA9546_I2C_SCL")
	)
	(segment
		(start 25.146 -25.527)
		(end 25.146 -38.989)
		(width 0.11938)
		(layer "F.Cu")
		(net "PCA9546_I2C_SCL")
	)
	(segment
		(start 24.13 -42.077894)
		(end 24.13 -45.085)
		(width 0.11938)
		(layer "F.Cu")
		(net "PCA9546_I2C_SCL")
	)
	(segment
		(start 24.511 -24.892)
		(end 25.146 -25.527)
		(width 0.11938)
		(layer "F.Cu")
		(net "PCA9546_I2C_SCL")
	)
	(segment
		(start 24.257 -39.878)
		(end 24.257 -40.853106)
		(width 0.11938)
		(layer "F.Cu")
		(net "PCA9546_I2C_SCL")
	)
	(segment
		(start 121.412 -19.812)
		(end 121.767092 -19.456908)
		(width 0.11938)
		(layer "F.Cu")
		(net "PCA9546_I2C_SCL")
	)
	(segment
		(start 24.13 -45.085)
		(end 23.114 -46.101)
		(width 0.11938)
		(layer "F.Cu")
		(net "PCA9546_I2C_SCL")
	)
	(segment
		(start 25.146 -38.989)
		(end 24.257 -39.878)
		(width 0.11938)
		(layer "F.Cu")
		(net "PCA9546_I2C_SCL")
	)
	(segment
		(start 24.57069 -41.637204)
		(end 24.13 -42.077894)
		(width 0.11938)
		(layer "F.Cu")
		(net "PCA9546_I2C_SCL")
	)
	(via
		(at 24.511 -24.892)
		(size 0.508)
		(drill 0.254)
		(layers "F.Cu" "B.Cu")
		(net "PCA9546_I2C_SCL")
	)
	(via
		(at 23.114 -46.101)
		(size 0.508)
		(drill 0.254)
		(layers "F.Cu" "B.Cu")
		(net "PCA9546_I2C_SCL")
	)
	(via
		(at 121.412 -19.812)
		(size 0.508)
		(drill 0.254)
		(layers "F.Cu" "B.Cu")
		(net "PCA9546_I2C_SCL")
	)
	(via
		(at 86.487 -22.098)
		(size 0.508)
		(drill 0.254)
		(layers "F.Cu" "B.Cu")
		(net "PCA9546_I2C_SCL")
	)
	(segment
		(start 17.145 -42.799)
		(end 17.145 -42.1132)
		(width 0.11938)
		(layer "B.Cu")
		(net "PCA9546_I2C_SCL")
	)
	(segment
		(start 16.256 -41.2242)
		(end 16.256 -40.1066)
		(width 0.11938)
		(layer "B.Cu")
		(net "PCA9546_I2C_SCL")
	)
	(segment
		(start 95.757746 -17.526)
		(end 90.169746 -23.114)
		(width 0.11938)
		(layer "B.Cu")
		(net "PCA9546_I2C_SCL")
	)
	(segment
		(start 90.169746 -23.114)
		(end 87.503 -23.114)
		(width 0.11938)
		(layer "B.Cu")
		(net "PCA9546_I2C_SCL")
	)
	(segment
		(start 20.828 -46.482)
		(end 17.145 -42.799)
		(width 0.11938)
		(layer "B.Cu")
		(net "PCA9546_I2C_SCL")
	)
	(segment
		(start 121.412 -19.812)
		(end 119.126 -17.526)
		(width 0.11938)
		(layer "B.Cu")
		(net "PCA9546_I2C_SCL")
	)
	(segment
		(start 22.733 -46.482)
		(end 20.828 -46.482)
		(width 0.11938)
		(layer "B.Cu")
		(net "PCA9546_I2C_SCL")
	)
	(segment
		(start 23.114 -46.101)
		(end 22.733 -46.482)
		(width 0.11938)
		(layer "B.Cu")
		(net "PCA9546_I2C_SCL")
	)
	(segment
		(start 16.256 -40.1066)
		(end 17.145 -39.2176)
		(width 0.11938)
		(layer "B.Cu")
		(net "PCA9546_I2C_SCL")
	)
	(segment
		(start 87.503 -23.114)
		(end 86.487 -22.098)
		(width 0.11938)
		(layer "B.Cu")
		(net "PCA9546_I2C_SCL")
	)
	(segment
		(start 119.126 -17.526)
		(end 95.757746 -17.526)
		(width 0.11938)
		(layer "B.Cu")
		(net "PCA9546_I2C_SCL")
	)
	(segment
		(start 17.145 -42.1132)
		(end 16.256 -41.2242)
		(width 0.11938)
		(layer "B.Cu")
		(net "PCA9546_I2C_SCL")
	)
	(segment
		(start 32.131254 -32.004)
		(end 74.737976 -32.004)
		(width 0.127)
		(layer "In2.Cu")
		(net "PCA9546_I2C_SCL")
	)
	(segment
		(start 84.643976 -22.098)
		(end 86.487 -22.098)
		(width 0.127)
		(layer "In2.Cu")
		(net "PCA9546_I2C_SCL")
	)
	(segment
		(start 25.146254 -25.019)
		(end 32.131254 -32.004)
		(width 0.127)
		(layer "In2.Cu")
		(net "PCA9546_I2C_SCL")
	)
	(segment
		(start 24.638 -25.019)
		(end 25.146254 -25.019)
		(width 0.127)
		(layer "In2.Cu")
		(net "PCA9546_I2C_SCL")
	)
	(segment
		(start 24.511 -24.892)
		(end 24.638 -25.019)
		(width 0.127)
		(layer "In2.Cu")
		(net "PCA9546_I2C_SCL")
	)
	(segment
		(start 74.737976 -32.004)
		(end 84.643976 -22.098)
		(width 0.127)
		(layer "In2.Cu")
		(net "PCA9546_I2C_SCL")
	)
	(segment
		(start 91.732862 -48.05426)
		(end 92.314014 -48.05426)
		(width 0.14478)
		(layer "F.Cu")
		(net "MAC_USB_DP")
	)
	(segment
		(start 91.7321 -48.053498)
		(end 91.732862 -48.05426)
		(width 0.14478)
		(layer "F.Cu")
		(net "MAC_USB_DP")
	)
	(segment
		(start 111.847122 -46.823122)
		(end 112.346994 -47.322994)
		(width 0.11938)
		(layer "F.Cu")
		(net "MAC_USB_DP")
	)
	(segment
		(start 90.984578 -48.053498)
		(end 91.7321 -48.053498)
		(width 0.14478)
		(layer "F.Cu")
		(net "MAC_USB_DP")
	)
	(via
		(at 92.735654 -47.843186)
		(size 0.4572)
		(drill 0.2032)
		(layers "F.Cu" "B.Cu")
		(net "MAC_USB_DP")
	)
	(arc
		(start 92.378276 -48.057562)
		(mid 92.57018 -47.9724)
		(end 92.735654 -47.843186)
		(width 0.14478)
		(layer "F.Cu")
		(net "MAC_USB_DP")
	)
	(arc
		(start 92.314014 -48.05426)
		(mid 92.346189 -48.055048)
		(end 92.378276 -48.057562)
		(width 0.14478)
		(layer "F.Cu")
		(net "MAC_USB_DP")
	)
	(segment
		(start 91.588844 -48.297846)
		(end 91.572842 -48.297846)
		(width 0.14478)
		(layer "B.Cu")
		(net "MAC_USB_DP")
	)
	(segment
		(start 92.735654 -47.843186)
		(end 92.666058 -47.912782)
		(width 0.14478)
		(layer "B.Cu")
		(net "MAC_USB_DP")
	)
	(segment
		(start 90.925396 -48.036988)
		(end 90.805 -47.916846)
		(width 0.14478)
		(layer "B.Cu")
		(net "MAC_USB_DP")
	)
	(segment
		(start 112.84712 -46.823122)
		(end 112.846866 -46.823122)
		(width 0.14478)
		(layer "B.Cu")
		(net "MAC_USB_DP")
	)
	(segment
		(start 112.846866 -46.823122)
		(end 112.346994 -47.322994)
		(width 0.14478)
		(layer "B.Cu")
		(net "MAC_USB_DP")
	)
	(arc
		(start 91.943428 -48.148494)
		(mid 91.902815 -48.171779)
		(end 91.864942 -48.199294)
		(width 0.14478)
		(layer "B.Cu")
		(net "MAC_USB_DP")
	)
	(arc
		(start 92.666058 -47.912782)
		(mid 92.499761 -48.023898)
		(end 92.3036 -48.062896)
		(width 0.14478)
		(layer "B.Cu")
		(net "MAC_USB_DP")
	)
	(arc
		(start 92.3036 -48.062896)
		(mid 92.118497 -48.084588)
		(end 91.943428 -48.148494)
		(width 0.14478)
		(layer "B.Cu")
		(net "MAC_USB_DP")
	)
	(arc
		(start 91.483688 -48.30064)
		(mid 91.181634 -48.217326)
		(end 90.925396 -48.036988)
		(width 0.14478)
		(layer "B.Cu")
		(net "MAC_USB_DP")
	)
	(arc
		(start 91.864942 -48.199294)
		(mid 91.735394 -48.272363)
		(end 91.588844 -48.297846)
		(width 0.14478)
		(layer "B.Cu")
		(net "MAC_USB_DP")
	)
	(arc
		(start 91.572842 -48.297846)
		(mid 91.528241 -48.298491)
		(end 91.483688 -48.30064)
		(width 0.14478)
		(layer "B.Cu")
		(net "MAC_USB_DP")
	)
	(segment
		(start 97.952052 -44.473368)
		(end 97.952052 -44.473622)
		(width 0.15748)
		(layer "In7.Cu")
		(net "MAC_USB_DP")
	)
	(segment
		(start 93.153992 -46.017688)
		(end 92.821252 -46.350428)
		(width 0.15748)
		(layer "In7.Cu")
		(net "MAC_USB_DP")
	)
	(segment
		(start 100.154232 -44.476162)
		(end 100.154232 -44.475908)
		(width 0.15748)
		(layer "In7.Cu")
		(net "MAC_USB_DP")
	)
	(segment
		(start 109.251496 -44.479718)
		(end 109.251496 -44.479972)
		(width 0.15748)
		(layer "In7.Cu")
		(net "MAC_USB_DP")
	)
	(segment
		(start 111.94542 -44.32046)
		(end 111.764826 -44.32046)
		(width 0.1143)
		(layer "In7.Cu")
		(net "MAC_USB_DP")
	)
	(segment
		(start 109.162088 -44.56938)
		(end 108.710984 -44.56938)
		(width 0.15748)
		(layer "In7.Cu")
		(net "MAC_USB_DP")
	)
	(segment
		(start 112.346994 -47.322994)
		(end 112.63757 -47.322994)
		(width 0.1143)
		(layer "In7.Cu")
		(net "MAC_USB_DP")
	)
	(segment
		(start 110.511336 -44.479718)
		(end 110.511336 -44.479972)
		(width 0.15748)
		(layer "In7.Cu")
		(net "MAC_USB_DP")
	)
	(segment
		(start 111.619284 -44.39031)
		(end 110.600744 -44.39031)
		(width 0.15748)
		(layer "In7.Cu")
		(net "MAC_USB_DP")
	)
	(segment
		(start 108.621576 -44.479972)
		(end 108.621576 -44.479718)
		(width 0.15748)
		(layer "In7.Cu")
		(net "MAC_USB_DP")
	)
	(segment
		(start 94.04477 -45.013626)
		(end 94.045024 -45.01388)
		(width 0.15748)
		(layer "In7.Cu")
		(net "MAC_USB_DP")
	)
	(segment
		(start 98.581972 -44.473622)
		(end 98.581972 -44.473368)
		(width 0.15748)
		(layer "In7.Cu")
		(net "MAC_USB_DP")
	)
	(segment
		(start 100.698554 -44.56176)
		(end 100.23983 -44.56176)
		(width 0.15748)
		(layer "In7.Cu")
		(net "MAC_USB_DP")
	)
	(segment
		(start 94.2467 -44.69892)
		(end 94.04477 -44.90085)
		(width 0.15748)
		(layer "In7.Cu")
		(net "MAC_USB_DP")
	)
	(segment
		(start 93.599508 -45.459396)
		(end 93.599254 -45.459142)
		(width 0.15748)
		(layer "In7.Cu")
		(net "MAC_USB_DP")
	)
	(segment
		(start 109.792008 -44.39031)
		(end 109.340904 -44.39031)
		(width 0.15748)
		(layer "In7.Cu")
		(net "MAC_USB_DP")
	)
	(segment
		(start 93.486478 -45.459142)
		(end 93.153738 -45.791882)
		(width 0.15748)
		(layer "In7.Cu")
		(net "MAC_USB_DP")
	)
	(segment
		(start 99.128834 -44.55668)
		(end 98.66503 -44.55668)
		(width 0.15748)
		(layer "In7.Cu")
		(net "MAC_USB_DP")
	)
	(segment
		(start 98.498914 -44.39031)
		(end 98.03511 -44.39031)
		(width 0.15748)
		(layer "In7.Cu")
		(net "MAC_USB_DP")
	)
	(segment
		(start 92.011754 -48.084486)
		(end 92.369894 -48.084486)
		(width 0.15748)
		(layer "In7.Cu")
		(net "MAC_USB_DP")
	)
	(segment
		(start 93.153738 -45.904658)
		(end 93.153992 -45.904912)
		(width 0.15748)
		(layer "In7.Cu")
		(net "MAC_USB_DP")
	)
	(segment
		(start 94.045024 -45.126656)
		(end 93.712284 -45.459396)
		(width 0.15748)
		(layer "In7.Cu")
		(net "MAC_USB_DP")
	)
	(segment
		(start 100.068634 -44.39031)
		(end 99.29495 -44.39031)
		(width 0.15748)
		(layer "In7.Cu")
		(net "MAC_USB_DP")
	)
	(segment
		(start 112.75187 -47.208694)
		(end 112.75187 -45.029882)
		(width 0.1143)
		(layer "In7.Cu")
		(net "MAC_USB_DP")
	)
	(segment
		(start 99.211892 -44.473368)
		(end 99.211892 -44.473622)
		(width 0.15748)
		(layer "In7.Cu")
		(net "MAC_USB_DP")
	)
	(segment
		(start 92.595446 -46.350174)
		(end 91.991434 -46.954186)
		(width 0.15748)
		(layer "In7.Cu")
		(net "MAC_USB_DP")
	)
	(segment
		(start 111.647732 -44.39031)
		(end 111.619284 -44.39031)
		(width 0.1143)
		(layer "In7.Cu")
		(net "MAC_USB_DP")
	)
	(segment
		(start 111.684054 -44.353988)
		(end 111.647732 -44.39031)
		(width 0.1143)
		(layer "In7.Cu")
		(net "MAC_USB_DP")
	)
	(segment
		(start 97.322132 -44.473622)
		(end 97.322132 -44.473368)
		(width 0.15748)
		(layer "In7.Cu")
		(net "MAC_USB_DP")
	)
	(segment
		(start 110.421928 -44.56938)
		(end 109.970824 -44.56938)
		(width 0.15748)
		(layer "In7.Cu")
		(net "MAC_USB_DP")
	)
	(segment
		(start 97.868994 -44.55668)
		(end 97.40519 -44.55668)
		(width 0.15748)
		(layer "In7.Cu")
		(net "MAC_USB_DP")
	)
	(segment
		(start 109.881416 -44.479972)
		(end 109.881416 -44.479718)
		(width 0.15748)
		(layer "In7.Cu")
		(net "MAC_USB_DP")
	)
	(segment
		(start 112.639856 -44.760134)
		(end 112.380776 -44.501054)
		(width 0.1143)
		(layer "In7.Cu")
		(net "MAC_USB_DP")
	)
	(segment
		(start 100.784152 -44.475908)
		(end 100.784152 -44.476162)
		(width 0.15748)
		(layer "In7.Cu")
		(net "MAC_USB_DP")
	)
	(segment
		(start 91.854274 -47.28464)
		(end 91.854274 -47.927006)
		(width 0.15748)
		(layer "In7.Cu")
		(net "MAC_USB_DP")
	)
	(segment
		(start 108.532168 -44.39031)
		(end 100.86975 -44.39031)
		(width 0.15748)
		(layer "In7.Cu")
		(net "MAC_USB_DP")
	)
	(segment
		(start 97.239074 -44.39031)
		(end 94.991682 -44.39031)
		(width 0.15748)
		(layer "In7.Cu")
		(net "MAC_USB_DP")
	)
	(segment
		(start 92.708476 -46.350428)
		(end 92.708222 -46.350174)
		(width 0.15748)
		(layer "In7.Cu")
		(net "MAC_USB_DP")
	)
	(segment
		(start 92.582238 -47.996602)
		(end 92.735654 -47.843186)
		(width 0.15748)
		(layer "In7.Cu")
		(net "MAC_USB_DP")
	)
	(arc
		(start 98.581972 -44.473368)
		(mid 98.557645 -44.414637)
		(end 98.498914 -44.39031)
		(width 0.15748)
		(layer "In7.Cu")
		(net "MAC_USB_DP")
	)
	(arc
		(start 94.991682 -44.39031)
		(mid 94.58849 -44.47051)
		(end 94.2467 -44.69892)
		(width 0.15748)
		(layer "In7.Cu")
		(net "MAC_USB_DP")
	)
	(arc
		(start 93.153738 -45.791882)
		(mid 93.130381 -45.84827)
		(end 93.153738 -45.904658)
		(width 0.15748)
		(layer "In7.Cu")
		(net "MAC_USB_DP")
	)
	(arc
		(start 93.599254 -45.459142)
		(mid 93.542866 -45.435785)
		(end 93.486478 -45.459142)
		(width 0.15748)
		(layer "In7.Cu")
		(net "MAC_USB_DP")
	)
	(arc
		(start 97.40519 -44.55668)
		(mid 97.346459 -44.532353)
		(end 97.322132 -44.473622)
		(width 0.15748)
		(layer "In7.Cu")
		(net "MAC_USB_DP")
	)
	(arc
		(start 91.854274 -47.927006)
		(mid 91.900399 -48.038361)
		(end 92.011754 -48.084486)
		(width 0.15748)
		(layer "In7.Cu")
		(net "MAC_USB_DP")
	)
	(arc
		(start 100.86975 -44.39031)
		(mid 100.809223 -44.415381)
		(end 100.784152 -44.475908)
		(width 0.15748)
		(layer "In7.Cu")
		(net "MAC_USB_DP")
	)
	(arc
		(start 110.600744 -44.39031)
		(mid 110.537523 -44.416497)
		(end 110.511336 -44.479718)
		(width 0.15748)
		(layer "In7.Cu")
		(net "MAC_USB_DP")
	)
	(arc
		(start 98.03511 -44.39031)
		(mid 97.976379 -44.414637)
		(end 97.952052 -44.473368)
		(width 0.15748)
		(layer "In7.Cu")
		(net "MAC_USB_DP")
	)
	(arc
		(start 112.63757 -47.322994)
		(mid 112.718392 -47.289516)
		(end 112.75187 -47.208694)
		(width 0.1143)
		(layer "In7.Cu")
		(net "MAC_USB_DP")
	)
	(arc
		(start 99.211892 -44.473622)
		(mid 99.187565 -44.532353)
		(end 99.128834 -44.55668)
		(width 0.15748)
		(layer "In7.Cu")
		(net "MAC_USB_DP")
	)
	(arc
		(start 112.380776 -44.501054)
		(mid 112.181061 -44.367483)
		(end 111.94542 -44.32046)
		(width 0.1143)
		(layer "In7.Cu")
		(net "MAC_USB_DP")
	)
	(arc
		(start 109.340904 -44.39031)
		(mid 109.277683 -44.416497)
		(end 109.251496 -44.479718)
		(width 0.15748)
		(layer "In7.Cu")
		(net "MAC_USB_DP")
	)
	(arc
		(start 112.75187 -45.029882)
		(mid 112.722697 -44.88387)
		(end 112.639856 -44.760134)
		(width 0.1143)
		(layer "In7.Cu")
		(net "MAC_USB_DP")
	)
	(arc
		(start 109.881416 -44.479718)
		(mid 109.855229 -44.416497)
		(end 109.792008 -44.39031)
		(width 0.15748)
		(layer "In7.Cu")
		(net "MAC_USB_DP")
	)
	(arc
		(start 100.154232 -44.475908)
		(mid 100.129161 -44.415381)
		(end 100.068634 -44.39031)
		(width 0.15748)
		(layer "In7.Cu")
		(net "MAC_USB_DP")
	)
	(arc
		(start 110.511336 -44.479972)
		(mid 110.485149 -44.543193)
		(end 110.421928 -44.56938)
		(width 0.15748)
		(layer "In7.Cu")
		(net "MAC_USB_DP")
	)
	(arc
		(start 109.970824 -44.56938)
		(mid 109.907603 -44.543193)
		(end 109.881416 -44.479972)
		(width 0.15748)
		(layer "In7.Cu")
		(net "MAC_USB_DP")
	)
	(arc
		(start 91.991434 -46.954186)
		(mid 91.889992 -47.10577)
		(end 91.854274 -47.28464)
		(width 0.15748)
		(layer "In7.Cu")
		(net "MAC_USB_DP")
	)
	(arc
		(start 94.045024 -45.01388)
		(mid 94.068381 -45.070268)
		(end 94.045024 -45.126656)
		(width 0.15748)
		(layer "In7.Cu")
		(net "MAC_USB_DP")
	)
	(arc
		(start 97.322132 -44.473368)
		(mid 97.297805 -44.414637)
		(end 97.239074 -44.39031)
		(width 0.15748)
		(layer "In7.Cu")
		(net "MAC_USB_DP")
	)
	(arc
		(start 92.369894 -48.084486)
		(mid 92.484801 -48.061648)
		(end 92.582238 -47.996602)
		(width 0.15748)
		(layer "In7.Cu")
		(net "MAC_USB_DP")
	)
	(arc
		(start 111.764826 -44.32046)
		(mid 111.7211 -44.329176)
		(end 111.684054 -44.353988)
		(width 0.1143)
		(layer "In7.Cu")
		(net "MAC_USB_DP")
	)
	(arc
		(start 98.66503 -44.55668)
		(mid 98.606299 -44.532353)
		(end 98.581972 -44.473622)
		(width 0.15748)
		(layer "In7.Cu")
		(net "MAC_USB_DP")
	)
	(arc
		(start 92.821252 -46.350428)
		(mid 92.764864 -46.373785)
		(end 92.708476 -46.350428)
		(width 0.15748)
		(layer "In7.Cu")
		(net "MAC_USB_DP")
	)
	(arc
		(start 97.952052 -44.473622)
		(mid 97.927725 -44.532353)
		(end 97.868994 -44.55668)
		(width 0.15748)
		(layer "In7.Cu")
		(net "MAC_USB_DP")
	)
	(arc
		(start 93.712284 -45.459396)
		(mid 93.655896 -45.482753)
		(end 93.599508 -45.459396)
		(width 0.15748)
		(layer "In7.Cu")
		(net "MAC_USB_DP")
	)
	(arc
		(start 92.708222 -46.350174)
		(mid 92.651834 -46.326817)
		(end 92.595446 -46.350174)
		(width 0.15748)
		(layer "In7.Cu")
		(net "MAC_USB_DP")
	)
	(arc
		(start 93.153992 -45.904912)
		(mid 93.177349 -45.9613)
		(end 93.153992 -46.017688)
		(width 0.15748)
		(layer "In7.Cu")
		(net "MAC_USB_DP")
	)
	(arc
		(start 108.710984 -44.56938)
		(mid 108.647763 -44.543193)
		(end 108.621576 -44.479972)
		(width 0.15748)
		(layer "In7.Cu")
		(net "MAC_USB_DP")
	)
	(arc
		(start 94.04477 -44.90085)
		(mid 94.021413 -44.957238)
		(end 94.04477 -45.013626)
		(width 0.15748)
		(layer "In7.Cu")
		(net "MAC_USB_DP")
	)
	(arc
		(start 99.29495 -44.39031)
		(mid 99.236219 -44.414637)
		(end 99.211892 -44.473368)
		(width 0.15748)
		(layer "In7.Cu")
		(net "MAC_USB_DP")
	)
	(arc
		(start 100.23983 -44.56176)
		(mid 100.179303 -44.536689)
		(end 100.154232 -44.476162)
		(width 0.15748)
		(layer "In7.Cu")
		(net "MAC_USB_DP")
	)
	(arc
		(start 109.251496 -44.479972)
		(mid 109.225309 -44.543193)
		(end 109.162088 -44.56938)
		(width 0.15748)
		(layer "In7.Cu")
		(net "MAC_USB_DP")
	)
	(arc
		(start 108.621576 -44.479718)
		(mid 108.595389 -44.416497)
		(end 108.532168 -44.39031)
		(width 0.15748)
		(layer "In7.Cu")
		(net "MAC_USB_DP")
	)
	(arc
		(start 100.784152 -44.476162)
		(mid 100.759081 -44.536689)
		(end 100.698554 -44.56176)
		(width 0.15748)
		(layer "In7.Cu")
		(net "MAC_USB_DP")
	)
	(segment
		(start 90.984578 -48.453548)
		(end 91.731846 -48.453548)
		(width 0.14478)
		(layer "F.Cu")
		(net "MAC_USB_DM")
	)
	(segment
		(start 91.750134 -48.43526)
		(end 92.314268 -48.43526)
		(width 0.14478)
		(layer "F.Cu")
		(net "MAC_USB_DM")
	)
	(segment
		(start 91.731846 -48.453548)
		(end 91.750134 -48.43526)
		(width 0.14478)
		(layer "F.Cu")
		(net "MAC_USB_DM")
	)
	(segment
		(start 112.84712 -46.823122)
		(end 113.346992 -47.322994)
		(width 0.11938)
		(layer "F.Cu")
		(net "MAC_USB_DM")
	)
	(via
		(at 92.735654 -48.655986)
		(size 0.4572)
		(drill 0.2032)
		(layers "F.Cu" "B.Cu")
		(net "MAC_USB_DM")
	)
	(arc
		(start 92.372434 -48.443134)
		(mid 92.567696 -48.526254)
		(end 92.735654 -48.655986)
		(width 0.14478)
		(layer "F.Cu")
		(net "MAC_USB_DM")
	)
	(arc
		(start 92.314268 -48.43526)
		(mid 92.343619 -48.437211)
		(end 92.372434 -48.443134)
		(width 0.14478)
		(layer "F.Cu")
		(net "MAC_USB_DM")
	)
	(segment
		(start 113.847118 -46.823122)
		(end 113.846864 -46.823122)
		(width 0.14478)
		(layer "B.Cu")
		(net "MAC_USB_DM")
	)
	(segment
		(start 113.846864 -46.823122)
		(end 113.346992 -47.322994)
		(width 0.14478)
		(layer "B.Cu")
		(net "MAC_USB_DM")
	)
	(segment
		(start 91.589098 -48.678846)
		(end 91.572842 -48.678846)
		(width 0.14478)
		(layer "B.Cu")
		(net "MAC_USB_DM")
	)
	(segment
		(start 90.912442 -48.952404)
		(end 90.805 -49.059846)
		(width 0.14478)
		(layer "B.Cu")
		(net "MAC_USB_DM")
	)
	(segment
		(start 92.735654 -48.655986)
		(end 92.666058 -48.58639)
		(width 0.14478)
		(layer "B.Cu")
		(net "MAC_USB_DM")
	)
	(arc
		(start 92.056458 -48.532288)
		(mid 91.834007 -48.641391)
		(end 91.589098 -48.678846)
		(width 0.14478)
		(layer "B.Cu")
		(net "MAC_USB_DM")
	)
	(arc
		(start 91.572842 -48.678846)
		(mid 91.215432 -48.749939)
		(end 90.912442 -48.952404)
		(width 0.14478)
		(layer "B.Cu")
		(net "MAC_USB_DM")
	)
	(arc
		(start 92.666058 -48.58639)
		(mid 92.371095 -48.448712)
		(end 92.056458 -48.532288)
		(width 0.14478)
		(layer "B.Cu")
		(net "MAC_USB_DM")
	)
	(segment
		(start 91.524074 -47.927006)
		(end 91.524074 -47.28464)
		(width 0.15748)
		(layer "In7.Cu")
		(net "MAC_USB_DM")
	)
	(segment
		(start 91.757754 -46.720506)
		(end 94.01302 -44.46524)
		(width 0.15748)
		(layer "In7.Cu")
		(net "MAC_USB_DM")
	)
	(segment
		(start 112.94237 -45.029628)
		(end 112.94237 -47.208694)
		(width 0.1143)
		(layer "In7.Cu")
		(net "MAC_USB_DM")
	)
	(segment
		(start 112.51565 -44.36618)
		(end 112.77473 -44.62526)
		(width 0.1143)
		(layer "In7.Cu")
		(net "MAC_USB_DM")
	)
	(segment
		(start 94.991428 -44.06011)
		(end 111.619284 -44.06011)
		(width 0.15748)
		(layer "In7.Cu")
		(net "MAC_USB_DM")
	)
	(segment
		(start 92.375736 -48.414686)
		(end 92.011754 -48.414686)
		(width 0.15748)
		(layer "In7.Cu")
		(net "MAC_USB_DM")
	)
	(segment
		(start 113.05667 -47.322994)
		(end 113.346992 -47.322994)
		(width 0.1143)
		(layer "In7.Cu")
		(net "MAC_USB_DM")
	)
	(segment
		(start 111.764826 -44.12996)
		(end 111.945674 -44.12996)
		(width 0.1143)
		(layer "In7.Cu")
		(net "MAC_USB_DM")
	)
	(segment
		(start 111.619284 -44.06011)
		(end 111.647732 -44.06011)
		(width 0.1143)
		(layer "In7.Cu")
		(net "MAC_USB_DM")
	)
	(segment
		(start 92.735654 -48.655986)
		(end 92.578428 -48.49876)
		(width 0.15748)
		(layer "In7.Cu")
		(net "MAC_USB_DM")
	)
	(segment
		(start 111.647732 -44.06011)
		(end 111.684054 -44.096432)
		(width 0.1143)
		(layer "In7.Cu")
		(net "MAC_USB_DM")
	)
	(arc
		(start 91.524074 -47.28464)
		(mid 91.584804 -46.97933)
		(end 91.757754 -46.720506)
		(width 0.15748)
		(layer "In7.Cu")
		(net "MAC_USB_DM")
	)
	(arc
		(start 92.011754 -48.414686)
		(mid 91.666912 -48.271848)
		(end 91.524074 -47.927006)
		(width 0.15748)
		(layer "In7.Cu")
		(net "MAC_USB_DM")
	)
	(arc
		(start 94.01302 -44.46524)
		(mid 94.461946 -44.165404)
		(end 94.991428 -44.06011)
		(width 0.15748)
		(layer "In7.Cu")
		(net "MAC_USB_DM")
	)
	(arc
		(start 112.77473 -44.62526)
		(mid 112.898777 -44.810771)
		(end 112.94237 -45.029628)
		(width 0.1143)
		(layer "In7.Cu")
		(net "MAC_USB_DM")
	)
	(arc
		(start 112.94237 -47.208694)
		(mid 112.975848 -47.289516)
		(end 113.05667 -47.322994)
		(width 0.1143)
		(layer "In7.Cu")
		(net "MAC_USB_DM")
	)
	(arc
		(start 111.945674 -44.12996)
		(mid 112.254178 -44.191343)
		(end 112.51565 -44.36618)
		(width 0.1143)
		(layer "In7.Cu")
		(net "MAC_USB_DM")
	)
	(arc
		(start 111.684054 -44.096432)
		(mid 111.721098 -44.121248)
		(end 111.764826 -44.12996)
		(width 0.1143)
		(layer "In7.Cu")
		(net "MAC_USB_DM")
	)
	(arc
		(start 92.578428 -48.49876)
		(mid 92.485447 -48.436539)
		(end 92.375736 -48.414686)
		(width 0.15748)
		(layer "In7.Cu")
		(net "MAC_USB_DM")
	)
	(segment
		(start 75.764136 -44.496736)
		(end 74.354436 -44.496736)
		(width 0.11938)
		(layer "F.Cu")
		(net "MAC_ALARM")
	)
	(segment
		(start 77.851 -43.053)
		(end 79.3496 -43.053)
		(width 0.11938)
		(layer "F.Cu")
		(net "MAC_ALARM")
	)
	(via
		(at 75.764136 -44.496736)
		(size 0.508)
		(drill 0.254)
		(layers "F.Cu" "B.Cu")
		(net "MAC_ALARM")
	)
	(segment
		(start 75.764136 -44.496736)
		(end 76.407264 -44.496736)
		(width 0.11938)
		(layer "B.Cu")
		(net "MAC_ALARM")
	)
	(segment
		(start 76.407264 -44.496736)
		(end 77.851 -43.053)
		(width 0.11938)
		(layer "B.Cu")
		(net "MAC_ALARM")
	)
	(segment
		(start 108.975144 -68.453)
		(end 104.394 -68.453)
		(width 0.11938)
		(layer "F.Cu")
		(net "LM75B_I2C_SDA")
	)
	(segment
		(start 102.743 -77.216)
		(end 102.235 -77.724)
		(width 0.11938)
		(layer "F.Cu")
		(net "LM75B_I2C_SDA")
	)
	(segment
		(start 63.50635 -84.37245)
		(end 69.03085 -84.37245)
		(width 0.11938)
		(layer "F.Cu")
		(net "LM75B_I2C_SDA")
	)
	(segment
		(start 71.6534 -86.995)
		(end 80.137 -86.995)
		(width 0.11938)
		(layer "F.Cu")
		(net "LM75B_I2C_SDA")
	)
	(segment
		(start 116.713 -66.548)
		(end 115.062 -66.548)
		(width 0.11938)
		(layer "F.Cu")
		(net "LM75B_I2C_SDA")
	)
	(segment
		(start 57.47512 -82.423)
		(end 61.5569 -82.423)
		(width 0.11938)
		(layer "F.Cu")
		(net "LM75B_I2C_SDA")
	)
	(segment
		(start 102.235 -77.724)
		(end 102.235 -78.232)
		(width 0.11938)
		(layer "F.Cu")
		(net "LM75B_I2C_SDA")
	)
	(segment
		(start 80.772 -85.471)
		(end 82.36712 -83.87588)
		(width 0.11938)
		(layer "F.Cu")
		(net "LM75B_I2C_SDA")
	)
	(segment
		(start 104.394 -68.453)
		(end 102.743 -70.104)
		(width 0.11938)
		(layer "F.Cu")
		(net "LM75B_I2C_SDA")
	)
	(segment
		(start 115.062 -66.548)
		(end 114.59718 -66.08318)
		(width 0.11938)
		(layer "F.Cu")
		(net "LM75B_I2C_SDA")
	)
	(segment
		(start 150.2156 -28.575)
		(end 150.2156 -27.432)
		(width 0.11938)
		(layer "F.Cu")
		(net "LM75B_I2C_SDA")
	)
	(segment
		(start 150.2156 -28.575)
		(end 148.971 -28.575)
		(width 0.11938)
		(layer "F.Cu")
		(net "LM75B_I2C_SDA")
	)
	(segment
		(start 82.36712 -83.87588)
		(end 83.3501 -83.87588)
		(width 0.11938)
		(layer "F.Cu")
		(net "LM75B_I2C_SDA")
	)
	(segment
		(start 61.5569 -82.423)
		(end 63.50635 -84.37245)
		(width 0.11938)
		(layer "F.Cu")
		(net "LM75B_I2C_SDA")
	)
	(segment
		(start 114.59718 -66.08318)
		(end 111.344964 -66.08318)
		(width 0.11938)
		(layer "F.Cu")
		(net "LM75B_I2C_SDA")
	)
	(segment
		(start 111.344964 -66.08318)
		(end 108.975144 -68.453)
		(width 0.11938)
		(layer "F.Cu")
		(net "LM75B_I2C_SDA")
	)
	(segment
		(start 56.515 -82.423)
		(end 57.47512 -82.423)
		(width 0.11938)
		(layer "F.Cu")
		(net "LM75B_I2C_SDA")
	)
	(segment
		(start 69.03085 -84.37245)
		(end 71.6534 -86.995)
		(width 0.11938)
		(layer "F.Cu")
		(net "LM75B_I2C_SDA")
	)
	(segment
		(start 80.137 -86.995)
		(end 80.772 -86.36)
		(width 0.11938)
		(layer "F.Cu")
		(net "LM75B_I2C_SDA")
	)
	(segment
		(start 80.772 -86.36)
		(end 80.772 -85.471)
		(width 0.11938)
		(layer "F.Cu")
		(net "LM75B_I2C_SDA")
	)
	(segment
		(start 102.743 -70.104)
		(end 102.743 -77.216)
		(width 0.11938)
		(layer "F.Cu")
		(net "LM75B_I2C_SDA")
	)
	(via
		(at 102.235 -78.232)
		(size 0.508)
		(drill 0.254)
		(layers "F.Cu" "B.Cu")
		(net "LM75B_I2C_SDA")
	)
	(via
		(at 56.515 -82.423)
		(size 0.508)
		(drill 0.254)
		(layers "F.Cu" "B.Cu")
		(net "LM75B_I2C_SDA")
	)
	(via
		(at 148.971 -28.575)
		(size 0.508)
		(drill 0.254)
		(layers "F.Cu" "B.Cu")
		(net "LM75B_I2C_SDA")
	)
	(via
		(at 116.713 -66.548)
		(size 0.508)
		(drill 0.254)
		(layers "F.Cu" "B.Cu")
		(net "LM75B_I2C_SDA")
	)
	(via
		(at 15.748 -77.978)
		(size 0.508)
		(drill 0.254)
		(layers "F.Cu" "B.Cu")
		(net "LM75B_I2C_SDA")
	)
	(segment
		(start 42.93616 -72.76084)
		(end 48.24984 -72.76084)
		(width 0.11938)
		(layer "B.Cu")
		(net "LM75B_I2C_SDA")
	)
	(segment
		(start 48.24984 -72.76084)
		(end 50.038 -74.549)
		(width 0.11938)
		(layer "B.Cu")
		(net "LM75B_I2C_SDA")
	)
	(segment
		(start 55.76062 -80.899)
		(end 56.515 -81.65338)
		(width 0.11938)
		(layer "B.Cu")
		(net "LM75B_I2C_SDA")
	)
	(segment
		(start 51.852322 -80.899)
		(end 55.76062 -80.899)
		(width 0.11938)
		(layer "B.Cu")
		(net "LM75B_I2C_SDA")
	)
	(segment
		(start 19.0246 -77.6224)
		(end 19.558 -77.089)
		(width 0.11938)
		(layer "B.Cu")
		(net "LM75B_I2C_SDA")
	)
	(segment
		(start 21.59 -77.978)
		(end 23.241 -77.978)
		(width 0.11938)
		(layer "B.Cu")
		(net "LM75B_I2C_SDA")
	)
	(segment
		(start 16.764 -77.6224)
		(end 19.0246 -77.6224)
		(width 0.11938)
		(layer "B.Cu")
		(net "LM75B_I2C_SDA")
	)
	(segment
		(start 16.764 -77.6224)
		(end 16.4084 -77.978)
		(width 0.11938)
		(layer "B.Cu")
		(net "LM75B_I2C_SDA")
	)
	(segment
		(start 19.558 -77.089)
		(end 20.701 -77.089)
		(width 0.11938)
		(layer "B.Cu")
		(net "LM75B_I2C_SDA")
	)
	(segment
		(start 25.781 -75.438)
		(end 34.417 -75.438)
		(width 0.11938)
		(layer "B.Cu")
		(net "LM75B_I2C_SDA")
	)
	(segment
		(start 50.038 -79.084678)
		(end 51.852322 -80.899)
		(width 0.11938)
		(layer "B.Cu")
		(net "LM75B_I2C_SDA")
	)
	(segment
		(start 20.701 -77.089)
		(end 21.59 -77.978)
		(width 0.11938)
		(layer "B.Cu")
		(net "LM75B_I2C_SDA")
	)
	(segment
		(start 34.417 -75.438)
		(end 35.814 -74.041)
		(width 0.11938)
		(layer "B.Cu")
		(net "LM75B_I2C_SDA")
	)
	(segment
		(start 16.4084 -77.978)
		(end 15.748 -77.978)
		(width 0.11938)
		(layer "B.Cu")
		(net "LM75B_I2C_SDA")
	)
	(segment
		(start 35.814 -74.041)
		(end 41.656 -74.041)
		(width 0.11938)
		(layer "B.Cu")
		(net "LM75B_I2C_SDA")
	)
	(segment
		(start 56.515 -81.65338)
		(end 56.515 -82.423)
		(width 0.11938)
		(layer "B.Cu")
		(net "LM75B_I2C_SDA")
	)
	(segment
		(start 50.038 -74.549)
		(end 50.038 -79.084678)
		(width 0.11938)
		(layer "B.Cu")
		(net "LM75B_I2C_SDA")
	)
	(segment
		(start 23.241 -77.978)
		(end 25.781 -75.438)
		(width 0.11938)
		(layer "B.Cu")
		(net "LM75B_I2C_SDA")
	)
	(segment
		(start 41.656 -74.041)
		(end 42.93616 -72.76084)
		(width 0.11938)
		(layer "B.Cu")
		(net "LM75B_I2C_SDA")
	)
	(segment
		(start 25.4508 -79.2988)
		(end 24.3586 -78.2066)
		(width 0.127)
		(layer "In2.Cu")
		(net "LM75B_I2C_SDA")
	)
	(segment
		(start 68.325746 -86.36)
		(end 59.817 -86.36)
		(width 0.127)
		(layer "In2.Cu")
		(net "LM75B_I2C_SDA")
	)
	(segment
		(start 148.209 -32.46628)
		(end 148.844 -32.46628)
		(width 0.127)
		(layer "In2.Cu")
		(net "LM75B_I2C_SDA")
	)
	(segment
		(start 24.3586 -78.2066)
		(end 21.887434 -78.2066)
		(width 0.127)
		(layer "In2.Cu")
		(net "LM75B_I2C_SDA")
	)
	(segment
		(start 148.971 -31.70428)
		(end 148.844 -31.83128)
		(width 0.127)
		(layer "In2.Cu")
		(net "LM75B_I2C_SDA")
	)
	(segment
		(start 19.8882 -77.6224)
		(end 19.5326 -77.978)
		(width 0.127)
		(layer "In2.Cu")
		(net "LM75B_I2C_SDA")
	)
	(segment
		(start 55.862982 -87.8967)
		(end 53.449982 -87.8967)
		(width 0.127)
		(layer "In2.Cu")
		(net "LM75B_I2C_SDA")
	)
	(segment
		(start 127.762 -50.8)
		(end 124.333 -50.8)
		(width 0.127)
		(layer "In2.Cu")
		(net "LM75B_I2C_SDA")
	)
	(segment
		(start 33.0962 -79.2988)
		(end 25.4508 -79.2988)
		(width 0.127)
		(layer "In2.Cu")
		(net "LM75B_I2C_SDA")
	)
	(segment
		(start 148.844 -30.56128)
		(end 148.209 -30.56128)
		(width 0.127)
		(layer "In2.Cu")
		(net "LM75B_I2C_SDA")
	)
	(segment
		(start 148.209 -31.19628)
		(end 148.844 -31.19628)
		(width 0.127)
		(layer "In2.Cu")
		(net "LM75B_I2C_SDA")
	)
	(segment
		(start 52.306982 -86.7537)
		(end 44.7167 -86.7537)
		(width 0.127)
		(layer "In2.Cu")
		(net "LM75B_I2C_SDA")
	)
	(segment
		(start 148.082 -31.06928)
		(end 148.209 -31.19628)
		(width 0.127)
		(layer "In2.Cu")
		(net "LM75B_I2C_SDA")
	)
	(segment
		(start 133.223 -37.381434)
		(end 133.223 -41.439084)
		(width 0.127)
		(layer "In2.Cu")
		(net "LM75B_I2C_SDA")
	)
	(segment
		(start 148.082 -32.33928)
		(end 148.209 -32.46628)
		(width 0.127)
		(layer "In2.Cu")
		(net "LM75B_I2C_SDA")
	)
	(segment
		(start 148.971 -31.32328)
		(end 148.971 -31.70428)
		(width 0.127)
		(layer "In2.Cu")
		(net "LM75B_I2C_SDA")
	)
	(segment
		(start 101.727 -78.74)
		(end 98.635566 -78.74)
		(width 0.127)
		(layer "In2.Cu")
		(net "LM75B_I2C_SDA")
	)
	(segment
		(start 148.844 -31.19628)
		(end 148.971 -31.32328)
		(width 0.127)
		(layer "In2.Cu")
		(net "LM75B_I2C_SDA")
	)
	(segment
		(start 88.646 -80.137)
		(end 88.138 -80.645)
		(width 0.127)
		(layer "In2.Cu")
		(net "LM75B_I2C_SDA")
	)
	(segment
		(start 36.7538 -83.2358)
		(end 36.7538 -80.771746)
		(width 0.127)
		(layer "In2.Cu")
		(net "LM75B_I2C_SDA")
	)
	(segment
		(start 19.5326 -77.978)
		(end 15.748 -77.978)
		(width 0.127)
		(layer "In2.Cu")
		(net "LM75B_I2C_SDA")
	)
	(segment
		(start 123.19 -53.213)
		(end 122.047 -53.213)
		(width 0.127)
		(layer "In2.Cu")
		(net "LM75B_I2C_SDA")
	)
	(segment
		(start 133.223 -41.439084)
		(end 129.54 -45.122084)
		(width 0.127)
		(layer "In2.Cu")
		(net "LM75B_I2C_SDA")
	)
	(segment
		(start 38.481 -84.963)
		(end 36.7538 -83.2358)
		(width 0.127)
		(layer "In2.Cu")
		(net "LM75B_I2C_SDA")
	)
	(segment
		(start 122.047 -53.213)
		(end 121.666 -53.594)
		(width 0.127)
		(layer "In2.Cu")
		(net "LM75B_I2C_SDA")
	)
	(segment
		(start 119.38 -57.785)
		(end 118.4275 -58.7375)
		(width 0.127)
		(layer "In2.Cu")
		(net "LM75B_I2C_SDA")
	)
	(segment
		(start 42.926 -84.963)
		(end 38.481 -84.963)
		(width 0.127)
		(layer "In2.Cu")
		(net "LM75B_I2C_SDA")
	)
	(segment
		(start 78.613 -80.391)
		(end 77.47 -81.534)
		(width 0.127)
		(layer "In2.Cu")
		(net "LM75B_I2C_SDA")
	)
	(segment
		(start 44.7167 -86.7537)
		(end 42.926 -84.963)
		(width 0.127)
		(layer "In2.Cu")
		(net "LM75B_I2C_SDA")
	)
	(segment
		(start 148.971 -30.43428)
		(end 148.844 -30.56128)
		(width 0.127)
		(layer "In2.Cu")
		(net "LM75B_I2C_SDA")
	)
	(segment
		(start 118.4275 -64.8335)
		(end 116.713 -66.548)
		(width 0.127)
		(layer "In2.Cu")
		(net "LM75B_I2C_SDA")
	)
	(segment
		(start 148.971 -28.575)
		(end 148.971 -30.43428)
		(width 0.127)
		(layer "In2.Cu")
		(net "LM75B_I2C_SDA")
	)
	(segment
		(start 148.971 -32.809434)
		(end 147.574 -34.206434)
		(width 0.127)
		(layer "In2.Cu")
		(net "LM75B_I2C_SDA")
	)
	(segment
		(start 147.574 -34.206434)
		(end 141.605 -34.206434)
		(width 0.127)
		(layer "In2.Cu")
		(net "LM75B_I2C_SDA")
	)
	(segment
		(start 140.251434 -35.56)
		(end 135.044434 -35.56)
		(width 0.127)
		(layer "In2.Cu")
		(net "LM75B_I2C_SDA")
	)
	(segment
		(start 21.887434 -78.2066)
		(end 21.303234 -77.6224)
		(width 0.127)
		(layer "In2.Cu")
		(net "LM75B_I2C_SDA")
	)
	(segment
		(start 36.7538 -80.771746)
		(end 34.595054 -78.613)
		(width 0.127)
		(layer "In2.Cu")
		(net "LM75B_I2C_SDA")
	)
	(segment
		(start 85.09 -80.645)
		(end 84.836 -80.391)
		(width 0.127)
		(layer "In2.Cu")
		(net "LM75B_I2C_SDA")
	)
	(segment
		(start 53.449982 -87.8967)
		(end 52.306982 -86.7537)
		(width 0.127)
		(layer "In2.Cu")
		(net "LM75B_I2C_SDA")
	)
	(segment
		(start 59.817 -86.36)
		(end 58.928 -87.249)
		(width 0.127)
		(layer "In2.Cu")
		(net "LM75B_I2C_SDA")
	)
	(segment
		(start 148.082 -30.68828)
		(end 148.082 -31.06928)
		(width 0.127)
		(layer "In2.Cu")
		(net "LM75B_I2C_SDA")
	)
	(segment
		(start 141.605 -34.206434)
		(end 140.251434 -35.56)
		(width 0.127)
		(layer "In2.Cu")
		(net "LM75B_I2C_SDA")
	)
	(segment
		(start 98.635566 -78.74)
		(end 97.238566 -80.137)
		(width 0.127)
		(layer "In2.Cu")
		(net "LM75B_I2C_SDA")
	)
	(segment
		(start 118.4275 -58.7375)
		(end 118.4275 -64.8335)
		(width 0.127)
		(layer "In2.Cu")
		(net "LM75B_I2C_SDA")
	)
	(segment
		(start 97.238566 -80.137)
		(end 88.646 -80.137)
		(width 0.127)
		(layer "In2.Cu")
		(net "LM75B_I2C_SDA")
	)
	(segment
		(start 77.47 -81.534)
		(end 73.151746 -81.534)
		(width 0.127)
		(layer "In2.Cu")
		(net "LM75B_I2C_SDA")
	)
	(segment
		(start 129.54 -45.122084)
		(end 129.54 -49.022)
		(width 0.127)
		(layer "In2.Cu")
		(net "LM75B_I2C_SDA")
	)
	(segment
		(start 121.666 -54.356)
		(end 121.9835 -54.6735)
		(width 0.127)
		(layer "In2.Cu")
		(net "LM75B_I2C_SDA")
	)
	(segment
		(start 73.151746 -81.534)
		(end 68.325746 -86.36)
		(width 0.127)
		(layer "In2.Cu")
		(net "LM75B_I2C_SDA")
	)
	(segment
		(start 84.836 -80.391)
		(end 78.613 -80.391)
		(width 0.127)
		(layer "In2.Cu")
		(net "LM75B_I2C_SDA")
	)
	(segment
		(start 148.971 -32.59328)
		(end 148.971 -32.809434)
		(width 0.127)
		(layer "In2.Cu")
		(net "LM75B_I2C_SDA")
	)
	(segment
		(start 129.54 -49.022)
		(end 127.762 -50.8)
		(width 0.127)
		(layer "In2.Cu")
		(net "LM75B_I2C_SDA")
	)
	(segment
		(start 124.333 -50.8)
		(end 123.952 -51.181)
		(width 0.127)
		(layer "In2.Cu")
		(net "LM75B_I2C_SDA")
	)
	(segment
		(start 123.952 -51.181)
		(end 123.952 -52.451)
		(width 0.127)
		(layer "In2.Cu")
		(net "LM75B_I2C_SDA")
	)
	(segment
		(start 56.510682 -87.249)
		(end 55.862982 -87.8967)
		(width 0.127)
		(layer "In2.Cu")
		(net "LM75B_I2C_SDA")
	)
	(segment
		(start 148.209 -30.56128)
		(end 148.082 -30.68828)
		(width 0.127)
		(layer "In2.Cu")
		(net "LM75B_I2C_SDA")
	)
	(segment
		(start 148.209 -31.83128)
		(end 148.082 -31.95828)
		(width 0.127)
		(layer "In2.Cu")
		(net "LM75B_I2C_SDA")
	)
	(segment
		(start 148.082 -31.95828)
		(end 148.082 -32.33928)
		(width 0.127)
		(layer "In2.Cu")
		(net "LM75B_I2C_SDA")
	)
	(segment
		(start 58.928 -87.249)
		(end 56.510682 -87.249)
		(width 0.127)
		(layer "In2.Cu")
		(net "LM75B_I2C_SDA")
	)
	(segment
		(start 88.138 -80.645)
		(end 85.09 -80.645)
		(width 0.127)
		(layer "In2.Cu")
		(net "LM75B_I2C_SDA")
	)
	(segment
		(start 121.9835 -54.6735)
		(end 121.9835 -57.340246)
		(width 0.127)
		(layer "In2.Cu")
		(net "LM75B_I2C_SDA")
	)
	(segment
		(start 21.303234 -77.6224)
		(end 19.8882 -77.6224)
		(width 0.127)
		(layer "In2.Cu")
		(net "LM75B_I2C_SDA")
	)
	(segment
		(start 102.235 -78.232)
		(end 101.727 -78.74)
		(width 0.127)
		(layer "In2.Cu")
		(net "LM75B_I2C_SDA")
	)
	(segment
		(start 135.044434 -35.56)
		(end 133.223 -37.381434)
		(width 0.127)
		(layer "In2.Cu")
		(net "LM75B_I2C_SDA")
	)
	(segment
		(start 121.538746 -57.785)
		(end 119.38 -57.785)
		(width 0.127)
		(layer "In2.Cu")
		(net "LM75B_I2C_SDA")
	)
	(segment
		(start 121.666 -53.594)
		(end 121.666 -54.356)
		(width 0.127)
		(layer "In2.Cu")
		(net "LM75B_I2C_SDA")
	)
	(segment
		(start 33.782 -78.613)
		(end 33.0962 -79.2988)
		(width 0.127)
		(layer "In2.Cu")
		(net "LM75B_I2C_SDA")
	)
	(segment
		(start 148.844 -32.46628)
		(end 148.971 -32.59328)
		(width 0.127)
		(layer "In2.Cu")
		(net "LM75B_I2C_SDA")
	)
	(segment
		(start 34.595054 -78.613)
		(end 33.782 -78.613)
		(width 0.127)
		(layer "In2.Cu")
		(net "LM75B_I2C_SDA")
	)
	(segment
		(start 148.844 -31.83128)
		(end 148.209 -31.83128)
		(width 0.127)
		(layer "In2.Cu")
		(net "LM75B_I2C_SDA")
	)
	(segment
		(start 123.952 -52.451)
		(end 123.19 -53.213)
		(width 0.127)
		(layer "In2.Cu")
		(net "LM75B_I2C_SDA")
	)
	(segment
		(start 121.9835 -57.340246)
		(end 121.538746 -57.785)
		(width 0.127)
		(layer "In2.Cu")
		(net "LM75B_I2C_SDA")
	)
	(segment
		(start 149.352 -26.797)
		(end 151.16302 -26.797)
		(width 0.11938)
		(layer "F.Cu")
		(net "LM75B_I2C_SCL")
	)
	(segment
		(start 152.97912 -26.86812)
		(end 152.146 -26.035)
		(width 0.11938)
		(layer "F.Cu")
		(net "LM75B_I2C_SCL")
	)
	(segment
		(start 114.934746 -65.659)
		(end 114.807746 -65.532)
		(width 0.11938)
		(layer "F.Cu")
		(net "LM75B_I2C_SCL")
	)
	(segment
		(start 154.5463 -26.86812)
		(end 152.97912 -26.86812)
		(width 0.11938)
		(layer "F.Cu")
		(net "LM75B_I2C_SCL")
	)
	(segment
		(start 68.834 -84.836)
		(end 71.628 -87.63)
		(width 0.11938)
		(layer "F.Cu")
		(net "LM75B_I2C_SCL")
	)
	(segment
		(start 110.998 -65.532)
		(end 108.585 -67.945)
		(width 0.11938)
		(layer "F.Cu")
		(net "LM75B_I2C_SCL")
	)
	(segment
		(start 81.153 -86.741)
		(end 81.153 -85.724746)
		(width 0.11938)
		(layer "F.Cu")
		(net "LM75B_I2C_SCL")
	)
	(segment
		(start 55.245 -84.836)
		(end 54.55412 -84.14512)
		(width 0.11938)
		(layer "F.Cu")
		(net "LM75B_I2C_SCL")
	)
	(segment
		(start 81.153 -85.724746)
		(end 82.351626 -84.52612)
		(width 0.11938)
		(layer "F.Cu")
		(net "LM75B_I2C_SCL")
	)
	(segment
		(start 80.264 -87.63)
		(end 81.153 -86.741)
		(width 0.11938)
		(layer "F.Cu")
		(net "LM75B_I2C_SCL")
	)
	(segment
		(start 82.351626 -84.52612)
		(end 83.3501 -84.52612)
		(width 0.11938)
		(layer "F.Cu")
		(net "LM75B_I2C_SCL")
	)
	(segment
		(start 57.531 -84.836)
		(end 68.834 -84.836)
		(width 0.11938)
		(layer "F.Cu")
		(net "LM75B_I2C_SCL")
	)
	(segment
		(start 151.16302 -26.797)
		(end 151.2824 -26.67762)
		(width 0.11938)
		(layer "F.Cu")
		(net "LM75B_I2C_SCL")
	)
	(segment
		(start 102.235 -69.713856)
		(end 102.235 -76.835)
		(width 0.11938)
		(layer "F.Cu")
		(net "LM75B_I2C_SCL")
	)
	(segment
		(start 108.585 -67.945)
		(end 104.003856 -67.945)
		(width 0.11938)
		(layer "F.Cu")
		(net "LM75B_I2C_SCL")
	)
	(segment
		(start 148.971 -27.178)
		(end 149.352 -26.797)
		(width 0.11938)
		(layer "F.Cu")
		(net "LM75B_I2C_SCL")
	)
	(segment
		(start 151.2824 -26.67762)
		(end 151.2824 -26.035)
		(width 0.11938)
		(layer "F.Cu")
		(net "LM75B_I2C_SCL")
	)
	(segment
		(start 114.807746 -65.532)
		(end 110.998 -65.532)
		(width 0.11938)
		(layer "F.Cu")
		(net "LM75B_I2C_SCL")
	)
	(segment
		(start 116.078 -65.659)
		(end 114.934746 -65.659)
		(width 0.11938)
		(layer "F.Cu")
		(net "LM75B_I2C_SCL")
	)
	(segment
		(start 54.55412 -84.14512)
		(end 54.55412 -82.9437)
		(width 0.11938)
		(layer "F.Cu")
		(net "LM75B_I2C_SCL")
	)
	(segment
		(start 104.003856 -67.945)
		(end 102.235 -69.713856)
		(width 0.11938)
		(layer "F.Cu")
		(net "LM75B_I2C_SCL")
	)
	(segment
		(start 102.235 -76.835)
		(end 102.108 -76.962)
		(width 0.11938)
		(layer "F.Cu")
		(net "LM75B_I2C_SCL")
	)
	(segment
		(start 57.531 -84.836)
		(end 55.245 -84.836)
		(width 0.11938)
		(layer "F.Cu")
		(net "LM75B_I2C_SCL")
	)
	(segment
		(start 152.146 -26.035)
		(end 151.2824 -26.035)
		(width 0.11938)
		(layer "F.Cu")
		(net "LM75B_I2C_SCL")
	)
	(segment
		(start 71.628 -87.63)
		(end 80.264 -87.63)
		(width 0.11938)
		(layer "F.Cu")
		(net "LM75B_I2C_SCL")
	)
	(via
		(at 148.971 -27.178)
		(size 0.508)
		(drill 0.254)
		(layers "F.Cu" "B.Cu")
		(net "LM75B_I2C_SCL")
	)
	(via
		(at 16.383 -75.3745)
		(size 0.508)
		(drill 0.254)
		(layers "F.Cu" "B.Cu")
		(net "LM75B_I2C_SCL")
	)
	(via
		(at 102.108 -76.962)
		(size 0.508)
		(drill 0.254)
		(layers "F.Cu" "B.Cu")
		(net "LM75B_I2C_SCL")
	)
	(via
		(at 57.531 -84.836)
		(size 0.508)
		(drill 0.254)
		(layers "F.Cu" "B.Cu")
		(net "LM75B_I2C_SCL")
	)
	(via
		(at 116.078 -65.659)
		(size 0.508)
		(drill 0.254)
		(layers "F.Cu" "B.Cu")
		(net "LM75B_I2C_SCL")
	)
	(segment
		(start 18.034 -74.676)
		(end 17.7546 -74.9554)
		(width 0.11938)
		(layer "B.Cu")
		(net "LM75B_I2C_SCL")
	)
	(segment
		(start 55.9816 -80.3656)
		(end 52.07 -80.3656)
		(width 0.11938)
		(layer "B.Cu")
		(net "LM75B_I2C_SCL")
	)
	(segment
		(start 21.463 -75.946)
		(end 20.193 -74.676)
		(width 0.11938)
		(layer "B.Cu")
		(net "LM75B_I2C_SCL")
	)
	(segment
		(start 17.7546 -75.311)
		(end 16.4465 -75.311)
		(width 0.11938)
		(layer "B.Cu")
		(net "LM75B_I2C_SCL")
	)
	(segment
		(start 15.96644 -75.3745)
		(end 15.06982 -76.27112)
		(width 0.11938)
		(layer "B.Cu")
		(net "LM75B_I2C_SCL")
	)
	(segment
		(start 15.06982 -76.27112)
		(end 13.9827 -76.27112)
		(width 0.11938)
		(layer "B.Cu")
		(net "LM75B_I2C_SCL")
	)
	(segment
		(start 50.673 -74.168)
		(end 48.82642 -72.32142)
		(width 0.11938)
		(layer "B.Cu")
		(net "LM75B_I2C_SCL")
	)
	(segment
		(start 52.07 -80.3656)
		(end 50.673 -78.9686)
		(width 0.11938)
		(layer "B.Cu")
		(net "LM75B_I2C_SCL")
	)
	(segment
		(start 57.277 -84.582)
		(end 57.277 -81.661)
		(width 0.11938)
		(layer "B.Cu")
		(net "LM75B_I2C_SCL")
	)
	(segment
		(start 57.277 -81.661)
		(end 55.9816 -80.3656)
		(width 0.11938)
		(layer "B.Cu")
		(net "LM75B_I2C_SCL")
	)
	(segment
		(start 50.673 -78.9686)
		(end 50.673 -74.168)
		(width 0.11938)
		(layer "B.Cu")
		(net "LM75B_I2C_SCL")
	)
	(segment
		(start 48.82642 -72.32142)
		(end 42.48658 -72.32142)
		(width 0.11938)
		(layer "B.Cu")
		(net "LM75B_I2C_SCL")
	)
	(segment
		(start 22.606 -75.946)
		(end 21.463 -75.946)
		(width 0.11938)
		(layer "B.Cu")
		(net "LM75B_I2C_SCL")
	)
	(segment
		(start 17.7546 -74.9554)
		(end 17.7546 -75.311)
		(width 0.11938)
		(layer "B.Cu")
		(net "LM75B_I2C_SCL")
	)
	(segment
		(start 16.4465 -75.311)
		(end 16.383 -75.3745)
		(width 0.11938)
		(layer "B.Cu")
		(net "LM75B_I2C_SCL")
	)
	(segment
		(start 35.70732 -73.51268)
		(end 34.22142 -74.99858)
		(width 0.11938)
		(layer "B.Cu")
		(net "LM75B_I2C_SCL")
	)
	(segment
		(start 16.383 -75.3745)
		(end 15.96644 -75.3745)
		(width 0.11938)
		(layer "B.Cu")
		(net "LM75B_I2C_SCL")
	)
	(segment
		(start 34.22142 -74.99858)
		(end 23.55342 -74.99858)
		(width 0.11938)
		(layer "B.Cu")
		(net "LM75B_I2C_SCL")
	)
	(segment
		(start 41.29532 -73.51268)
		(end 35.70732 -73.51268)
		(width 0.11938)
		(layer "B.Cu")
		(net "LM75B_I2C_SCL")
	)
	(segment
		(start 57.531 -84.836)
		(end 57.277 -84.582)
		(width 0.11938)
		(layer "B.Cu")
		(net "LM75B_I2C_SCL")
	)
	(segment
		(start 20.193 -74.676)
		(end 18.034 -74.676)
		(width 0.11938)
		(layer "B.Cu")
		(net "LM75B_I2C_SCL")
	)
	(segment
		(start 23.55342 -74.99858)
		(end 22.606 -75.946)
		(width 0.11938)
		(layer "B.Cu")
		(net "LM75B_I2C_SCL")
	)
	(segment
		(start 42.48658 -72.32142)
		(end 41.29532 -73.51268)
		(width 0.11938)
		(layer "B.Cu")
		(net "LM75B_I2C_SCL")
	)
	(segment
		(start 101.219 -78.105)
		(end 98.552 -78.105)
		(width 0.127)
		(layer "In2.Cu")
		(net "LM75B_I2C_SCL")
	)
	(segment
		(start 149.606 -27.813)
		(end 149.606 -32.893)
		(width 0.127)
		(layer "In2.Cu")
		(net "LM75B_I2C_SCL")
	)
	(segment
		(start 21.5138 -77.1144)
		(end 19.677634 -77.1144)
		(width 0.127)
		(layer "In2.Cu")
		(net "LM75B_I2C_SCL")
	)
	(segment
		(start 116.078 -66.929)
		(end 116.078 -65.659)
		(width 0.127)
		(layer "In2.Cu")
		(net "LM75B_I2C_SCL")
	)
	(segment
		(start 121.749312 -58.293)
		(end 120.904 -58.293)
		(width 0.127)
		(layer "In2.Cu")
		(net "LM75B_I2C_SCL")
	)
	(segment
		(start 44.927266 -86.2457)
		(end 43.136566 -84.455)
		(width 0.127)
		(layer "In2.Cu")
		(net "LM75B_I2C_SCL")
	)
	(segment
		(start 133.731 -41.64965)
		(end 130.048 -45.33265)
		(width 0.127)
		(layer "In2.Cu")
		(net "LM75B_I2C_SCL")
	)
	(segment
		(start 33.571434 -78.105)
		(end 32.936434 -78.74)
		(width 0.127)
		(layer "In2.Cu")
		(net "LM75B_I2C_SCL")
	)
	(segment
		(start 72.94118 -79.883)
		(end 67.09918 -85.725)
		(width 0.127)
		(layer "In2.Cu")
		(net "LM75B_I2C_SCL")
	)
	(segment
		(start 32.936434 -78.74)
		(end 25.8572 -78.74)
		(width 0.127)
		(layer "In2.Cu")
		(net "LM75B_I2C_SCL")
	)
	(segment
		(start 39.2684 -84.455)
		(end 37.2618 -82.4484)
		(width 0.127)
		(layer "In2.Cu")
		(net "LM75B_I2C_SCL")
	)
	(segment
		(start 86.868 -79.629)
		(end 86.6775 -79.4385)
		(width 0.127)
		(layer "In2.Cu")
		(net "LM75B_I2C_SCL")
	)
	(segment
		(start 85.170518 -79.883)
		(end 72.94118 -79.883)
		(width 0.127)
		(layer "In2.Cu")
		(net "LM75B_I2C_SCL")
	)
	(segment
		(start 124.46 -51.689)
		(end 124.46 -52.958746)
		(width 0.127)
		(layer "In2.Cu")
		(net "LM75B_I2C_SCL")
	)
	(segment
		(start 133.731 -37.592)
		(end 133.731 -41.64965)
		(width 0.127)
		(layer "In2.Cu")
		(net "LM75B_I2C_SCL")
	)
	(segment
		(start 53.449982 -86.6267)
		(end 52.306982 -85.4837)
		(width 0.127)
		(layer "In2.Cu")
		(net "LM75B_I2C_SCL")
	)
	(segment
		(start 116.332 -67.183)
		(end 116.078 -66.929)
		(width 0.127)
		(layer "In2.Cu")
		(net "LM75B_I2C_SCL")
	)
	(segment
		(start 140.462 -36.068)
		(end 135.255 -36.068)
		(width 0.127)
		(layer "In2.Cu")
		(net "LM75B_I2C_SCL")
	)
	(segment
		(start 51.833018 -85.4837)
		(end 51.071018 -86.2457)
		(width 0.127)
		(layer "In2.Cu")
		(net "LM75B_I2C_SCL")
	)
	(segment
		(start 122.4915 -57.550812)
		(end 121.749312 -58.293)
		(width 0.127)
		(layer "In2.Cu")
		(net "LM75B_I2C_SCL")
	)
	(segment
		(start 98.552 -78.105)
		(end 97.028 -79.629)
		(width 0.127)
		(layer "In2.Cu")
		(net "LM75B_I2C_SCL")
	)
	(segment
		(start 43.136566 -84.455)
		(end 39.2684 -84.455)
		(width 0.127)
		(layer "In2.Cu")
		(net "LM75B_I2C_SCL")
	)
	(segment
		(start 130.048 -45.33265)
		(end 130.048 -49.232566)
		(width 0.127)
		(layer "In2.Cu")
		(net "LM75B_I2C_SCL")
	)
	(segment
		(start 52.306982 -85.4837)
		(end 51.833018 -85.4837)
		(width 0.127)
		(layer "In2.Cu")
		(net "LM75B_I2C_SCL")
	)
	(segment
		(start 148.971 -27.178)
		(end 149.606 -27.813)
		(width 0.127)
		(layer "In2.Cu")
		(net "LM75B_I2C_SCL")
	)
	(segment
		(start 149.606 -32.893)
		(end 147.701 -34.798)
		(width 0.127)
		(layer "In2.Cu")
		(net "LM75B_I2C_SCL")
	)
	(segment
		(start 19.474434 -77.3176)
		(end 18.3261 -77.3176)
		(width 0.127)
		(layer "In2.Cu")
		(net "LM75B_I2C_SCL")
	)
	(segment
		(start 135.255 -36.068)
		(end 133.731 -37.592)
		(width 0.127)
		(layer "In2.Cu")
		(net "LM75B_I2C_SCL")
	)
	(segment
		(start 19.677634 -77.1144)
		(end 19.474434 -77.3176)
		(width 0.127)
		(layer "In2.Cu")
		(net "LM75B_I2C_SCL")
	)
	(segment
		(start 58.6613 -86.6267)
		(end 53.449982 -86.6267)
		(width 0.127)
		(layer "In2.Cu")
		(net "LM75B_I2C_SCL")
	)
	(segment
		(start 118.999 -60.198)
		(end 118.999 -65.151)
		(width 0.127)
		(layer "In2.Cu")
		(net "LM75B_I2C_SCL")
	)
	(segment
		(start 118.999 -65.151)
		(end 116.967 -67.183)
		(width 0.127)
		(layer "In2.Cu")
		(net "LM75B_I2C_SCL")
	)
	(segment
		(start 141.732 -34.798)
		(end 140.462 -36.068)
		(width 0.127)
		(layer "In2.Cu")
		(net "LM75B_I2C_SCL")
	)
	(segment
		(start 122.4915 -54.927246)
		(end 122.4915 -57.550812)
		(width 0.127)
		(layer "In2.Cu")
		(net "LM75B_I2C_SCL")
	)
	(segment
		(start 124.46 -52.958746)
		(end 122.4915 -54.927246)
		(width 0.127)
		(layer "In2.Cu")
		(net "LM75B_I2C_SCL")
	)
	(segment
		(start 67.09918 -85.725)
		(end 59.563 -85.725)
		(width 0.127)
		(layer "In2.Cu")
		(net "LM75B_I2C_SCL")
	)
	(segment
		(start 25.8572 -78.74)
		(end 24.8158 -77.6986)
		(width 0.127)
		(layer "In2.Cu")
		(net "LM75B_I2C_SCL")
	)
	(segment
		(start 124.841 -51.308)
		(end 124.46 -51.689)
		(width 0.127)
		(layer "In2.Cu")
		(net "LM75B_I2C_SCL")
	)
	(segment
		(start 37.2618 -80.56118)
		(end 34.80562 -78.105)
		(width 0.127)
		(layer "In2.Cu")
		(net "LM75B_I2C_SCL")
	)
	(segment
		(start 116.967 -67.183)
		(end 116.332 -67.183)
		(width 0.127)
		(layer "In2.Cu")
		(net "LM75B_I2C_SCL")
	)
	(segment
		(start 127.972566 -51.308)
		(end 124.841 -51.308)
		(width 0.127)
		(layer "In2.Cu")
		(net "LM75B_I2C_SCL")
	)
	(segment
		(start 120.904 -58.293)
		(end 118.999 -60.198)
		(width 0.127)
		(layer "In2.Cu")
		(net "LM75B_I2C_SCL")
	)
	(segment
		(start 102.108 -76.962)
		(end 102.108 -77.216)
		(width 0.127)
		(layer "In2.Cu")
		(net "LM75B_I2C_SCL")
	)
	(segment
		(start 22.098 -77.6986)
		(end 21.5138 -77.1144)
		(width 0.127)
		(layer "In2.Cu")
		(net "LM75B_I2C_SCL")
	)
	(segment
		(start 59.563 -85.725)
		(end 58.6613 -86.6267)
		(width 0.127)
		(layer "In2.Cu")
		(net "LM75B_I2C_SCL")
	)
	(segment
		(start 51.071018 -86.2457)
		(end 44.927266 -86.2457)
		(width 0.127)
		(layer "In2.Cu")
		(net "LM75B_I2C_SCL")
	)
	(segment
		(start 147.701 -34.798)
		(end 141.732 -34.798)
		(width 0.127)
		(layer "In2.Cu")
		(net "LM75B_I2C_SCL")
	)
	(segment
		(start 18.3261 -77.3176)
		(end 16.383 -75.3745)
		(width 0.127)
		(layer "In2.Cu")
		(net "LM75B_I2C_SCL")
	)
	(segment
		(start 130.048 -49.232566)
		(end 127.972566 -51.308)
		(width 0.127)
		(layer "In2.Cu")
		(net "LM75B_I2C_SCL")
	)
	(segment
		(start 102.108 -77.216)
		(end 101.219 -78.105)
		(width 0.127)
		(layer "In2.Cu")
		(net "LM75B_I2C_SCL")
	)
	(segment
		(start 34.80562 -78.105)
		(end 33.571434 -78.105)
		(width 0.127)
		(layer "In2.Cu")
		(net "LM75B_I2C_SCL")
	)
	(segment
		(start 37.2618 -82.4484)
		(end 37.2618 -80.56118)
		(width 0.127)
		(layer "In2.Cu")
		(net "LM75B_I2C_SCL")
	)
	(segment
		(start 97.028 -79.629)
		(end 86.868 -79.629)
		(width 0.127)
		(layer "In2.Cu")
		(net "LM75B_I2C_SCL")
	)
	(segment
		(start 24.8158 -77.6986)
		(end 22.098 -77.6986)
		(width 0.127)
		(layer "In2.Cu")
		(net "LM75B_I2C_SCL")
	)
	(segment
		(start 86.6775 -79.4385)
		(end 85.615018 -79.4385)
		(width 0.127)
		(layer "In2.Cu")
		(net "LM75B_I2C_SCL")
	)
	(segment
		(start 85.615018 -79.4385)
		(end 85.170518 -79.883)
		(width 0.127)
		(layer "In2.Cu")
		(net "LM75B_I2C_SCL")
	)
	(segment
		(start 101.847142 -47.82312)
		(end 101.34727 -48.322992)
		(width 0.11938)
		(layer "F.Cu")
		(net "LED_DATOUT3")
	)
	(segment
		(start 138.050016 -107.100116)
		(end 139.402566 -105.747566)
		(width 0.11938)
		(layer "F.Cu")
		(net "LED_DATOUT3")
	)
	(via
		(at 139.402566 -105.747566)
		(size 0.508)
		(drill 0.254)
		(layers "F.Cu" "B.Cu")
		(net "LED_DATOUT3")
	)
	(via
		(at 101.34727 -48.322992)
		(size 0.4572)
		(drill 0.2032)
		(layers "F.Cu" "B.Cu")
		(net "LED_DATOUT3")
	)
	(segment
		(start 100.78593 -48.884332)
		(end 101.34727 -48.322992)
		(width 0.127)
		(layer "In2.Cu")
		(net "LED_DATOUT3")
	)
	(segment
		(start 138.684 -105.029)
		(end 138.684 -96.647)
		(width 0.127)
		(layer "In2.Cu")
		(net "LED_DATOUT3")
	)
	(segment
		(start 95.690182 -64.2493)
		(end 95.364554 -64.2493)
		(width 0.127)
		(layer "In2.Cu")
		(net "LED_DATOUT3")
	)
	(segment
		(start 95.364554 -64.2493)
		(end 94.2975 -63.182246)
		(width 0.127)
		(layer "In2.Cu")
		(net "LED_DATOUT3")
	)
	(segment
		(start 122.335036 -91.948)
		(end 121.319036 -90.932)
		(width 0.127)
		(layer "In2.Cu")
		(net "LED_DATOUT3")
	)
	(segment
		(start 110.035594 -77.315822)
		(end 107.0991 -74.379328)
		(width 0.127)
		(layer "In2.Cu")
		(net "LED_DATOUT3")
	)
	(segment
		(start 94.2975 -62.4205)
		(end 95.758 -60.96)
		(width 0.127)
		(layer "In2.Cu")
		(net "LED_DATOUT3")
	)
	(segment
		(start 127.127 -91.948)
		(end 122.335036 -91.948)
		(width 0.127)
		(layer "In2.Cu")
		(net "LED_DATOUT3")
	)
	(segment
		(start 115.824 -86.487)
		(end 115.824 -83.789012)
		(width 0.127)
		(layer "In2.Cu")
		(net "LED_DATOUT3")
	)
	(segment
		(start 91.6305 -53.9115)
		(end 92.4052 -53.1368)
		(width 0.127)
		(layer "In2.Cu")
		(net "LED_DATOUT3")
	)
	(segment
		(start 95.702882 -64.262)
		(end 95.690182 -64.2493)
		(width 0.127)
		(layer "In2.Cu")
		(net "LED_DATOUT3")
	)
	(segment
		(start 128.397 -90.678)
		(end 127.127 -91.948)
		(width 0.127)
		(layer "In2.Cu")
		(net "LED_DATOUT3")
	)
	(segment
		(start 110.763304 -77.315822)
		(end 110.035594 -77.315822)
		(width 0.127)
		(layer "In2.Cu")
		(net "LED_DATOUT3")
	)
	(segment
		(start 92.1385 -57.023)
		(end 91.6305 -56.515)
		(width 0.127)
		(layer "In2.Cu")
		(net "LED_DATOUT3")
	)
	(segment
		(start 120.269 -90.932)
		(end 115.824 -86.487)
		(width 0.127)
		(layer "In2.Cu")
		(net "LED_DATOUT3")
	)
	(segment
		(start 101.6127 -65.743582)
		(end 101.6127 -65.405)
		(width 0.127)
		(layer "In2.Cu")
		(net "LED_DATOUT3")
	)
	(segment
		(start 112.552988 -81.026)
		(end 111.887 -80.360012)
		(width 0.127)
		(layer "In2.Cu")
		(net "LED_DATOUT3")
	)
	(segment
		(start 96.773746 -65.278)
		(end 95.757746 -64.262)
		(width 0.127)
		(layer "In2.Cu")
		(net "LED_DATOUT3")
	)
	(segment
		(start 114.3 -82.265012)
		(end 114.3 -81.153)
		(width 0.127)
		(layer "In2.Cu")
		(net "LED_DATOUT3")
	)
	(segment
		(start 138.684 -96.647)
		(end 132.715 -90.678)
		(width 0.127)
		(layer "In2.Cu")
		(net "LED_DATOUT3")
	)
	(segment
		(start 97.652078 -48.884332)
		(end 100.78593 -48.884332)
		(width 0.127)
		(layer "In2.Cu")
		(net "LED_DATOUT3")
	)
	(segment
		(start 139.402566 -105.747566)
		(end 138.684 -105.029)
		(width 0.127)
		(layer "In2.Cu")
		(net "LED_DATOUT3")
	)
	(segment
		(start 91.6305 -56.515)
		(end 91.6305 -53.9115)
		(width 0.127)
		(layer "In2.Cu")
		(net "LED_DATOUT3")
	)
	(segment
		(start 94.488 -57.023)
		(end 92.1385 -57.023)
		(width 0.127)
		(layer "In2.Cu")
		(net "LED_DATOUT3")
	)
	(segment
		(start 105.41 -72.678036)
		(end 105.41 -69.540882)
		(width 0.127)
		(layer "In2.Cu")
		(net "LED_DATOUT3")
	)
	(segment
		(start 101.4857 -65.278)
		(end 96.773746 -65.278)
		(width 0.127)
		(layer "In2.Cu")
		(net "LED_DATOUT3")
	)
	(segment
		(start 95.758 -58.293)
		(end 94.488 -57.023)
		(width 0.127)
		(layer "In2.Cu")
		(net "LED_DATOUT3")
	)
	(segment
		(start 114.173 -81.026)
		(end 112.552988 -81.026)
		(width 0.127)
		(layer "In2.Cu")
		(net "LED_DATOUT3")
	)
	(segment
		(start 93.39961 -53.1368)
		(end 97.652078 -48.884332)
		(width 0.127)
		(layer "In2.Cu")
		(net "LED_DATOUT3")
	)
	(segment
		(start 101.6127 -65.405)
		(end 101.4857 -65.278)
		(width 0.127)
		(layer "In2.Cu")
		(net "LED_DATOUT3")
	)
	(segment
		(start 95.757746 -64.262)
		(end 95.702882 -64.262)
		(width 0.127)
		(layer "In2.Cu")
		(net "LED_DATOUT3")
	)
	(segment
		(start 111.887 -80.360012)
		(end 111.887 -78.439518)
		(width 0.127)
		(layer "In2.Cu")
		(net "LED_DATOUT3")
	)
	(segment
		(start 92.4052 -53.1368)
		(end 93.39961 -53.1368)
		(width 0.127)
		(layer "In2.Cu")
		(net "LED_DATOUT3")
	)
	(segment
		(start 111.887 -78.439518)
		(end 110.763304 -77.315822)
		(width 0.127)
		(layer "In2.Cu")
		(net "LED_DATOUT3")
	)
	(segment
		(start 114.3 -81.153)
		(end 114.173 -81.026)
		(width 0.127)
		(layer "In2.Cu")
		(net "LED_DATOUT3")
	)
	(segment
		(start 115.824 -83.789012)
		(end 114.3 -82.265012)
		(width 0.127)
		(layer "In2.Cu")
		(net "LED_DATOUT3")
	)
	(segment
		(start 94.2975 -63.182246)
		(end 94.2975 -62.4205)
		(width 0.127)
		(layer "In2.Cu")
		(net "LED_DATOUT3")
	)
	(segment
		(start 107.0991 -74.367136)
		(end 105.41 -72.678036)
		(width 0.127)
		(layer "In2.Cu")
		(net "LED_DATOUT3")
	)
	(segment
		(start 132.715 -90.678)
		(end 128.397 -90.678)
		(width 0.127)
		(layer "In2.Cu")
		(net "LED_DATOUT3")
	)
	(segment
		(start 121.319036 -90.932)
		(end 120.269 -90.932)
		(width 0.127)
		(layer "In2.Cu")
		(net "LED_DATOUT3")
	)
	(segment
		(start 107.0991 -74.379328)
		(end 107.0991 -74.367136)
		(width 0.127)
		(layer "In2.Cu")
		(net "LED_DATOUT3")
	)
	(segment
		(start 95.758 -60.96)
		(end 95.758 -58.293)
		(width 0.127)
		(layer "In2.Cu")
		(net "LED_DATOUT3")
	)
	(segment
		(start 105.41 -69.540882)
		(end 101.6127 -65.743582)
		(width 0.127)
		(layer "In2.Cu")
		(net "LED_DATOUT3")
	)
	(segment
		(start 101.847142 -46.823122)
		(end 101.34727 -47.322994)
		(width 0.11938)
		(layer "F.Cu")
		(net "LED_DATOUT2")
	)
	(segment
		(start 141.05001 -107.100116)
		(end 141.05001 -106.045)
		(width 0.11938)
		(layer "F.Cu")
		(net "LED_DATOUT2")
	)
	(via
		(at 101.34727 -47.322994)
		(size 0.4572)
		(drill 0.2032)
		(layers "F.Cu" "B.Cu")
		(net "LED_DATOUT2")
	)
	(via
		(at 141.05001 -106.045)
		(size 0.508)
		(drill 0.254)
		(layers "F.Cu" "B.Cu")
		(net "LED_DATOUT2")
	)
	(segment
		(start 92.4306 -52.7558)
		(end 92.247212 -52.7558)
		(width 0.127)
		(layer "In2.Cu")
		(net "LED_DATOUT2")
	)
	(segment
		(start 127.254 -92.456)
		(end 128.651 -91.059)
		(width 0.127)
		(layer "In2.Cu")
		(net "LED_DATOUT2")
	)
	(segment
		(start 140.66901 -106.426)
		(end 141.05001 -106.045)
		(width 0.127)
		(layer "In2.Cu")
		(net "LED_DATOUT2")
	)
	(segment
		(start 113.792 -83.312)
		(end 114.808 -83.312)
		(width 0.127)
		(layer "In2.Cu")
		(net "LED_DATOUT2")
	)
	(segment
		(start 109.054392 -76.873608)
		(end 109.054392 -77.431392)
		(width 0.127)
		(layer "In2.Cu")
		(net "LED_DATOUT2")
	)
	(segment
		(start 138.049 -102.87)
		(end 138.049 -105.664)
		(width 0.127)
		(layer "In2.Cu")
		(net "LED_DATOUT2")
	)
	(segment
		(start 111.252 -80.772)
		(end 113.792 -83.312)
		(width 0.127)
		(layer "In2.Cu")
		(net "LED_DATOUT2")
	)
	(segment
		(start 97.446084 -48.551338)
		(end 93.267022 -52.7304)
		(width 0.127)
		(layer "In2.Cu")
		(net "LED_DATOUT2")
	)
	(segment
		(start 93.267022 -52.7304)
		(end 92.456 -52.7304)
		(width 0.127)
		(layer "In2.Cu")
		(net "LED_DATOUT2")
	)
	(segment
		(start 106.7181 -74.525124)
		(end 106.7181 -74.537316)
		(width 0.127)
		(layer "In2.Cu")
		(net "LED_DATOUT2")
	)
	(segment
		(start 138.049 -105.664)
		(end 138.811 -106.426)
		(width 0.127)
		(layer "In2.Cu")
		(net "LED_DATOUT2")
	)
	(segment
		(start 97.01276 -65.659)
		(end 98.15576 -66.802)
		(width 0.127)
		(layer "In2.Cu")
		(net "LED_DATOUT2")
	)
	(segment
		(start 136.7409 -95.4659)
		(end 136.7409 -101.5619)
		(width 0.127)
		(layer "In2.Cu")
		(net "LED_DATOUT2")
	)
	(segment
		(start 128.651 -91.059)
		(end 132.334 -91.059)
		(width 0.127)
		(layer "In2.Cu")
		(net "LED_DATOUT2")
	)
	(segment
		(start 121.161048 -91.313)
		(end 122.304048 -92.456)
		(width 0.127)
		(layer "In2.Cu")
		(net "LED_DATOUT2")
	)
	(segment
		(start 95.25 -60.929012)
		(end 93.853 -62.326012)
		(width 0.127)
		(layer "In2.Cu")
		(net "LED_DATOUT2")
	)
	(segment
		(start 92.456 -52.7304)
		(end 92.4306 -52.7558)
		(width 0.127)
		(layer "In2.Cu")
		(net "LED_DATOUT2")
	)
	(segment
		(start 100.859844 -47.81042)
		(end 99.63658 -47.81042)
		(width 0.127)
		(layer "In2.Cu")
		(net "LED_DATOUT2")
	)
	(segment
		(start 91.2495 -56.672988)
		(end 91.980512 -57.404)
		(width 0.127)
		(layer "In2.Cu")
		(net "LED_DATOUT2")
	)
	(segment
		(start 95.25 -58.754518)
		(end 95.25 -60.929012)
		(width 0.127)
		(layer "In2.Cu")
		(net "LED_DATOUT2")
	)
	(segment
		(start 93.899482 -57.404)
		(end 95.25 -58.754518)
		(width 0.127)
		(layer "In2.Cu")
		(net "LED_DATOUT2")
	)
	(segment
		(start 132.334 -91.059)
		(end 136.7409 -95.4659)
		(width 0.127)
		(layer "In2.Cu")
		(net "LED_DATOUT2")
	)
	(segment
		(start 122.304048 -92.456)
		(end 127.254 -92.456)
		(width 0.127)
		(layer "In2.Cu")
		(net "LED_DATOUT2")
	)
	(segment
		(start 92.247212 -52.7558)
		(end 91.2495 -53.753512)
		(width 0.127)
		(layer "In2.Cu")
		(net "LED_DATOUT2")
	)
	(segment
		(start 115.316 -87.272622)
		(end 115.951 -87.907622)
		(width 0.127)
		(layer "In2.Cu")
		(net "LED_DATOUT2")
	)
	(segment
		(start 91.2495 -53.753512)
		(end 91.2495 -56.672988)
		(width 0.127)
		(layer "In2.Cu")
		(net "LED_DATOUT2")
	)
	(segment
		(start 94.996 -65.659)
		(end 97.01276 -65.659)
		(width 0.127)
		(layer "In2.Cu")
		(net "LED_DATOUT2")
	)
	(segment
		(start 115.951 -87.907622)
		(end 115.951 -89.188036)
		(width 0.127)
		(layer "In2.Cu")
		(net "LED_DATOUT2")
	)
	(segment
		(start 106.7181 -74.537316)
		(end 109.054392 -76.873608)
		(width 0.127)
		(layer "In2.Cu")
		(net "LED_DATOUT2")
	)
	(segment
		(start 111.252 -79.629)
		(end 111.252 -80.772)
		(width 0.127)
		(layer "In2.Cu")
		(net "LED_DATOUT2")
	)
	(segment
		(start 101.34727 -47.322994)
		(end 100.859844 -47.81042)
		(width 0.127)
		(layer "In2.Cu")
		(net "LED_DATOUT2")
	)
	(segment
		(start 101.854 -66.802)
		(end 105.029 -69.977)
		(width 0.127)
		(layer "In2.Cu")
		(net "LED_DATOUT2")
	)
	(segment
		(start 109.054392 -77.431392)
		(end 111.252 -79.629)
		(width 0.127)
		(layer "In2.Cu")
		(net "LED_DATOUT2")
	)
	(segment
		(start 93.853 -64.516)
		(end 94.996 -65.659)
		(width 0.127)
		(layer "In2.Cu")
		(net "LED_DATOUT2")
	)
	(segment
		(start 114.808 -83.312)
		(end 115.316 -83.82)
		(width 0.127)
		(layer "In2.Cu")
		(net "LED_DATOUT2")
	)
	(segment
		(start 105.029 -69.977)
		(end 105.029 -72.836024)
		(width 0.127)
		(layer "In2.Cu")
		(net "LED_DATOUT2")
	)
	(segment
		(start 99.63658 -47.81042)
		(end 98.895662 -48.551338)
		(width 0.127)
		(layer "In2.Cu")
		(net "LED_DATOUT2")
	)
	(segment
		(start 93.853 -62.326012)
		(end 93.853 -64.516)
		(width 0.127)
		(layer "In2.Cu")
		(net "LED_DATOUT2")
	)
	(segment
		(start 98.895662 -48.551338)
		(end 97.446084 -48.551338)
		(width 0.127)
		(layer "In2.Cu")
		(net "LED_DATOUT2")
	)
	(segment
		(start 91.980512 -57.404)
		(end 93.899482 -57.404)
		(width 0.127)
		(layer "In2.Cu")
		(net "LED_DATOUT2")
	)
	(segment
		(start 98.15576 -66.802)
		(end 101.854 -66.802)
		(width 0.127)
		(layer "In2.Cu")
		(net "LED_DATOUT2")
	)
	(segment
		(start 136.7409 -101.5619)
		(end 138.049 -102.87)
		(width 0.127)
		(layer "In2.Cu")
		(net "LED_DATOUT2")
	)
	(segment
		(start 138.811 -106.426)
		(end 140.66901 -106.426)
		(width 0.127)
		(layer "In2.Cu")
		(net "LED_DATOUT2")
	)
	(segment
		(start 115.951 -89.188036)
		(end 118.075964 -91.313)
		(width 0.127)
		(layer "In2.Cu")
		(net "LED_DATOUT2")
	)
	(segment
		(start 105.029 -72.836024)
		(end 106.7181 -74.525124)
		(width 0.127)
		(layer "In2.Cu")
		(net "LED_DATOUT2")
	)
	(segment
		(start 118.075964 -91.313)
		(end 121.161048 -91.313)
		(width 0.127)
		(layer "In2.Cu")
		(net "LED_DATOUT2")
	)
	(segment
		(start 115.316 -83.82)
		(end 115.316 -87.272622)
		(width 0.127)
		(layer "In2.Cu")
		(net "LED_DATOUT2")
	)
	(segment
		(start 100.347018 -46.322996)
		(end 100.84689 -45.823124)
		(width 0.11938)
		(layer "F.Cu")
		(net "LED_DATOUT1")
	)
	(segment
		(start 144.050004 -107.100116)
		(end 144.050004 -106.045)
		(width 0.11938)
		(layer "F.Cu")
		(net "LED_DATOUT1")
	)
	(via
		(at 144.050004 -106.045)
		(size 0.508)
		(drill 0.254)
		(layers "F.Cu" "B.Cu")
		(net "LED_DATOUT1")
	)
	(via
		(at 100.347018 -46.322996)
		(size 0.4572)
		(drill 0.2032)
		(layers "F.Cu" "B.Cu")
		(net "LED_DATOUT1")
	)
	(segment
		(start 102.8827 -73.9267)
		(end 103.759 -74.803)
		(width 0.127)
		(layer "In2.Cu")
		(net "LED_DATOUT1")
	)
	(segment
		(start 94.24924 -66.81724)
		(end 96.26346 -66.81724)
		(width 0.127)
		(layer "In2.Cu")
		(net "LED_DATOUT1")
	)
	(segment
		(start 89.926668 -63.5381)
		(end 90.9701 -63.5381)
		(width 0.127)
		(layer "In2.Cu")
		(net "LED_DATOUT1")
	)
	(segment
		(start 118.422166 -93.276166)
		(end 119.70258 -93.276166)
		(width 0.127)
		(layer "In2.Cu")
		(net "LED_DATOUT1")
	)
	(segment
		(start 114.808 -88.381586)
		(end 114.808 -89.662)
		(width 0.127)
		(layer "In2.Cu")
		(net "LED_DATOUT1")
	)
	(segment
		(start 134.484618 -102.1715)
		(end 135.067548 -102.1715)
		(width 0.127)
		(layer "In2.Cu")
		(net "LED_DATOUT1")
	)
	(segment
		(start 93.230446 -51.149758)
		(end 90.99423 -51.149758)
		(width 0.127)
		(layer "In2.Cu")
		(net "LED_DATOUT1")
	)
	(segment
		(start 105.36682 -74.803)
		(end 106.97591 -76.41209)
		(width 0.127)
		(layer "In2.Cu")
		(net "LED_DATOUT1")
	)
	(segment
		(start 103.759 -74.803)
		(end 105.36682 -74.803)
		(width 0.127)
		(layer "In2.Cu")
		(net "LED_DATOUT1")
	)
	(segment
		(start 135.7249 -106.0069)
		(end 137.287 -107.569)
		(width 0.127)
		(layer "In2.Cu")
		(net "LED_DATOUT1")
	)
	(segment
		(start 106.97591 -80.30591)
		(end 109.22 -82.55)
		(width 0.127)
		(layer "In2.Cu")
		(net "LED_DATOUT1")
	)
	(segment
		(start 132.334 -100.020882)
		(end 134.484618 -102.1715)
		(width 0.127)
		(layer "In2.Cu")
		(net "LED_DATOUT1")
	)
	(segment
		(start 109.22 -85.100414)
		(end 111.813086 -87.6935)
		(width 0.127)
		(layer "In2.Cu")
		(net "LED_DATOUT1")
	)
	(segment
		(start 106.97591 -76.41209)
		(end 106.97591 -80.30591)
		(width 0.127)
		(layer "In2.Cu")
		(net "LED_DATOUT1")
	)
	(segment
		(start 99.558094 -45.83684)
		(end 98.543364 -45.83684)
		(width 0.127)
		(layer "In2.Cu")
		(net "LED_DATOUT1")
	)
	(segment
		(start 109.22 -82.55)
		(end 109.22 -85.100414)
		(width 0.127)
		(layer "In2.Cu")
		(net "LED_DATOUT1")
	)
	(segment
		(start 96.26346 -66.81724)
		(end 98.28022 -68.834)
		(width 0.127)
		(layer "In2.Cu")
		(net "LED_DATOUT1")
	)
	(segment
		(start 90.9701 -63.5381)
		(end 94.24924 -66.81724)
		(width 0.127)
		(layer "In2.Cu")
		(net "LED_DATOUT1")
	)
	(segment
		(start 88.9 -53.243988)
		(end 88.9 -55.656988)
		(width 0.127)
		(layer "In2.Cu")
		(net "LED_DATOUT1")
	)
	(segment
		(start 90.99423 -51.149758)
		(end 88.9 -53.243988)
		(width 0.127)
		(layer "In2.Cu")
		(net "LED_DATOUT1")
	)
	(segment
		(start 119.70258 -93.276166)
		(end 124.216414 -97.79)
		(width 0.127)
		(layer "In2.Cu")
		(net "LED_DATOUT1")
	)
	(segment
		(start 88.9 -55.656988)
		(end 88.3031 -56.253888)
		(width 0.127)
		(layer "In2.Cu")
		(net "LED_DATOUT1")
	)
	(segment
		(start 132.207 -97.79)
		(end 132.334 -97.917)
		(width 0.127)
		(layer "In2.Cu")
		(net "LED_DATOUT1")
	)
	(segment
		(start 135.067548 -102.1715)
		(end 135.7249 -102.828852)
		(width 0.127)
		(layer "In2.Cu")
		(net "LED_DATOUT1")
	)
	(segment
		(start 114.119914 -87.6935)
		(end 114.808 -88.381586)
		(width 0.127)
		(layer "In2.Cu")
		(net "LED_DATOUT1")
	)
	(segment
		(start 100.04425 -46.322996)
		(end 99.558094 -45.83684)
		(width 0.127)
		(layer "In2.Cu")
		(net "LED_DATOUT1")
	)
	(segment
		(start 114.808 -89.662)
		(end 118.422166 -93.276166)
		(width 0.127)
		(layer "In2.Cu")
		(net "LED_DATOUT1")
	)
	(segment
		(start 98.543364 -45.83684)
		(end 93.230446 -51.149758)
		(width 0.127)
		(layer "In2.Cu")
		(net "LED_DATOUT1")
	)
	(segment
		(start 135.7249 -102.828852)
		(end 135.7249 -106.0069)
		(width 0.127)
		(layer "In2.Cu")
		(net "LED_DATOUT1")
	)
	(segment
		(start 101.885242 -68.834)
		(end 102.8827 -69.831458)
		(width 0.127)
		(layer "In2.Cu")
		(net "LED_DATOUT1")
	)
	(segment
		(start 88.3031 -61.914532)
		(end 89.926668 -63.5381)
		(width 0.127)
		(layer "In2.Cu")
		(net "LED_DATOUT1")
	)
	(segment
		(start 98.28022 -68.834)
		(end 101.885242 -68.834)
		(width 0.127)
		(layer "In2.Cu")
		(net "LED_DATOUT1")
	)
	(segment
		(start 137.287 -107.569)
		(end 142.526004 -107.569)
		(width 0.127)
		(layer "In2.Cu")
		(net "LED_DATOUT1")
	)
	(segment
		(start 100.347018 -46.322996)
		(end 100.04425 -46.322996)
		(width 0.127)
		(layer "In2.Cu")
		(net "LED_DATOUT1")
	)
	(segment
		(start 88.3031 -56.253888)
		(end 88.3031 -61.914532)
		(width 0.127)
		(layer "In2.Cu")
		(net "LED_DATOUT1")
	)
	(segment
		(start 102.8827 -69.831458)
		(end 102.8827 -73.9267)
		(width 0.127)
		(layer "In2.Cu")
		(net "LED_DATOUT1")
	)
	(segment
		(start 124.216414 -97.79)
		(end 132.207 -97.79)
		(width 0.127)
		(layer "In2.Cu")
		(net "LED_DATOUT1")
	)
	(segment
		(start 132.334 -97.917)
		(end 132.334 -100.020882)
		(width 0.127)
		(layer "In2.Cu")
		(net "LED_DATOUT1")
	)
	(segment
		(start 111.813086 -87.6935)
		(end 114.119914 -87.6935)
		(width 0.127)
		(layer "In2.Cu")
		(net "LED_DATOUT1")
	)
	(segment
		(start 142.526004 -107.569)
		(end 144.050004 -106.045)
		(width 0.127)
		(layer "In2.Cu")
		(net "LED_DATOUT1")
	)
	(segment
		(start 99.34702 -46.322996)
		(end 99.846892 -45.823124)
		(width 0.11938)
		(layer "F.Cu")
		(net "LED_DATOUT0")
	)
	(segment
		(start 147.049998 -107.100116)
		(end 147.049998 -106.045)
		(width 0.11938)
		(layer "F.Cu")
		(net "LED_DATOUT0")
	)
	(via
		(at 99.34702 -46.322996)
		(size 0.4572)
		(drill 0.2032)
		(layers "F.Cu" "B.Cu")
		(net "LED_DATOUT0")
	)
	(via
		(at 147.049998 -106.045)
		(size 0.508)
		(drill 0.254)
		(layers "F.Cu" "B.Cu")
		(net "LED_DATOUT0")
	)
	(segment
		(start 96.421448 -66.43624)
		(end 94.441772 -66.43624)
		(width 0.127)
		(layer "In2.Cu")
		(net "LED_DATOUT0")
	)
	(segment
		(start 113.157 -86.191598)
		(end 113.157 -84.201)
		(width 0.127)
		(layer "In2.Cu")
		(net "LED_DATOUT0")
	)
	(segment
		(start 105.9561 -74.8411)
		(end 104.521 -73.406)
		(width 0.127)
		(layer "In2.Cu")
		(net "LED_DATOUT0")
	)
	(segment
		(start 115.189 -89.504012)
		(end 115.189 -88.223598)
		(width 0.127)
		(layer "In2.Cu")
		(net "LED_DATOUT0")
	)
	(segment
		(start 110.998 -82.042)
		(end 109.474 -82.042)
		(width 0.127)
		(layer "In2.Cu")
		(net "LED_DATOUT0")
	)
	(segment
		(start 92.202 -58.42)
		(end 91.948 -58.166)
		(width 0.127)
		(layer "In2.Cu")
		(net "LED_DATOUT0")
	)
	(segment
		(start 103.2637 -69.67347)
		(end 103.251 -69.66077)
		(width 0.127)
		(layer "In2.Cu")
		(net "LED_DATOUT0")
	)
	(segment
		(start 89.408 -53.594)
		(end 91.0844 -51.9176)
		(width 0.127)
		(layer "In2.Cu")
		(net "LED_DATOUT0")
	)
	(segment
		(start 98.438208 -68.453)
		(end 96.421448 -66.43624)
		(width 0.127)
		(layer "In2.Cu")
		(net "LED_DATOUT0")
	)
	(segment
		(start 135.89 -95.692976)
		(end 132.018024 -91.821)
		(width 0.127)
		(layer "In2.Cu")
		(net "LED_DATOUT0")
	)
	(segment
		(start 91.0844 -51.9176)
		(end 93.001592 -51.9176)
		(width 0.127)
		(layer "In2.Cu")
		(net "LED_DATOUT0")
	)
	(segment
		(start 104.521 -73.406)
		(end 103.759 -73.406)
		(width 0.127)
		(layer "In2.Cu")
		(net "LED_DATOUT0")
	)
	(segment
		(start 127.8255 -93.4085)
		(end 120.373902 -93.4085)
		(width 0.127)
		(layer "In2.Cu")
		(net "LED_DATOUT0")
	)
	(segment
		(start 109.474 -82.042)
		(end 107.499404 -80.067404)
		(width 0.127)
		(layer "In2.Cu")
		(net "LED_DATOUT0")
	)
	(segment
		(start 120.373902 -93.4085)
		(end 119.860568 -92.895166)
		(width 0.127)
		(layer "In2.Cu")
		(net "LED_DATOUT0")
	)
	(segment
		(start 103.2637 -72.9107)
		(end 103.2637 -69.67347)
		(width 0.127)
		(layer "In2.Cu")
		(net "LED_DATOUT0")
	)
	(segment
		(start 103.759 -73.406)
		(end 103.2637 -72.9107)
		(width 0.127)
		(layer "In2.Cu")
		(net "LED_DATOUT0")
	)
	(segment
		(start 136.144 -102.489)
		(end 135.89 -102.235)
		(width 0.127)
		(layer "In2.Cu")
		(net "LED_DATOUT0")
	)
	(segment
		(start 94.441772 -66.43624)
		(end 92.425266 -64.419734)
		(width 0.127)
		(layer "In2.Cu")
		(net "LED_DATOUT0")
	)
	(segment
		(start 141.986 -107.188)
		(end 137.795 -107.188)
		(width 0.127)
		(layer "In2.Cu")
		(net "LED_DATOUT0")
	)
	(segment
		(start 93.001592 -51.9176)
		(end 98.596196 -46.322996)
		(width 0.127)
		(layer "In2.Cu")
		(net "LED_DATOUT0")
	)
	(segment
		(start 107.499404 -80.067404)
		(end 107.499404 -76.396596)
		(width 0.127)
		(layer "In2.Cu")
		(net "LED_DATOUT0")
	)
	(segment
		(start 89.408 -57.785)
		(end 89.408 -53.594)
		(width 0.127)
		(layer "In2.Cu")
		(net "LED_DATOUT0")
	)
	(segment
		(start 119.860568 -92.895166)
		(end 118.580154 -92.895166)
		(width 0.127)
		(layer "In2.Cu")
		(net "LED_DATOUT0")
	)
	(segment
		(start 103.251 -69.596)
		(end 102.108 -68.453)
		(width 0.127)
		(layer "In2.Cu")
		(net "LED_DATOUT0")
	)
	(segment
		(start 113.157 -84.201)
		(end 110.998 -82.042)
		(width 0.127)
		(layer "In2.Cu")
		(net "LED_DATOUT0")
	)
	(segment
		(start 89.789 -58.166)
		(end 89.408 -57.785)
		(width 0.127)
		(layer "In2.Cu")
		(net "LED_DATOUT0")
	)
	(segment
		(start 105.9561 -74.853292)
		(end 105.9561 -74.8411)
		(width 0.127)
		(layer "In2.Cu")
		(net "LED_DATOUT0")
	)
	(segment
		(start 137.795 -107.188)
		(end 136.144 -105.537)
		(width 0.127)
		(layer "In2.Cu")
		(net "LED_DATOUT0")
	)
	(segment
		(start 118.580154 -92.895166)
		(end 115.189 -89.504012)
		(width 0.127)
		(layer "In2.Cu")
		(net "LED_DATOUT0")
	)
	(segment
		(start 147.049998 -106.045)
		(end 145.432018 -106.045)
		(width 0.127)
		(layer "In2.Cu")
		(net "LED_DATOUT0")
	)
	(segment
		(start 107.499404 -76.396596)
		(end 105.9561 -74.853292)
		(width 0.127)
		(layer "In2.Cu")
		(net "LED_DATOUT0")
	)
	(segment
		(start 132.018024 -91.821)
		(end 129.413 -91.821)
		(width 0.127)
		(layer "In2.Cu")
		(net "LED_DATOUT0")
	)
	(segment
		(start 135.89 -102.235)
		(end 135.89 -95.692976)
		(width 0.127)
		(layer "In2.Cu")
		(net "LED_DATOUT0")
	)
	(segment
		(start 145.432018 -106.045)
		(end 144.797018 -105.41)
		(width 0.127)
		(layer "In2.Cu")
		(net "LED_DATOUT0")
	)
	(segment
		(start 143.764 -105.41)
		(end 141.986 -107.188)
		(width 0.127)
		(layer "In2.Cu")
		(net "LED_DATOUT0")
	)
	(segment
		(start 136.144 -105.537)
		(end 136.144 -102.489)
		(width 0.127)
		(layer "In2.Cu")
		(net "LED_DATOUT0")
	)
	(segment
		(start 92.202 -62.865)
		(end 92.202 -58.42)
		(width 0.127)
		(layer "In2.Cu")
		(net "LED_DATOUT0")
	)
	(segment
		(start 92.425266 -64.419734)
		(end 92.425266 -63.088266)
		(width 0.127)
		(layer "In2.Cu")
		(net "LED_DATOUT0")
	)
	(segment
		(start 144.797018 -105.41)
		(end 143.764 -105.41)
		(width 0.127)
		(layer "In2.Cu")
		(net "LED_DATOUT0")
	)
	(segment
		(start 92.425266 -63.088266)
		(end 92.202 -62.865)
		(width 0.127)
		(layer "In2.Cu")
		(net "LED_DATOUT0")
	)
	(segment
		(start 129.413 -91.821)
		(end 127.8255 -93.4085)
		(width 0.127)
		(layer "In2.Cu")
		(net "LED_DATOUT0")
	)
	(segment
		(start 98.596196 -46.322996)
		(end 99.34702 -46.322996)
		(width 0.127)
		(layer "In2.Cu")
		(net "LED_DATOUT0")
	)
	(segment
		(start 103.251 -69.66077)
		(end 103.251 -69.596)
		(width 0.127)
		(layer "In2.Cu")
		(net "LED_DATOUT0")
	)
	(segment
		(start 91.948 -58.166)
		(end 89.789 -58.166)
		(width 0.127)
		(layer "In2.Cu")
		(net "LED_DATOUT0")
	)
	(segment
		(start 102.108 -68.453)
		(end 98.438208 -68.453)
		(width 0.127)
		(layer "In2.Cu")
		(net "LED_DATOUT0")
	)
	(segment
		(start 115.189 -88.223598)
		(end 113.157 -86.191598)
		(width 0.127)
		(layer "In2.Cu")
		(net "LED_DATOUT0")
	)
	(segment
		(start 104.394 -55.88)
		(end 104.394 -54.276244)
		(width 0.11938)
		(layer "F.Cu")
		(net "IO_L24P_16")
	)
	(segment
		(start 104.394 -54.276244)
		(end 104.847136 -53.823108)
		(width 0.11938)
		(layer "F.Cu")
		(net "IO_L24P_16")
	)
	(segment
		(start 106.807 -58.293)
		(end 104.394 -55.88)
		(width 0.11938)
		(layer "F.Cu")
		(net "IO_L24P_16")
	)
	(segment
		(start 117.84711 -41.823132)
		(end 118.346982 -41.32326)
		(width 0.11938)
		(layer "F.Cu")
		(net "IO_L24N_34")
	)
	(segment
		(start 108.0516 -58.3184)
		(end 104.847136 -55.113936)
		(width 0.11938)
		(layer "F.Cu")
		(net "IO_L24N_16")
	)
	(segment
		(start 104.847136 -55.113936)
		(end 104.847136 -54.823106)
		(width 0.11938)
		(layer "F.Cu")
		(net "IO_L24N_16")
	)
	(segment
		(start 107.442 -59.7916)
		(end 106.7308 -59.0804)
		(width 0.11938)
		(layer "F.Cu")
		(net "IO_L23P_16")
	)
	(segment
		(start 102.362 -54.308248)
		(end 102.84714 -53.823108)
		(width 0.11938)
		(layer "F.Cu")
		(net "IO_L23P_16")
	)
	(segment
		(start 106.7308 -59.0804)
		(end 104.632506 -59.0804)
		(width 0.11938)
		(layer "F.Cu")
		(net "IO_L23P_16")
	)
	(segment
		(start 102.362 -56.809894)
		(end 102.362 -54.308248)
		(width 0.11938)
		(layer "F.Cu")
		(net "IO_L23P_16")
	)
	(segment
		(start 104.632506 -59.0804)
		(end 102.362 -56.809894)
		(width 0.11938)
		(layer "F.Cu")
		(net "IO_L23P_16")
	)
	(segment
		(start 117.84711 -39.823136)
		(end 118.346982 -39.323264)
		(width 0.11938)
		(layer "F.Cu")
		(net "IO_L23N_34")
	)
	(via
		(at 118.346982 -39.323264)
		(size 0.4572)
		(drill 0.2032)
		(layers "F.Cu" "B.Cu")
		(net "IO_L23N_34")
	)
	(segment
		(start 118.685564 -39.323264)
		(end 119.1895 -39.8272)
		(width 0.127)
		(layer "In7.Cu")
		(net "IO_L23N_34")
	)
	(segment
		(start 118.346982 -39.323264)
		(end 118.685564 -39.323264)
		(width 0.127)
		(layer "In7.Cu")
		(net "IO_L23N_34")
	)
	(segment
		(start 119.1895 -39.8272)
		(end 123.46686 -39.8272)
		(width 0.127)
		(layer "In7.Cu")
		(net "IO_L23N_34")
	)
	(segment
		(start 124.0155 -39.27856)
		(end 124.0155 -38.5445)
		(width 0.127)
		(layer "In7.Cu")
		(net "IO_L23N_34")
	)
	(segment
		(start 123.46686 -39.8272)
		(end 124.0155 -39.27856)
		(width 0.127)
		(layer "In7.Cu")
		(net "IO_L23N_34")
	)
	(segment
		(start 124.0155 -38.5445)
		(end 124.841 -37.719)
		(width 0.127)
		(layer "In7.Cu")
		(net "IO_L23N_34")
	)
	(segment
		(start 100.076 -56.769)
		(end 100.593652 -56.251348)
		(width 0.11938)
		(layer "F.Cu")
		(net "IO_L23N_16")
	)
	(segment
		(start 100.593652 -56.251348)
		(end 100.593652 -55.743348)
		(width 0.11938)
		(layer "F.Cu")
		(net "IO_L23N_16")
	)
	(segment
		(start 101.346 -54.991)
		(end 101.346 -54.32425)
		(width 0.11938)
		(layer "F.Cu")
		(net "IO_L23N_16")
	)
	(segment
		(start 101.346 -54.32425)
		(end 101.847142 -53.823108)
		(width 0.11938)
		(layer "F.Cu")
		(net "IO_L23N_16")
	)
	(segment
		(start 100.593652 -55.743348)
		(end 101.346 -54.991)
		(width 0.11938)
		(layer "F.Cu")
		(net "IO_L23N_16")
	)
	(segment
		(start 119.284242 -40.386)
		(end 118.847108 -40.823134)
		(width 0.11938)
		(layer "F.Cu")
		(net "IO_L22P_34")
	)
	(segment
		(start 123.19 -39.116)
		(end 121.92 -40.386)
		(width 0.11938)
		(layer "F.Cu")
		(net "IO_L22P_34")
	)
	(segment
		(start 121.92 -40.386)
		(end 119.284242 -40.386)
		(width 0.11938)
		(layer "F.Cu")
		(net "IO_L22P_34")
	)
	(segment
		(start 102.84714 -55.60314)
		(end 102.84714 -54.823106)
		(width 0.11938)
		(layer "F.Cu")
		(net "IO_L22P_16")
	)
	(segment
		(start 105.3846 -58.1406)
		(end 102.84714 -55.60314)
		(width 0.11938)
		(layer "F.Cu")
		(net "IO_L22P_16")
	)
	(segment
		(start 105.3846 -58.3692)
		(end 105.3846 -58.1406)
		(width 0.11938)
		(layer "F.Cu")
		(net "IO_L22P_16")
	)
	(segment
		(start 101.847142 -54.823106)
		(end 101.847142 -55.407306)
		(width 0.11938)
		(layer "F.Cu")
		(net "IO_L22N_16")
	)
	(segment
		(start 101.9556 -57.531)
		(end 104.2162 -59.7916)
		(width 0.11938)
		(layer "F.Cu")
		(net "IO_L22N_16")
	)
	(segment
		(start 104.2162 -59.7916)
		(end 105.6894 -59.7916)
		(width 0.11938)
		(layer "F.Cu")
		(net "IO_L22N_16")
	)
	(segment
		(start 101.847142 -55.407306)
		(end 101.9556 -55.515764)
		(width 0.11938)
		(layer "F.Cu")
		(net "IO_L22N_16")
	)
	(segment
		(start 101.9556 -55.515764)
		(end 101.9556 -57.531)
		(width 0.11938)
		(layer "F.Cu")
		(net "IO_L22N_16")
	)
	(segment
		(start 95.25 -53.34)
		(end 96.266 -54.356)
		(width 0.11938)
		(layer "F.Cu")
		(net "IO_L21P_16")
	)
	(segment
		(start 99.314 -54.356)
		(end 99.846892 -53.823108)
		(width 0.11938)
		(layer "F.Cu")
		(net "IO_L21P_16")
	)
	(segment
		(start 96.266 -54.356)
		(end 99.314 -54.356)
		(width 0.11938)
		(layer "F.Cu")
		(net "IO_L21P_16")
	)
	(segment
		(start 115.847114 -40.823134)
		(end 116.346986 -40.323262)
		(width 0.11938)
		(layer "F.Cu")
		(net "IO_L21N_34")
	)
	(via
		(at 116.346986 -40.323262)
		(size 0.4572)
		(drill 0.2032)
		(layers "F.Cu" "B.Cu")
		(net "IO_L21N_34")
	)
	(segment
		(start 118.90502 -40.1828)
		(end 121.2596 -40.1828)
		(width 0.1016)
		(layer "In7.Cu")
		(net "IO_L21N_34")
	)
	(segment
		(start 118.58244 -39.86022)
		(end 118.90502 -40.1828)
		(width 0.1016)
		(layer "In7.Cu")
		(net "IO_L21N_34")
	)
	(segment
		(start 116.346986 -40.323262)
		(end 116.810028 -39.86022)
		(width 0.1016)
		(layer "In7.Cu")
		(net "IO_L21N_34")
	)
	(segment
		(start 124.968254 -40.259)
		(end 125.476 -39.751254)
		(width 0.127)
		(layer "In7.Cu")
		(net "IO_L21N_34")
	)
	(segment
		(start 121.3358 -40.259)
		(end 124.968254 -40.259)
		(width 0.127)
		(layer "In7.Cu")
		(net "IO_L21N_34")
	)
	(segment
		(start 125.476 -39.751254)
		(end 125.476 -38.608)
		(width 0.127)
		(layer "In7.Cu")
		(net "IO_L21N_34")
	)
	(segment
		(start 125.476 -38.608)
		(end 126.365 -37.719)
		(width 0.127)
		(layer "In7.Cu")
		(net "IO_L21N_34")
	)
	(segment
		(start 116.810028 -39.86022)
		(end 118.58244 -39.86022)
		(width 0.1016)
		(layer "In7.Cu")
		(net "IO_L21N_34")
	)
	(segment
		(start 121.2596 -40.1828)
		(end 121.3358 -40.259)
		(width 0.127)
		(layer "In7.Cu")
		(net "IO_L21N_34")
	)
	(segment
		(start 97.003108 -53.823108)
		(end 98.846894 -53.823108)
		(width 0.11938)
		(layer "F.Cu")
		(net "IO_L21N_16")
	)
	(segment
		(start 96.52 -53.34)
		(end 97.003108 -53.823108)
		(width 0.11938)
		(layer "F.Cu")
		(net "IO_L21N_16")
	)
	(segment
		(start 119.847106 -39.823136)
		(end 120.346978 -39.323264)
		(width 0.11938)
		(layer "F.Cu")
		(net "IO_L20P_34")
	)
	(segment
		(start 99.06 -56.609996)
		(end 100.84689 -54.823106)
		(width 0.11938)
		(layer "F.Cu")
		(net "IO_L20P_16")
	)
	(segment
		(start 99.06 -59.055)
		(end 99.06 -56.609996)
		(width 0.11938)
		(layer "F.Cu")
		(net "IO_L20P_16")
	)
	(segment
		(start 119.847106 -38.823138)
		(end 120.346978 -38.323266)
		(width 0.11938)
		(layer "F.Cu")
		(net "IO_L20N_34")
	)
	(segment
		(start 98.425 -57.912)
		(end 98.425 -56.244998)
		(width 0.11938)
		(layer "F.Cu")
		(net "IO_L20N_16")
	)
	(segment
		(start 98.425 -56.244998)
		(end 99.846892 -54.823106)
		(width 0.11938)
		(layer "F.Cu")
		(net "IO_L20N_16")
	)
	(segment
		(start 97.282 -59.055)
		(end 98.425 -57.912)
		(width 0.11938)
		(layer "F.Cu")
		(net "IO_L20N_16")
	)
	(segment
		(start 71.871078 -86.476078)
		(end 77.2795 -86.476078)
		(width 0.11938)
		(layer "F.Cu")
		(net "ICP10100_I2C_SDA")
	)
	(segment
		(start 77.978 -78.867)
		(end 76.327 -77.216)
		(width 0.11938)
		(layer "F.Cu")
		(net "ICP10100_I2C_SDA")
	)
	(segment
		(start 83.312 -77.851)
		(end 82.296 -78.867)
		(width 0.11938)
		(layer "F.Cu")
		(net "ICP10100_I2C_SDA")
	)
	(segment
		(start 21.17852 -62.91072)
		(end 21.17852 -61.6585)
		(width 0.11938)
		(layer "F.Cu")
		(net "ICP10100_I2C_SDA")
	)
	(segment
		(start 82.296 -78.867)
		(end 77.978 -78.867)
		(width 0.11938)
		(layer "F.Cu")
		(net "ICP10100_I2C_SDA")
	)
	(segment
		(start 21.4884 -63.2206)
		(end 21.17852 -62.91072)
		(width 0.11938)
		(layer "F.Cu")
		(net "ICP10100_I2C_SDA")
	)
	(segment
		(start 73.830434 -77.216)
		(end 71.501 -79.545434)
		(width 0.11938)
		(layer "F.Cu")
		(net "ICP10100_I2C_SDA")
	)
	(segment
		(start 71.501 -86.106)
		(end 71.871078 -86.476078)
		(width 0.11938)
		(layer "F.Cu")
		(net "ICP10100_I2C_SDA")
	)
	(segment
		(start 71.501 -79.545434)
		(end 71.501 -86.106)
		(width 0.11938)
		(layer "F.Cu")
		(net "ICP10100_I2C_SDA")
	)
	(segment
		(start 76.327 -77.216)
		(end 73.830434 -77.216)
		(width 0.11938)
		(layer "F.Cu")
		(net "ICP10100_I2C_SDA")
	)
	(via
		(at 83.312 -77.851)
		(size 0.508)
		(drill 0.254)
		(layers "F.Cu" "B.Cu")
		(net "ICP10100_I2C_SDA")
	)
	(via
		(at 21.4884 -63.2206)
		(size 0.4572)
		(drill 0.2032)
		(layers "F.Cu" "B.Cu")
		(net "ICP10100_I2C_SDA")
	)
	(segment
		(start 66.873882 -83.25358)
		(end 73.292462 -76.835)
		(width 0.11938)
		(layer "B.Cu")
		(net "ICP10100_I2C_SDA")
	)
	(segment
		(start 52.507388 -69.28485)
		(end 57.774078 -69.28485)
		(width 0.11938)
		(layer "B.Cu")
		(net "ICP10100_I2C_SDA")
	)
	(segment
		(start 60.29452 -71.805292)
		(end 60.29452 -81.9023)
		(width 0.11938)
		(layer "B.Cu")
		(net "ICP10100_I2C_SDA")
	)
	(segment
		(start 81.652364 -78.09738)
		(end 81.652364 -78.62062)
		(width 0.11938)
		(layer "B.Cu")
		(net "ICP10100_I2C_SDA")
	)
	(segment
		(start 73.292462 -76.835)
		(end 76.835 -76.835)
		(width 0.11938)
		(layer "B.Cu")
		(net "ICP10100_I2C_SDA")
	)
	(segment
		(start 80.905604 -78.74)
		(end 81.024984 -78.62062)
		(width 0.11938)
		(layer "B.Cu")
		(net "ICP10100_I2C_SDA")
	)
	(segment
		(start 61.6458 -83.25358)
		(end 66.873882 -83.25358)
		(width 0.11938)
		(layer "B.Cu")
		(net "ICP10100_I2C_SDA")
	)
	(segment
		(start 21.4884 -63.2206)
		(end 22.31009 -64.04229)
		(width 0.11938)
		(layer "B.Cu")
		(net "ICP10100_I2C_SDA")
	)
	(segment
		(start 81.771744 -78.74)
		(end 82.423 -78.74)
		(width 0.11938)
		(layer "B.Cu")
		(net "ICP10100_I2C_SDA")
	)
	(segment
		(start 20.447 -62.0776)
		(end 21.59 -62.0776)
		(width 0.11938)
		(layer "B.Cu")
		(net "ICP10100_I2C_SDA")
	)
	(segment
		(start 81.144364 -77.978)
		(end 81.532984 -77.978)
		(width 0.11938)
		(layer "B.Cu")
		(net "ICP10100_I2C_SDA")
	)
	(segment
		(start 81.532984 -77.978)
		(end 81.652364 -78.09738)
		(width 0.11938)
		(layer "B.Cu")
		(net "ICP10100_I2C_SDA")
	)
	(segment
		(start 81.024984 -78.62062)
		(end 81.024984 -78.09738)
		(width 0.11938)
		(layer "B.Cu")
		(net "ICP10100_I2C_SDA")
	)
	(segment
		(start 81.024984 -78.09738)
		(end 81.144364 -77.978)
		(width 0.11938)
		(layer "B.Cu")
		(net "ICP10100_I2C_SDA")
	)
	(segment
		(start 22.31009 -64.04229)
		(end 23.099014 -64.04229)
		(width 0.11938)
		(layer "B.Cu")
		(net "ICP10100_I2C_SDA")
	)
	(segment
		(start 82.423 -78.74)
		(end 83.312 -77.851)
		(width 0.11938)
		(layer "B.Cu")
		(net "ICP10100_I2C_SDA")
	)
	(segment
		(start 78.74 -78.74)
		(end 80.905604 -78.74)
		(width 0.11938)
		(layer "B.Cu")
		(net "ICP10100_I2C_SDA")
	)
	(segment
		(start 76.835 -76.835)
		(end 78.74 -78.74)
		(width 0.11938)
		(layer "B.Cu")
		(net "ICP10100_I2C_SDA")
	)
	(segment
		(start 60.29452 -81.9023)
		(end 61.6458 -83.25358)
		(width 0.11938)
		(layer "B.Cu")
		(net "ICP10100_I2C_SDA")
	)
	(segment
		(start 81.652364 -78.62062)
		(end 81.771744 -78.74)
		(width 0.11938)
		(layer "B.Cu")
		(net "ICP10100_I2C_SDA")
	)
	(segment
		(start 21.4884 -63.2206)
		(end 21.59 -63.119)
		(width 0.11938)
		(layer "B.Cu")
		(net "ICP10100_I2C_SDA")
	)
	(segment
		(start 45.706538 -62.484)
		(end 52.507388 -69.28485)
		(width 0.11938)
		(layer "B.Cu")
		(net "ICP10100_I2C_SDA")
	)
	(segment
		(start 24.657304 -62.484)
		(end 45.706538 -62.484)
		(width 0.11938)
		(layer "B.Cu")
		(net "ICP10100_I2C_SDA")
	)
	(segment
		(start 57.774078 -69.28485)
		(end 60.29452 -71.805292)
		(width 0.11938)
		(layer "B.Cu")
		(net "ICP10100_I2C_SDA")
	)
	(segment
		(start 21.59 -63.119)
		(end 21.59 -62.0776)
		(width 0.11938)
		(layer "B.Cu")
		(net "ICP10100_I2C_SDA")
	)
	(segment
		(start 23.099014 -64.04229)
		(end 24.657304 -62.484)
		(width 0.11938)
		(layer "B.Cu")
		(net "ICP10100_I2C_SDA")
	)
	(segment
		(start 75.946 -77.851)
		(end 73.914 -77.851)
		(width 0.11938)
		(layer "F.Cu")
		(net "ICP10100_I2C_SCL")
	)
	(segment
		(start 73.914 -77.851)
		(end 72.009 -79.756)
		(width 0.11938)
		(layer "F.Cu")
		(net "ICP10100_I2C_SCL")
	)
	(segment
		(start 77.47 -79.375)
		(end 75.946 -77.851)
		(width 0.11938)
		(layer "F.Cu")
		(net "ICP10100_I2C_SCL")
	)
	(segment
		(start 82.931 -79.375)
		(end 77.47 -79.375)
		(width 0.11938)
		(layer "F.Cu")
		(net "ICP10100_I2C_SCL")
	)
	(segment
		(start 84.455 -77.851)
		(end 82.931 -79.375)
		(width 0.11938)
		(layer "F.Cu")
		(net "ICP10100_I2C_SCL")
	)
	(segment
		(start 72.009 -79.756)
		(end 72.009 -85.598)
		(width 0.11938)
		(layer "F.Cu")
		(net "ICP10100_I2C_SCL")
	)
	(segment
		(start 72.009 -85.598)
		(end 72.237092 -85.826092)
		(width 0.11938)
		(layer "F.Cu")
		(net "ICP10100_I2C_SCL")
	)
	(segment
		(start 72.237092 -85.826092)
		(end 77.2795 -85.826092)
		(width 0.11938)
		(layer "F.Cu")
		(net "ICP10100_I2C_SCL")
	)
	(segment
		(start 20.2184 -63.2206)
		(end 20.52828 -62.91072)
		(width 0.11938)
		(layer "F.Cu")
		(net "ICP10100_I2C_SCL")
	)
	(segment
		(start 20.52828 -62.91072)
		(end 20.52828 -61.6585)
		(width 0.11938)
		(layer "F.Cu")
		(net "ICP10100_I2C_SCL")
	)
	(via
		(at 84.455 -77.851)
		(size 0.508)
		(drill 0.254)
		(layers "F.Cu" "B.Cu")
		(net "ICP10100_I2C_SCL")
	)
	(via
		(at 20.2184 -63.2206)
		(size 0.4572)
		(drill 0.2032)
		(layers "F.Cu" "B.Cu")
		(net "ICP10100_I2C_SCL")
	)
	(segment
		(start 78.359 -79.248)
		(end 76.454 -77.343)
		(width 0.11938)
		(layer "B.Cu")
		(net "ICP10100_I2C_SCL")
	)
	(segment
		(start 73.406 -77.343)
		(end 67.056 -83.693)
		(width 0.11938)
		(layer "B.Cu")
		(net "ICP10100_I2C_SCL")
	)
	(segment
		(start 84.455 -77.851)
		(end 83.058 -79.248)
		(width 0.11938)
		(layer "B.Cu")
		(net "ICP10100_I2C_SCL")
	)
	(segment
		(start 21.47951 -64.48171)
		(end 20.2184 -63.2206)
		(width 0.11938)
		(layer "B.Cu")
		(net "ICP10100_I2C_SCL")
	)
	(segment
		(start 76.454 -77.343)
		(end 73.406 -77.343)
		(width 0.11938)
		(layer "B.Cu")
		(net "ICP10100_I2C_SCL")
	)
	(segment
		(start 61.463682 -83.693)
		(end 59.8551 -82.084418)
		(width 0.11938)
		(layer "B.Cu")
		(net "ICP10100_I2C_SCL")
	)
	(segment
		(start 23.281132 -64.48171)
		(end 21.47951 -64.48171)
		(width 0.11938)
		(layer "B.Cu")
		(net "ICP10100_I2C_SCL")
	)
	(segment
		(start 52.32527 -69.72427)
		(end 45.593 -62.992)
		(width 0.11938)
		(layer "B.Cu")
		(net "ICP10100_I2C_SCL")
	)
	(segment
		(start 45.593 -62.992)
		(end 24.770842 -62.992)
		(width 0.11938)
		(layer "B.Cu")
		(net "ICP10100_I2C_SCL")
	)
	(segment
		(start 19.5072 -63.2206)
		(end 19.304 -63.0174)
		(width 0.11938)
		(layer "B.Cu")
		(net "ICP10100_I2C_SCL")
	)
	(segment
		(start 20.2184 -63.2206)
		(end 19.5072 -63.2206)
		(width 0.11938)
		(layer "B.Cu")
		(net "ICP10100_I2C_SCL")
	)
	(segment
		(start 67.056 -83.693)
		(end 61.463682 -83.693)
		(width 0.11938)
		(layer "B.Cu")
		(net "ICP10100_I2C_SCL")
	)
	(segment
		(start 83.058 -79.248)
		(end 78.359 -79.248)
		(width 0.11938)
		(layer "B.Cu")
		(net "ICP10100_I2C_SCL")
	)
	(segment
		(start 59.8551 -82.084418)
		(end 59.8551 -71.98741)
		(width 0.11938)
		(layer "B.Cu")
		(net "ICP10100_I2C_SCL")
	)
	(segment
		(start 24.770842 -62.992)
		(end 23.281132 -64.48171)
		(width 0.11938)
		(layer "B.Cu")
		(net "ICP10100_I2C_SCL")
	)
	(segment
		(start 19.304 -63.0174)
		(end 19.304 -62.0776)
		(width 0.11938)
		(layer "B.Cu")
		(net "ICP10100_I2C_SCL")
	)
	(segment
		(start 59.8551 -71.98741)
		(end 57.59196 -69.72427)
		(width 0.11938)
		(layer "B.Cu")
		(net "ICP10100_I2C_SCL")
	)
	(segment
		(start 19.304 -62.0776)
		(end 18.161 -62.0776)
		(width 0.11938)
		(layer "B.Cu")
		(net "ICP10100_I2C_SCL")
	)
	(segment
		(start 57.59196 -69.72427)
		(end 52.32527 -69.72427)
		(width 0.11938)
		(layer "B.Cu")
		(net "ICP10100_I2C_SCL")
	)
	(segment
		(start 127.762 -94.361)
		(end 126.746 -95.377)
		(width 0.11938)
		(layer "F.Cu")
		(net "GPS_UART_TXD")
	)
	(segment
		(start 126.746 -96.012)
		(end 125.487938 -97.270062)
		(width 0.11938)
		(layer "F.Cu")
		(net "GPS_UART_TXD")
	)
	(segment
		(start 125.487938 -97.270062)
		(end 124.853446 -97.270062)
		(width 0.11938)
		(layer "F.Cu")
		(net "GPS_UART_TXD")
	)
	(segment
		(start 126.746 -95.377)
		(end 126.746 -96.012)
		(width 0.11938)
		(layer "F.Cu")
		(net "GPS_UART_TXD")
	)
	(segment
		(start 126.619 -90.0684)
		(end 127.762 -90.0684)
		(width 0.11938)
		(layer "F.Cu")
		(net "GPS_UART_TXD")
	)
	(segment
		(start 127.762 -90.0684)
		(end 127.762 -94.361)
		(width 0.11938)
		(layer "F.Cu")
		(net "GPS_UART_TXD")
	)
	(via
		(at 127.762 -90.0684)
		(size 0.4572)
		(drill 0.2032)
		(layers "F.Cu" "B.Cu")
		(net "GPS_UART_TXD")
	)
	(segment
		(start 126.619 -90.0684)
		(end 127.762 -90.0684)
		(width 0.11938)
		(layer "B.Cu")
		(net "GPS_UART_TXD")
	)
	(segment
		(start 125.349 -90.0684)
		(end 124.079 -90.0684)
		(width 0.11938)
		(layer "F.Cu")
		(net "GPS_UART_RXD")
	)
	(segment
		(start 126.217934 -95.270066)
		(end 127.32258 -94.16542)
		(width 0.11938)
		(layer "F.Cu")
		(net "GPS_UART_RXD")
	)
	(segment
		(start 127.32258 -94.16542)
		(end 127.32258 -91.30538)
		(width 0.11938)
		(layer "F.Cu")
		(net "GPS_UART_RXD")
	)
	(segment
		(start 126.550166 -91.30538)
		(end 126.550166 -91.95562)
		(width 0.11938)
		(layer "F.Cu")
		(net "GPS_UART_RXD")
	)
	(segment
		(start 126.669546 -91.186)
		(end 126.550166 -91.30538)
		(width 0.11938)
		(layer "F.Cu")
		(net "GPS_UART_RXD")
	)
	(segment
		(start 125.349 -91.186)
		(end 125.349 -90.0684)
		(width 0.11938)
		(layer "F.Cu")
		(net "GPS_UART_RXD")
	)
	(segment
		(start 127.2032 -91.186)
		(end 126.669546 -91.186)
		(width 0.11938)
		(layer "F.Cu")
		(net "GPS_UART_RXD")
	)
	(segment
		(start 127.32258 -91.30538)
		(end 127.2032 -91.186)
		(width 0.11938)
		(layer "F.Cu")
		(net "GPS_UART_RXD")
	)
	(segment
		(start 126.550166 -91.95562)
		(end 126.430786 -92.075)
		(width 0.11938)
		(layer "F.Cu")
		(net "GPS_UART_RXD")
	)
	(segment
		(start 124.853446 -95.270066)
		(end 126.217934 -95.270066)
		(width 0.11938)
		(layer "F.Cu")
		(net "GPS_UART_RXD")
	)
	(segment
		(start 125.922786 -91.95562)
		(end 125.922786 -91.30538)
		(width 0.11938)
		(layer "F.Cu")
		(net "GPS_UART_RXD")
	)
	(segment
		(start 126.042166 -92.075)
		(end 125.922786 -91.95562)
		(width 0.11938)
		(layer "F.Cu")
		(net "GPS_UART_RXD")
	)
	(segment
		(start 125.803406 -91.186)
		(end 125.349 -91.186)
		(width 0.11938)
		(layer "F.Cu")
		(net "GPS_UART_RXD")
	)
	(segment
		(start 125.922786 -91.30538)
		(end 125.803406 -91.186)
		(width 0.11938)
		(layer "F.Cu")
		(net "GPS_UART_RXD")
	)
	(segment
		(start 126.430786 -92.075)
		(end 126.042166 -92.075)
		(width 0.11938)
		(layer "F.Cu")
		(net "GPS_UART_RXD")
	)
	(via
		(at 125.349 -91.186)
		(size 0.4572)
		(drill 0.2032)
		(layers "F.Cu" "B.Cu")
		(net "GPS_UART_RXD")
	)
	(segment
		(start 125.349 -90.0684)
		(end 125.349 -91.186)
		(width 0.11938)
		(layer "B.Cu")
		(net "GPS_UART_RXD")
	)
	(segment
		(start 120.269 -90.0684)
		(end 118.8466 -90.0684)
		(width 0.11938)
		(layer "F.Cu")
		(net "GPS_RST_N")
	)
	(segment
		(start 118.237 -90.678)
		(end 118.618 -90.297)
		(width 0.11938)
		(layer "F.Cu")
		(net "GPS_RST_N")
	)
	(segment
		(start 118.8466 -90.0684)
		(end 118.618 -90.297)
		(width 0.11938)
		(layer "F.Cu")
		(net "GPS_RST_N")
	)
	(segment
		(start 121.578624 -97.270062)
		(end 120.053862 -97.270062)
		(width 0.11938)
		(layer "F.Cu")
		(net "GPS_RST_N")
	)
	(segment
		(start 120.053862 -97.270062)
		(end 119.6594 -96.8756)
		(width 0.11938)
		(layer "F.Cu")
		(net "GPS_RST_N")
	)
	(segment
		(start 118.237 -93.9292)
		(end 118.237 -90.678)
		(width 0.11938)
		(layer "F.Cu")
		(net "GPS_RST_N")
	)
	(segment
		(start 119.6594 -95.3516)
		(end 118.237 -93.9292)
		(width 0.11938)
		(layer "F.Cu")
		(net "GPS_RST_N")
	)
	(segment
		(start 121.539 -90.0684)
		(end 120.269 -90.0684)
		(width 0.11938)
		(layer "F.Cu")
		(net "GPS_RST_N")
	)
	(segment
		(start 119.6594 -96.8756)
		(end 119.6594 -95.3516)
		(width 0.11938)
		(layer "F.Cu")
		(net "GPS_RST_N")
	)
	(segment
		(start 120.2944 -90.1954)
		(end 118.7196 -90.1954)
		(width 0.11938)
		(layer "B.Cu")
		(net "GPS_RST_N")
	)
	(segment
		(start 118.7196 -90.1954)
		(end 118.618 -90.297)
		(width 0.11938)
		(layer "B.Cu")
		(net "GPS_RST_N")
	)
	(segment
		(start 124.079 -91.419934)
		(end 124.853446 -92.19438)
		(width 0.11938)
		(layer "F.Cu")
		(net "GPSTP2_OUT")
	)
	(segment
		(start 124.079 -91.186)
		(end 124.079 -91.419934)
		(width 0.11938)
		(layer "F.Cu")
		(net "GPSTP2_OUT")
	)
	(segment
		(start 124.853446 -92.19438)
		(end 124.853446 -93.27007)
		(width 0.11938)
		(layer "F.Cu")
		(net "GPSTP2_OUT")
	)
	(via
		(at 124.079 -91.186)
		(size 0.4572)
		(drill 0.2032)
		(layers "F.Cu" "B.Cu")
		(net "GPSTP2_OUT")
	)
	(segment
		(start 124.079 -90.0684)
		(end 124.079 -91.186)
		(width 0.11938)
		(layer "B.Cu")
		(net "GPSTP2_OUT")
	)
	(segment
		(start 120.924066 -95.270066)
		(end 119.497348 -93.843348)
		(width 0.11938)
		(layer "F.Cu")
		(net "GPSTP1_OUT")
	)
	(segment
		(start 119.3292 -91.2876)
		(end 118.8974 -91.7194)
		(width 0.11938)
		(layer "F.Cu")
		(net "GPSTP1_OUT")
	)
	(segment
		(start 121.5898 -91.2876)
		(end 119.3292 -91.2876)
		(width 0.11938)
		(layer "F.Cu")
		(net "GPSTP1_OUT")
	)
	(segment
		(start 118.8974 -91.7194)
		(end 118.8974 -93.2434)
		(width 0.11938)
		(layer "F.Cu")
		(net "GPSTP1_OUT")
	)
	(segment
		(start 122.809 -90.0684)
		(end 121.5898 -91.2876)
		(width 0.11938)
		(layer "F.Cu")
		(net "GPSTP1_OUT")
	)
	(segment
		(start 118.8974 -93.2434)
		(end 119.497348 -93.843348)
		(width 0.11938)
		(layer "F.Cu")
		(net "GPSTP1_OUT")
	)
	(segment
		(start 121.578624 -95.270066)
		(end 120.924066 -95.270066)
		(width 0.11938)
		(layer "F.Cu")
		(net "GPSTP1_OUT")
	)
	(via
		(at 119.497348 -93.843348)
		(size 0.4572)
		(drill 0.2032)
		(layers "F.Cu" "B.Cu")
		(net "GPSTP1_OUT")
	)
	(segment
		(start 114.34699 -46.322996)
		(end 113.847118 -45.823124)
		(width 0.11938)
		(layer "F.Cu")
		(net "FPGA_TMS")
	)
	(via
		(at 114.34699 -46.322996)
		(size 0.4572)
		(drill 0.2032)
		(layers "F.Cu" "B.Cu")
		(net "FPGA_TMS")
	)
	(via
		(at 137.033 -74.168)
		(size 0.508)
		(drill 0.254)
		(layers "F.Cu" "B.Cu")
		(net "FPGA_TMS")
	)
	(segment
		(start 139.7508 -74.2315)
		(end 138.4808 -74.2315)
		(width 0.11938)
		(layer "B.Cu")
		(net "FPGA_TMS")
	)
	(segment
		(start 139.5984 -73.3044)
		(end 139.7508 -73.4568)
		(width 0.11938)
		(layer "B.Cu")
		(net "FPGA_TMS")
	)
	(segment
		(start 137.0965 -74.2315)
		(end 138.4808 -74.2315)
		(width 0.11938)
		(layer "B.Cu")
		(net "FPGA_TMS")
	)
	(segment
		(start 137.033 -74.168)
		(end 137.0965 -74.2315)
		(width 0.11938)
		(layer "B.Cu")
		(net "FPGA_TMS")
	)
	(segment
		(start 139.7508 -73.4568)
		(end 139.7508 -74.2315)
		(width 0.11938)
		(layer "B.Cu")
		(net "FPGA_TMS")
	)
	(segment
		(start 139.5984 -72.898)
		(end 139.5984 -73.3044)
		(width 0.11938)
		(layer "B.Cu")
		(net "FPGA_TMS")
	)
	(segment
		(start 125.6665 -55.6895)
		(end 125.6665 -54.606952)
		(width 0.127)
		(layer "In7.Cu")
		(net "FPGA_TMS")
	)
	(segment
		(start 137.033 -74.168)
		(end 137.0076 -74.1934)
		(width 0.127)
		(layer "In7.Cu")
		(net "FPGA_TMS")
	)
	(segment
		(start 125.6665 -54.606952)
		(end 125.1585 -54.098952)
		(width 0.127)
		(layer "In7.Cu")
		(net "FPGA_TMS")
	)
	(segment
		(start 136.051544 -72.9488)
		(end 135.848344 -73.152)
		(width 0.127)
		(layer "In7.Cu")
		(net "FPGA_TMS")
	)
	(segment
		(start 121.75109 -47.793656)
		(end 120.85955 -46.902116)
		(width 0.127)
		(layer "In7.Cu")
		(net "FPGA_TMS")
	)
	(segment
		(start 125.1585 -52.769262)
		(end 124.841 -52.450746)
		(width 0.127)
		(layer "In7.Cu")
		(net "FPGA_TMS")
	)
	(segment
		(start 114.737388 -46.713394)
		(end 114.34699 -46.322996)
		(width 0.1016)
		(layer "In7.Cu")
		(net "FPGA_TMS")
	)
	(segment
		(start 135.848344 -74.168)
		(end 135.721344 -74.295)
		(width 0.127)
		(layer "In7.Cu")
		(net "FPGA_TMS")
	)
	(segment
		(start 118.149116 -46.902116)
		(end 117.960394 -46.713394)
		(width 0.1016)
		(layer "In7.Cu")
		(net "FPGA_TMS")
	)
	(segment
		(start 124.841 -49.276)
		(end 123.358656 -47.793656)
		(width 0.127)
		(layer "In7.Cu")
		(net "FPGA_TMS")
	)
	(segment
		(start 117.960394 -46.713394)
		(end 114.737388 -46.713394)
		(width 0.1016)
		(layer "In7.Cu")
		(net "FPGA_TMS")
	)
	(segment
		(start 136.610344 -74.1934)
		(end 136.483344 -74.0664)
		(width 0.127)
		(layer "In7.Cu")
		(net "FPGA_TMS")
	)
	(segment
		(start 125.1585 -54.098952)
		(end 125.1585 -52.769262)
		(width 0.127)
		(layer "In7.Cu")
		(net "FPGA_TMS")
	)
	(segment
		(start 137.0076 -74.1934)
		(end 136.610344 -74.1934)
		(width 0.127)
		(layer "In7.Cu")
		(net "FPGA_TMS")
	)
	(segment
		(start 131.191 -70.4596)
		(end 131.191 -61.214)
		(width 0.127)
		(layer "In7.Cu")
		(net "FPGA_TMS")
	)
	(segment
		(start 120.85955 -46.902116)
		(end 118.149116 -46.902116)
		(width 0.127)
		(layer "In7.Cu")
		(net "FPGA_TMS")
	)
	(segment
		(start 135.721344 -74.295)
		(end 135.0264 -74.295)
		(width 0.127)
		(layer "In7.Cu")
		(net "FPGA_TMS")
	)
	(segment
		(start 136.483344 -73.152)
		(end 136.280144 -72.9488)
		(width 0.127)
		(layer "In7.Cu")
		(net "FPGA_TMS")
	)
	(segment
		(start 136.280144 -72.9488)
		(end 136.051544 -72.9488)
		(width 0.127)
		(layer "In7.Cu")
		(net "FPGA_TMS")
	)
	(segment
		(start 131.191 -61.214)
		(end 125.6665 -55.6895)
		(width 0.127)
		(layer "In7.Cu")
		(net "FPGA_TMS")
	)
	(segment
		(start 135.0264 -74.295)
		(end 131.191 -70.4596)
		(width 0.127)
		(layer "In7.Cu")
		(net "FPGA_TMS")
	)
	(segment
		(start 136.483344 -74.0664)
		(end 136.483344 -73.152)
		(width 0.127)
		(layer "In7.Cu")
		(net "FPGA_TMS")
	)
	(segment
		(start 123.358656 -47.793656)
		(end 121.75109 -47.793656)
		(width 0.127)
		(layer "In7.Cu")
		(net "FPGA_TMS")
	)
	(segment
		(start 135.848344 -73.152)
		(end 135.848344 -74.168)
		(width 0.127)
		(layer "In7.Cu")
		(net "FPGA_TMS")
	)
	(segment
		(start 124.841 -52.450746)
		(end 124.841 -49.276)
		(width 0.127)
		(layer "In7.Cu")
		(net "FPGA_TMS")
	)
	(via
		(at 137.154158 -69.881496)
		(size 0.4572)
		(drill 0.2032)
		(layers "F.Cu" "B.Cu")
		(net "FPGA_TDO")
	)
	(via
		(at 127.381 -48.895)
		(size 0.508)
		(drill 0.254)
		(layers "F.Cu" "B.Cu")
		(net "FPGA_TDO")
	)
	(segment
		(start 139.8016 -70.358)
		(end 139.132056 -70.358)
		(width 0.11938)
		(layer "B.Cu")
		(net "FPGA_TDO")
	)
	(segment
		(start 137.656062 -70.3834)
		(end 137.154158 -69.881496)
		(width 0.11938)
		(layer "B.Cu")
		(net "FPGA_TDO")
	)
	(segment
		(start 127.381 -46.736)
		(end 126.94031 -46.29531)
		(width 0.11938)
		(layer "B.Cu")
		(net "FPGA_TDO")
	)
	(segment
		(start 139.8016 -71.501)
		(end 139.8016 -70.358)
		(width 0.11938)
		(layer "B.Cu")
		(net "FPGA_TDO")
	)
	(segment
		(start 138.4808 -70.3834)
		(end 137.656062 -70.3834)
		(width 0.11938)
		(layer "B.Cu")
		(net "FPGA_TDO")
	)
	(segment
		(start 127.381 -48.895)
		(end 127.381 -46.736)
		(width 0.11938)
		(layer "B.Cu")
		(net "FPGA_TDO")
	)
	(segment
		(start 126.94031 -46.29531)
		(end 125.44171 -46.29531)
		(width 0.11938)
		(layer "B.Cu")
		(net "FPGA_TDO")
	)
	(segment
		(start 139.106656 -70.3834)
		(end 138.4808 -70.3834)
		(width 0.11938)
		(layer "B.Cu")
		(net "FPGA_TDO")
	)
	(segment
		(start 125.44171 -46.29531)
		(end 125.1204 -45.974)
		(width 0.11938)
		(layer "B.Cu")
		(net "FPGA_TDO")
	)
	(segment
		(start 139.132056 -70.358)
		(end 139.106656 -70.3834)
		(width 0.11938)
		(layer "B.Cu")
		(net "FPGA_TDO")
	)
	(segment
		(start 139.5476 -64.663066)
		(end 138.76655 -63.882016)
		(width 0.127)
		(layer "In7.Cu")
		(net "FPGA_TDO")
	)
	(segment
		(start 136.695434 -62.484)
		(end 134.724648 -62.484)
		(width 0.127)
		(layer "In7.Cu")
		(net "FPGA_TDO")
	)
	(segment
		(start 127.381 -51.348386)
		(end 127.381 -48.895)
		(width 0.127)
		(layer "In7.Cu")
		(net "FPGA_TDO")
	)
	(segment
		(start 137.738358 -69.881496)
		(end 138.078972 -69.540882)
		(width 0.127)
		(layer "In7.Cu")
		(net "FPGA_TDO")
	)
	(segment
		(start 138.09345 -63.882016)
		(end 136.695434 -62.484)
		(width 0.127)
		(layer "In7.Cu")
		(net "FPGA_TDO")
	)
	(segment
		(start 137.154158 -69.881496)
		(end 137.738358 -69.881496)
		(width 0.127)
		(layer "In7.Cu")
		(net "FPGA_TDO")
	)
	(segment
		(start 139.5476 -66.275966)
		(end 139.5476 -64.663066)
		(width 0.127)
		(layer "In7.Cu")
		(net "FPGA_TDO")
	)
	(segment
		(start 127.5715 -51.538886)
		(end 127.381 -51.348386)
		(width 0.127)
		(layer "In7.Cu")
		(net "FPGA_TDO")
	)
	(segment
		(start 138.078972 -67.744594)
		(end 139.5476 -66.275966)
		(width 0.127)
		(layer "In7.Cu")
		(net "FPGA_TDO")
	)
	(segment
		(start 138.078972 -69.540882)
		(end 138.078972 -67.744594)
		(width 0.127)
		(layer "In7.Cu")
		(net "FPGA_TDO")
	)
	(segment
		(start 128.016 -55.775352)
		(end 128.016 -53.42382)
		(width 0.127)
		(layer "In7.Cu")
		(net "FPGA_TDO")
	)
	(segment
		(start 128.016 -53.42382)
		(end 127.5715 -52.97932)
		(width 0.127)
		(layer "In7.Cu")
		(net "FPGA_TDO")
	)
	(segment
		(start 138.76655 -63.882016)
		(end 138.09345 -63.882016)
		(width 0.127)
		(layer "In7.Cu")
		(net "FPGA_TDO")
	)
	(segment
		(start 134.724648 -62.484)
		(end 128.016 -55.775352)
		(width 0.127)
		(layer "In7.Cu")
		(net "FPGA_TDO")
	)
	(segment
		(start 127.5715 -52.97932)
		(end 127.5715 -51.538886)
		(width 0.127)
		(layer "In7.Cu")
		(net "FPGA_TDO")
	)
	(segment
		(start 112.84712 -45.823124)
		(end 113.346992 -46.322996)
		(width 0.11938)
		(layer "F.Cu")
		(net "FPGA_TDI")
	)
	(via
		(at 136.525 -75.338178)
		(size 0.4572)
		(drill 0.2032)
		(layers "F.Cu" "B.Cu")
		(net "FPGA_TDI")
	)
	(via
		(at 113.346992 -46.322996)
		(size 0.4572)
		(drill 0.2032)
		(layers "F.Cu" "B.Cu")
		(net "FPGA_TDI")
	)
	(segment
		(start 139.8016 -76.708)
		(end 139.132056 -76.708)
		(width 0.11938)
		(layer "B.Cu")
		(net "FPGA_TDI")
	)
	(segment
		(start 136.525 -75.338178)
		(end 136.552178 -75.338178)
		(width 0.11938)
		(layer "B.Cu")
		(net "FPGA_TDI")
	)
	(segment
		(start 139.106656 -76.6826)
		(end 138.4808 -76.6826)
		(width 0.11938)
		(layer "B.Cu")
		(net "FPGA_TDI")
	)
	(segment
		(start 139.132056 -76.708)
		(end 139.106656 -76.6826)
		(width 0.11938)
		(layer "B.Cu")
		(net "FPGA_TDI")
	)
	(segment
		(start 137.8966 -76.6826)
		(end 138.4808 -76.6826)
		(width 0.11938)
		(layer "B.Cu")
		(net "FPGA_TDI")
	)
	(segment
		(start 139.8016 -77.851)
		(end 139.8016 -76.708)
		(width 0.11938)
		(layer "B.Cu")
		(net "FPGA_TDI")
	)
	(segment
		(start 136.552178 -75.338178)
		(end 137.8966 -76.6826)
		(width 0.11938)
		(layer "B.Cu")
		(net "FPGA_TDI")
	)
	(segment
		(start 124.6505 -54.309518)
		(end 125.1585 -54.817518)
		(width 0.127)
		(layer "In7.Cu")
		(net "FPGA_TDI")
	)
	(segment
		(start 113.94059 -46.916594)
		(end 117.59946 -46.916594)
		(width 0.1016)
		(layer "In7.Cu")
		(net "FPGA_TDI")
	)
	(segment
		(start 129.286 -68.224654)
		(end 130.5941 -69.532754)
		(width 0.127)
		(layer "In7.Cu")
		(net "FPGA_TDI")
	)
	(segment
		(start 129.286 -61.463682)
		(end 129.286 -68.224654)
		(width 0.127)
		(layer "In7.Cu")
		(net "FPGA_TDI")
	)
	(segment
		(start 130.5941 -70.650354)
		(end 135.281924 -75.338178)
		(width 0.127)
		(layer "In7.Cu")
		(net "FPGA_TDI")
	)
	(segment
		(start 120.399048 -47.752)
		(end 121.034048 -48.387)
		(width 0.127)
		(layer "In7.Cu")
		(net "FPGA_TDI")
	)
	(segment
		(start 121.034048 -48.387)
		(end 122.580146 -48.387)
		(width 0.127)
		(layer "In7.Cu")
		(net "FPGA_TDI")
	)
	(segment
		(start 122.580146 -48.387)
		(end 124.333 -50.139854)
		(width 0.127)
		(layer "In7.Cu")
		(net "FPGA_TDI")
	)
	(segment
		(start 117.59946 -46.916594)
		(end 117.856 -47.173134)
		(width 0.1016)
		(layer "In7.Cu")
		(net "FPGA_TDI")
	)
	(segment
		(start 118.142766 -47.752)
		(end 120.399048 -47.752)
		(width 0.127)
		(layer "In7.Cu")
		(net "FPGA_TDI")
	)
	(segment
		(start 126.7968 -58.7756)
		(end 127.249682 -58.7756)
		(width 0.127)
		(layer "In7.Cu")
		(net "FPGA_TDI")
	)
	(segment
		(start 127.249682 -58.7756)
		(end 129.3749 -60.900818)
		(width 0.127)
		(layer "In7.Cu")
		(net "FPGA_TDI")
	)
	(segment
		(start 124.333 -50.139854)
		(end 124.333 -52.736242)
		(width 0.127)
		(layer "In7.Cu")
		(net "FPGA_TDI")
	)
	(segment
		(start 125.1585 -54.817518)
		(end 125.1585 -56.324754)
		(width 0.127)
		(layer "In7.Cu")
		(net "FPGA_TDI")
	)
	(segment
		(start 124.333 -52.736242)
		(end 124.53747 -52.940712)
		(width 0.127)
		(layer "In7.Cu")
		(net "FPGA_TDI")
	)
	(segment
		(start 125.73 -57.7088)
		(end 126.7968 -58.7756)
		(width 0.127)
		(layer "In7.Cu")
		(net "FPGA_TDI")
	)
	(segment
		(start 113.346992 -46.322996)
		(end 113.94059 -46.916594)
		(width 0.1016)
		(layer "In7.Cu")
		(net "FPGA_TDI")
	)
	(segment
		(start 117.856 -47.465234)
		(end 118.142766 -47.752)
		(width 0.127)
		(layer "In7.Cu")
		(net "FPGA_TDI")
	)
	(segment
		(start 129.3749 -60.900818)
		(end 129.3749 -61.374782)
		(width 0.127)
		(layer "In7.Cu")
		(net "FPGA_TDI")
	)
	(segment
		(start 135.281924 -75.338178)
		(end 136.525 -75.338178)
		(width 0.127)
		(layer "In7.Cu")
		(net "FPGA_TDI")
	)
	(segment
		(start 124.6505 -53.05425)
		(end 124.6505 -54.309518)
		(width 0.127)
		(layer "In7.Cu")
		(net "FPGA_TDI")
	)
	(segment
		(start 125.1585 -56.324754)
		(end 125.73 -56.896254)
		(width 0.127)
		(layer "In7.Cu")
		(net "FPGA_TDI")
	)
	(segment
		(start 124.53747 -52.940712)
		(end 124.6505 -53.05425)
		(width 0.127)
		(layer "In7.Cu")
		(net "FPGA_TDI")
	)
	(segment
		(start 125.73 -56.896254)
		(end 125.73 -57.7088)
		(width 0.127)
		(layer "In7.Cu")
		(net "FPGA_TDI")
	)
	(segment
		(start 130.5941 -69.532754)
		(end 130.5941 -70.650354)
		(width 0.127)
		(layer "In7.Cu")
		(net "FPGA_TDI")
	)
	(segment
		(start 117.856 -47.173134)
		(end 117.856 -47.465234)
		(width 0.1016)
		(layer "In7.Cu")
		(net "FPGA_TDI")
	)
	(segment
		(start 129.3749 -61.374782)
		(end 129.286 -61.463682)
		(width 0.127)
		(layer "In7.Cu")
		(net "FPGA_TDI")
	)
	(segment
		(start 115.847114 -44.823126)
		(end 116.346986 -45.322998)
		(width 0.11938)
		(layer "F.Cu")
		(net "FPGA_TCK")
	)
	(via
		(at 116.346986 -45.322998)
		(size 0.4572)
		(drill 0.2032)
		(layers "F.Cu" "B.Cu")
		(net "FPGA_TCK")
	)
	(via
		(at 138.4935 -65.1002)
		(size 0.4572)
		(drill 0.2032)
		(layers "F.Cu" "B.Cu")
		(net "FPGA_TCK")
	)
	(segment
		(start 138.557 -67.056)
		(end 138.4935 -66.9925)
		(width 0.11938)
		(layer "B.Cu")
		(net "FPGA_TCK")
	)
	(segment
		(start 139.8016 -67.056)
		(end 139.8016 -65.913)
		(width 0.11938)
		(layer "B.Cu")
		(net "FPGA_TCK")
	)
	(segment
		(start 138.4935 -66.9925)
		(end 138.4935 -65.1002)
		(width 0.11938)
		(layer "B.Cu")
		(net "FPGA_TCK")
	)
	(segment
		(start 139.8016 -67.056)
		(end 138.557 -67.056)
		(width 0.11938)
		(layer "B.Cu")
		(net "FPGA_TCK")
	)
	(segment
		(start 125.498352 -46.099984)
		(end 124.497084 -47.101252)
		(width 0.127)
		(layer "In7.Cu")
		(net "FPGA_TCK")
	)
	(segment
		(start 116.346986 -45.322998)
		(end 116.346986 -45.047154)
		(width 0.127)
		(layer "In7.Cu")
		(net "FPGA_TCK")
	)
	(segment
		(start 117.143784 -44.250356)
		(end 120.190768 -44.250356)
		(width 0.127)
		(layer "In7.Cu")
		(net "FPGA_TCK")
	)
	(segment
		(start 127 -53.844952)
		(end 127 -56.304434)
		(width 0.127)
		(layer "In7.Cu")
		(net "FPGA_TCK")
	)
	(segment
		(start 120.771412 -44.831)
		(end 122.047 -44.831)
		(width 0.127)
		(layer "In7.Cu")
		(net "FPGA_TCK")
	)
	(segment
		(start 131.699 -62.992)
		(end 132.207 -63.5)
		(width 0.127)
		(layer "In7.Cu")
		(net "FPGA_TCK")
	)
	(segment
		(start 125.184408 -44.61764)
		(end 123.59894 -46.203108)
		(width 0.127)
		(layer "In7.Cu")
		(net "FPGA_TCK")
	)
	(segment
		(start 124.497084 -47.281084)
		(end 125.349 -48.133)
		(width 0.127)
		(layer "In7.Cu")
		(net "FPGA_TCK")
	)
	(segment
		(start 132.207 -63.5)
		(end 136.144 -63.5)
		(width 0.127)
		(layer "In7.Cu")
		(net "FPGA_TCK")
	)
	(segment
		(start 125.498352 -45.920152)
		(end 125.498352 -46.099984)
		(width 0.127)
		(layer "In7.Cu")
		(net "FPGA_TCK")
	)
	(segment
		(start 125.229112 -45.650912)
		(end 125.498352 -45.920152)
		(width 0.127)
		(layer "In7.Cu")
		(net "FPGA_TCK")
	)
	(segment
		(start 125.349 -50.753518)
		(end 126.5555 -51.960018)
		(width 0.127)
		(layer "In7.Cu")
		(net "FPGA_TCK")
	)
	(segment
		(start 136.144 -63.5)
		(end 137.7442 -65.1002)
		(width 0.127)
		(layer "In7.Cu")
		(net "FPGA_TCK")
	)
	(segment
		(start 124.497084 -47.101252)
		(end 124.497084 -47.281084)
		(width 0.127)
		(layer "In7.Cu")
		(net "FPGA_TCK")
	)
	(segment
		(start 126.5555 -51.960018)
		(end 126.5555 -53.400452)
		(width 0.127)
		(layer "In7.Cu")
		(net "FPGA_TCK")
	)
	(segment
		(start 123.149868 -45.754036)
		(end 124.735336 -44.168568)
		(width 0.127)
		(layer "In7.Cu")
		(net "FPGA_TCK")
	)
	(segment
		(start 122.047 -44.831)
		(end 122.970036 -45.754036)
		(width 0.127)
		(layer "In7.Cu")
		(net "FPGA_TCK")
	)
	(segment
		(start 127 -56.304434)
		(end 131.699 -61.003434)
		(width 0.127)
		(layer "In7.Cu")
		(net "FPGA_TCK")
	)
	(segment
		(start 122.970036 -45.754036)
		(end 123.149868 -45.754036)
		(width 0.127)
		(layer "In7.Cu")
		(net "FPGA_TCK")
	)
	(segment
		(start 125.04928 -45.650912)
		(end 125.229112 -45.650912)
		(width 0.127)
		(layer "In7.Cu")
		(net "FPGA_TCK")
	)
	(segment
		(start 123.86818 -46.65218)
		(end 124.048012 -46.65218)
		(width 0.127)
		(layer "In7.Cu")
		(net "FPGA_TCK")
	)
	(segment
		(start 125.184408 -44.437808)
		(end 125.184408 -44.61764)
		(width 0.127)
		(layer "In7.Cu")
		(net "FPGA_TCK")
	)
	(segment
		(start 126.5555 -53.400452)
		(end 127 -53.844952)
		(width 0.127)
		(layer "In7.Cu")
		(net "FPGA_TCK")
	)
	(segment
		(start 124.735336 -44.168568)
		(end 124.915168 -44.168568)
		(width 0.127)
		(layer "In7.Cu")
		(net "FPGA_TCK")
	)
	(segment
		(start 116.346986 -45.047154)
		(end 117.143784 -44.250356)
		(width 0.127)
		(layer "In7.Cu")
		(net "FPGA_TCK")
	)
	(segment
		(start 120.190768 -44.250356)
		(end 120.771412 -44.831)
		(width 0.127)
		(layer "In7.Cu")
		(net "FPGA_TCK")
	)
	(segment
		(start 125.349 -48.133)
		(end 125.349 -50.753518)
		(width 0.127)
		(layer "In7.Cu")
		(net "FPGA_TCK")
	)
	(segment
		(start 124.915168 -44.168568)
		(end 125.184408 -44.437808)
		(width 0.127)
		(layer "In7.Cu")
		(net "FPGA_TCK")
	)
	(segment
		(start 131.699 -61.003434)
		(end 131.699 -62.992)
		(width 0.127)
		(layer "In7.Cu")
		(net "FPGA_TCK")
	)
	(segment
		(start 123.59894 -46.203108)
		(end 123.59894 -46.38294)
		(width 0.127)
		(layer "In7.Cu")
		(net "FPGA_TCK")
	)
	(segment
		(start 137.7442 -65.1002)
		(end 138.4935 -65.1002)
		(width 0.127)
		(layer "In7.Cu")
		(net "FPGA_TCK")
	)
	(segment
		(start 123.59894 -46.38294)
		(end 123.86818 -46.65218)
		(width 0.127)
		(layer "In7.Cu")
		(net "FPGA_TCK")
	)
	(segment
		(start 124.048012 -46.65218)
		(end 125.04928 -45.650912)
		(width 0.127)
		(layer "In7.Cu")
		(net "FPGA_TCK")
	)
	(segment
		(start 129.12598 -18.806922)
		(end 130.1623 -18.806922)
		(width 0.11938)
		(layer "F.Cu")
		(net "EEPROM_I2C_SDA")
	)
	(segment
		(start 129.159 -16.383)
		(end 129.032 -16.51)
		(width 0.11938)
		(layer "F.Cu")
		(net "EEPROM_I2C_SDA")
	)
	(segment
		(start 129.032 -18.712942)
		(end 129.12598 -18.806922)
		(width 0.11938)
		(layer "F.Cu")
		(net "EEPROM_I2C_SDA")
	)
	(segment
		(start 36.4236 -15.09522)
		(end 36.4236 -14.57198)
		(width 0.11938)
		(layer "F.Cu")
		(net "EEPROM_I2C_SDA")
	)
	(segment
		(start 36.30422 -14.4526)
		(end 34.5948 -14.4526)
		(width 0.11938)
		(layer "F.Cu")
		(net "EEPROM_I2C_SDA")
	)
	(segment
		(start 35.433 -15.875)
		(end 36.0934 -15.2146)
		(width 0.11938)
		(layer "F.Cu")
		(net "EEPROM_I2C_SDA")
	)
	(segment
		(start 36.4236 -14.57198)
		(end 36.30422 -14.4526)
		(width 0.11938)
		(layer "F.Cu")
		(net "EEPROM_I2C_SDA")
	)
	(segment
		(start 34.3027 -14.7447)
		(end 34.3027 -15.5702)
		(width 0.11938)
		(layer "F.Cu")
		(net "EEPROM_I2C_SDA")
	)
	(segment
		(start 34.5948 -14.4526)
		(end 34.3027 -14.7447)
		(width 0.11938)
		(layer "F.Cu")
		(net "EEPROM_I2C_SDA")
	)
	(segment
		(start 129.032 -16.51)
		(end 129.032 -18.712942)
		(width 0.11938)
		(layer "F.Cu")
		(net "EEPROM_I2C_SDA")
	)
	(segment
		(start 36.0934 -15.2146)
		(end 36.30422 -15.2146)
		(width 0.11938)
		(layer "F.Cu")
		(net "EEPROM_I2C_SDA")
	)
	(segment
		(start 36.30422 -15.2146)
		(end 36.4236 -15.09522)
		(width 0.11938)
		(layer "F.Cu")
		(net "EEPROM_I2C_SDA")
	)
	(via
		(at 129.159 -16.383)
		(size 0.508)
		(drill 0.254)
		(layers "F.Cu" "B.Cu")
		(net "EEPROM_I2C_SDA")
	)
	(via
		(at 35.433 -15.875)
		(size 0.4572)
		(drill 0.2032)
		(layers "F.Cu" "B.Cu")
		(net "EEPROM_I2C_SDA")
	)
	(via
		(at 90.043 -15.47368)
		(size 0.508)
		(drill 0.254)
		(layers "F.Cu" "B.Cu")
		(net "EEPROM_I2C_SDA")
	)
	(segment
		(start 79.857346 -14.3256)
		(end 88.89492 -14.3256)
		(width 0.127)
		(layer "In2.Cu")
		(net "EEPROM_I2C_SDA")
	)
	(segment
		(start 57.404 -10.922)
		(end 62.738 -10.922)
		(width 0.127)
		(layer "In2.Cu")
		(net "EEPROM_I2C_SDA")
	)
	(segment
		(start 53.35778 -11.303)
		(end 57.023 -11.303)
		(width 0.127)
		(layer "In2.Cu")
		(net "EEPROM_I2C_SDA")
	)
	(segment
		(start 62.738 -10.922)
		(end 63.627 -11.811)
		(width 0.127)
		(layer "In2.Cu")
		(net "EEPROM_I2C_SDA")
	)
	(segment
		(start 48.768 -14.605)
		(end 50.05578 -14.605)
		(width 0.127)
		(layer "In2.Cu")
		(net "EEPROM_I2C_SDA")
	)
	(segment
		(start 63.627 -11.811)
		(end 72.263 -11.811)
		(width 0.127)
		(layer "In2.Cu")
		(net "EEPROM_I2C_SDA")
	)
	(segment
		(start 73.563734 -13.111734)
		(end 78.64348 -13.111734)
		(width 0.127)
		(layer "In2.Cu")
		(net "EEPROM_I2C_SDA")
	)
	(segment
		(start 45.72 -16.764)
		(end 46.609 -16.764)
		(width 0.127)
		(layer "In2.Cu")
		(net "EEPROM_I2C_SDA")
	)
	(segment
		(start 37.973 -15.113)
		(end 38.4175 -15.5575)
		(width 0.127)
		(layer "In2.Cu")
		(net "EEPROM_I2C_SDA")
	)
	(segment
		(start 46.609 -16.764)
		(end 48.768 -14.605)
		(width 0.127)
		(layer "In2.Cu")
		(net "EEPROM_I2C_SDA")
	)
	(segment
		(start 36.195 -15.113)
		(end 37.973 -15.113)
		(width 0.127)
		(layer "In2.Cu")
		(net "EEPROM_I2C_SDA")
	)
	(segment
		(start 44.5135 -15.5575)
		(end 45.72 -16.764)
		(width 0.127)
		(layer "In2.Cu")
		(net "EEPROM_I2C_SDA")
	)
	(segment
		(start 88.89492 -14.3256)
		(end 90.043 -15.47368)
		(width 0.127)
		(layer "In2.Cu")
		(net "EEPROM_I2C_SDA")
	)
	(segment
		(start 72.263 -11.811)
		(end 73.563734 -13.111734)
		(width 0.127)
		(layer "In2.Cu")
		(net "EEPROM_I2C_SDA")
	)
	(segment
		(start 57.023 -11.303)
		(end 57.404 -10.922)
		(width 0.127)
		(layer "In2.Cu")
		(net "EEPROM_I2C_SDA")
	)
	(segment
		(start 35.433 -15.875)
		(end 36.195 -15.113)
		(width 0.127)
		(layer "In2.Cu")
		(net "EEPROM_I2C_SDA")
	)
	(segment
		(start 50.05578 -14.605)
		(end 53.35778 -11.303)
		(width 0.127)
		(layer "In2.Cu")
		(net "EEPROM_I2C_SDA")
	)
	(segment
		(start 78.64348 -13.111734)
		(end 79.857346 -14.3256)
		(width 0.127)
		(layer "In2.Cu")
		(net "EEPROM_I2C_SDA")
	)
	(segment
		(start 38.4175 -15.5575)
		(end 44.5135 -15.5575)
		(width 0.127)
		(layer "In2.Cu")
		(net "EEPROM_I2C_SDA")
	)
	(segment
		(start 128.397 -17.145)
		(end 123.825 -17.145)
		(width 0.127)
		(layer "In7.Cu")
		(net "EEPROM_I2C_SDA")
	)
	(segment
		(start 121.5898 -14.9098)
		(end 90.5002 -14.9098)
		(width 0.127)
		(layer "In7.Cu")
		(net "EEPROM_I2C_SDA")
	)
	(segment
		(start 90.5002 -14.9098)
		(end 90.043 -15.367)
		(width 0.127)
		(layer "In7.Cu")
		(net "EEPROM_I2C_SDA")
	)
	(segment
		(start 129.159 -16.383)
		(end 128.397 -17.145)
		(width 0.127)
		(layer "In7.Cu")
		(net "EEPROM_I2C_SDA")
	)
	(segment
		(start 90.043 -15.367)
		(end 90.043 -15.47368)
		(width 0.127)
		(layer "In7.Cu")
		(net "EEPROM_I2C_SDA")
	)
	(segment
		(start 123.825 -17.145)
		(end 121.5898 -14.9098)
		(width 0.127)
		(layer "In7.Cu")
		(net "EEPROM_I2C_SDA")
	)
	(segment
		(start 129.036572 -20.75688)
		(end 130.1623 -20.75688)
		(width 0.11938)
		(layer "F.Cu")
		(net "EEPROM_I2C_SCL")
	)
	(segment
		(start 35.1282 -17.9832)
		(end 34.30778 -17.9832)
		(width 0.11938)
		(layer "F.Cu")
		(net "EEPROM_I2C_SCL")
	)
	(segment
		(start 35.433 -18.288)
		(end 35.1282 -17.9832)
		(width 0.11938)
		(layer "F.Cu")
		(net "EEPROM_I2C_SCL")
	)
	(segment
		(start 36.83 -16.764)
		(end 36.83 -17.907)
		(width 0.11938)
		(layer "F.Cu")
		(net "EEPROM_I2C_SCL")
	)
	(segment
		(start 37.719 -15.875)
		(end 36.83 -16.764)
		(width 0.11938)
		(layer "F.Cu")
		(net "EEPROM_I2C_SCL")
	)
	(segment
		(start 128.016 -19.736308)
		(end 129.036572 -20.75688)
		(width 0.11938)
		(layer "F.Cu")
		(net "EEPROM_I2C_SCL")
	)
	(segment
		(start 36.83 -17.907)
		(end 36.449 -18.288)
		(width 0.11938)
		(layer "F.Cu")
		(net "EEPROM_I2C_SCL")
	)
	(segment
		(start 128.016 -16.383)
		(end 128.016 -19.736308)
		(width 0.11938)
		(layer "F.Cu")
		(net "EEPROM_I2C_SCL")
	)
	(segment
		(start 36.449 -18.288)
		(end 35.433 -18.288)
		(width 0.11938)
		(layer "F.Cu")
		(net "EEPROM_I2C_SCL")
	)
	(via
		(at 37.719 -15.875)
		(size 0.4572)
		(drill 0.2032)
		(layers "F.Cu" "B.Cu")
		(net "EEPROM_I2C_SCL")
	)
	(via
		(at 128.016 -16.383)
		(size 0.508)
		(drill 0.254)
		(layers "F.Cu" "B.Cu")
		(net "EEPROM_I2C_SCL")
	)
	(via
		(at 88.773 -15.494)
		(size 0.508)
		(drill 0.254)
		(layers "F.Cu" "B.Cu")
		(net "EEPROM_I2C_SCL")
	)
	(segment
		(start 73.2155 -13.6779)
		(end 78.2701 -13.6779)
		(width 0.127)
		(layer "In2.Cu")
		(net "EEPROM_I2C_SCL")
	)
	(segment
		(start 46.863 -17.27454)
		(end 48.91024 -15.2273)
		(width 0.127)
		(layer "In2.Cu")
		(net "EEPROM_I2C_SCL")
	)
	(segment
		(start 45.466 -17.27454)
		(end 46.863 -17.27454)
		(width 0.127)
		(layer "In2.Cu")
		(net "EEPROM_I2C_SCL")
	)
	(segment
		(start 62.484 -11.43)
		(end 63.373 -12.319)
		(width 0.127)
		(layer "In2.Cu")
		(net "EEPROM_I2C_SCL")
	)
	(segment
		(start 63.373 -12.319)
		(end 71.8566 -12.319)
		(width 0.127)
		(layer "In2.Cu")
		(net "EEPROM_I2C_SCL")
	)
	(segment
		(start 78.2701 -13.6779)
		(end 79.502 -14.9098)
		(width 0.127)
		(layer "In2.Cu")
		(net "EEPROM_I2C_SCL")
	)
	(segment
		(start 88.1888 -14.9098)
		(end 88.773 -15.494)
		(width 0.127)
		(layer "In2.Cu")
		(net "EEPROM_I2C_SCL")
	)
	(segment
		(start 50.152046 -15.2273)
		(end 53.568346 -11.811)
		(width 0.127)
		(layer "In2.Cu")
		(net "EEPROM_I2C_SCL")
	)
	(segment
		(start 57.658 -11.43)
		(end 62.484 -11.43)
		(width 0.127)
		(layer "In2.Cu")
		(net "EEPROM_I2C_SCL")
	)
	(segment
		(start 37.719 -15.875)
		(end 38.1 -16.256)
		(width 0.127)
		(layer "In2.Cu")
		(net "EEPROM_I2C_SCL")
	)
	(segment
		(start 53.568346 -11.811)
		(end 57.277 -11.811)
		(width 0.127)
		(layer "In2.Cu")
		(net "EEPROM_I2C_SCL")
	)
	(segment
		(start 71.8566 -12.319)
		(end 73.2155 -13.6779)
		(width 0.127)
		(layer "In2.Cu")
		(net "EEPROM_I2C_SCL")
	)
	(segment
		(start 79.502 -14.9098)
		(end 88.1888 -14.9098)
		(width 0.127)
		(layer "In2.Cu")
		(net "EEPROM_I2C_SCL")
	)
	(segment
		(start 57.277 -11.811)
		(end 57.658 -11.43)
		(width 0.127)
		(layer "In2.Cu")
		(net "EEPROM_I2C_SCL")
	)
	(segment
		(start 48.91024 -15.2273)
		(end 50.152046 -15.2273)
		(width 0.127)
		(layer "In2.Cu")
		(net "EEPROM_I2C_SCL")
	)
	(segment
		(start 44.44746 -16.256)
		(end 45.466 -17.27454)
		(width 0.127)
		(layer "In2.Cu")
		(net "EEPROM_I2C_SCL")
	)
	(segment
		(start 38.1 -16.256)
		(end 44.44746 -16.256)
		(width 0.127)
		(layer "In2.Cu")
		(net "EEPROM_I2C_SCL")
	)
	(segment
		(start 121.7422 -14.3256)
		(end 89.9414 -14.3256)
		(width 0.127)
		(layer "In7.Cu")
		(net "EEPROM_I2C_SCL")
	)
	(segment
		(start 128.016 -16.383)
		(end 126.71552 -15.08252)
		(width 0.127)
		(layer "In7.Cu")
		(net "EEPROM_I2C_SCL")
	)
	(segment
		(start 122.49912 -15.08252)
		(end 121.7422 -14.3256)
		(width 0.127)
		(layer "In7.Cu")
		(net "EEPROM_I2C_SCL")
	)
	(segment
		(start 126.71552 -15.08252)
		(end 122.49912 -15.08252)
		(width 0.127)
		(layer "In7.Cu")
		(net "EEPROM_I2C_SCL")
	)
	(segment
		(start 89.9414 -14.3256)
		(end 88.773 -15.494)
		(width 0.127)
		(layer "In7.Cu")
		(net "EEPROM_I2C_SCL")
	)
	(segment
		(start 59.649868 -3.500374)
		(end 59.649868 -5.99567)
		(width 0.09906)
		(layer "B.Cu")
		(net "C_PCIEREFCLKP")
	)
	(segment
		(start 59.852306 -14.493494)
		(end 59.51474 -14.83106)
		(width 0.09906)
		(layer "B.Cu")
		(net "C_PCIEREFCLKP")
	)
	(segment
		(start 59.997594 -6.75386)
		(end 59.997594 -14.142974)
		(width 0.09906)
		(layer "B.Cu")
		(net "C_PCIEREFCLKP")
	)
	(segment
		(start 59.795156 -6.34619)
		(end 59.852306 -6.40334)
		(width 0.09906)
		(layer "B.Cu")
		(net "C_PCIEREFCLKP")
	)
	(arc
		(start 59.649868 -5.99567)
		(mid 59.687624 -6.185393)
		(end 59.795156 -6.34619)
		(width 0.09906)
		(layer "B.Cu")
		(net "C_PCIEREFCLKP")
	)
	(arc
		(start 59.997594 -14.142974)
		(mid 59.959838 -14.332697)
		(end 59.852306 -14.493494)
		(width 0.09906)
		(layer "B.Cu")
		(net "C_PCIEREFCLKP")
	)
	(arc
		(start 59.852306 -6.40334)
		(mid 59.959816 -6.564146)
		(end 59.997594 -6.75386)
		(width 0.09906)
		(layer "B.Cu")
		(net "C_PCIEREFCLKP")
	)
	(segment
		(start 60.447682 -14.496288)
		(end 60.784994 -14.8336)
		(width 0.09906)
		(layer "B.Cu")
		(net "C_PCIEREFCLKN")
	)
	(segment
		(start 60.504578 -6.350508)
		(end 60.447682 -6.407404)
		(width 0.09906)
		(layer "B.Cu")
		(net "C_PCIEREFCLKN")
	)
	(segment
		(start 60.649866 -3.500374)
		(end 60.649866 -5.999988)
		(width 0.09906)
		(layer "B.Cu")
		(net "C_PCIEREFCLKN")
	)
	(segment
		(start 60.302394 -6.757924)
		(end 60.302394 -14.145768)
		(width 0.09906)
		(layer "B.Cu")
		(net "C_PCIEREFCLKN")
	)
	(arc
		(start 60.447682 -6.407404)
		(mid 60.340172 -6.56821)
		(end 60.302394 -6.757924)
		(width 0.09906)
		(layer "B.Cu")
		(net "C_PCIEREFCLKN")
	)
	(arc
		(start 60.302394 -14.145768)
		(mid 60.34015 -14.335491)
		(end 60.447682 -14.496288)
		(width 0.09906)
		(layer "B.Cu")
		(net "C_PCIEREFCLKN")
	)
	(arc
		(start 60.649866 -5.999988)
		(mid 60.61211 -6.189711)
		(end 60.504578 -6.350508)
		(width 0.09906)
		(layer "B.Cu")
		(net "C_PCIEREFCLKN")
	)
	(segment
		(start 75.871832 -6.144514)
		(end 75.732132 -6.004814)
		(width 0.14478)
		(layer "B.Cu")
		(net "C_CPU_RX_PCIE_MGT3_TXP")
	)
	(segment
		(start 75.959462 -13.76045)
		(end 75.959462 -13.698728)
		(width 0.14478)
		(layer "B.Cu")
		(net "C_CPU_RX_PCIE_MGT3_TXP")
	)
	(segment
		(start 76.5302 -12.585954)
		(end 76.5302 -8.345678)
		(width 0.14478)
		(layer "B.Cu")
		(net "C_CPU_RX_PCIE_MGT3_TXP")
	)
	(segment
		(start 75.959208 -7.092188)
		(end 75.959208 -6.355334)
		(width 0.14478)
		(layer "B.Cu")
		(net "C_CPU_RX_PCIE_MGT3_TXP")
	)
	(segment
		(start 76.362306 -7.940294)
		(end 76.273406 -7.851394)
		(width 0.14478)
		(layer "B.Cu")
		(net "C_CPU_RX_PCIE_MGT3_TXP")
	)
	(segment
		(start 75.649836 -5.806186)
		(end 75.649836 -3.500374)
		(width 0.14478)
		(layer "B.Cu")
		(net "C_CPU_RX_PCIE_MGT3_TXP")
	)
	(segment
		(start 76.190094 -13.141706)
		(end 76.3778 -12.954)
		(width 0.14478)
		(layer "B.Cu")
		(net "C_CPU_RX_PCIE_MGT3_TXP")
	)
	(arc
		(start 75.917044 -6.20268)
		(mid 75.896253 -6.172185)
		(end 75.871832 -6.144514)
		(width 0.14478)
		(layer "B.Cu")
		(net "C_CPU_RX_PCIE_MGT3_TXP")
	)
	(arc
		(start 75.732132 -6.004814)
		(mid 75.67124 -5.913683)
		(end 75.649836 -5.806186)
		(width 0.14478)
		(layer "B.Cu")
		(net "C_CPU_RX_PCIE_MGT3_TXP")
	)
	(arc
		(start 76.3778 -12.954)
		(mid 76.490629 -12.785139)
		(end 76.5302 -12.585954)
		(width 0.14478)
		(layer "B.Cu")
		(net "C_CPU_RX_PCIE_MGT3_TXP")
	)
	(arc
		(start 75.514962 -14.8336)
		(mid 75.84395 -14.341235)
		(end 75.959462 -13.76045)
		(width 0.14478)
		(layer "B.Cu")
		(net "C_CPU_RX_PCIE_MGT3_TXP")
	)
	(arc
		(start 76.273406 -7.851394)
		(mid 76.040774 -7.503051)
		(end 75.959208 -7.092188)
		(width 0.14478)
		(layer "B.Cu")
		(net "C_CPU_RX_PCIE_MGT3_TXP")
	)
	(arc
		(start 75.959462 -13.698728)
		(mid 76.019336 -13.397252)
		(end 76.190094 -13.141706)
		(width 0.14478)
		(layer "B.Cu")
		(net "C_CPU_RX_PCIE_MGT3_TXP")
	)
	(arc
		(start 76.5302 -8.345678)
		(mid 76.486562 -8.126294)
		(end 76.362306 -7.940294)
		(width 0.14478)
		(layer "B.Cu")
		(net "C_CPU_RX_PCIE_MGT3_TXP")
	)
	(arc
		(start 75.959208 -6.355334)
		(mid 75.948435 -6.276161)
		(end 75.917044 -6.20268)
		(width 0.14478)
		(layer "B.Cu")
		(net "C_CPU_RX_PCIE_MGT3_TXP")
	)
	(segment
		(start 76.6318 -7.6708)
		(end 76.5429 -7.5819)
		(width 0.14478)
		(layer "B.Cu")
		(net "C_CPU_RX_PCIE_MGT3_TXN")
	)
	(segment
		(start 76.9112 -12.5857)
		(end 76.9112 -8.345932)
		(width 0.14478)
		(layer "B.Cu")
		(net "C_CPU_RX_PCIE_MGT3_TXN")
	)
	(segment
		(start 76.340462 -13.76045)
		(end 76.340462 -13.698728)
		(width 0.14478)
		(layer "B.Cu")
		(net "C_CPU_RX_PCIE_MGT3_TXN")
	)
	(segment
		(start 76.414122 -6.157976)
		(end 76.553822 -6.018276)
		(width 0.14478)
		(layer "B.Cu")
		(net "C_CPU_RX_PCIE_MGT3_TXN")
	)
	(segment
		(start 76.340208 -7.092442)
		(end 76.340208 -6.336538)
		(width 0.14478)
		(layer "B.Cu")
		(net "C_CPU_RX_PCIE_MGT3_TXN")
	)
	(segment
		(start 76.459588 -13.4112)
		(end 76.647294 -13.223494)
		(width 0.14478)
		(layer "B.Cu")
		(net "C_CPU_RX_PCIE_MGT3_TXN")
	)
	(segment
		(start 76.649834 -5.786374)
		(end 76.649834 -3.500374)
		(width 0.14478)
		(layer "B.Cu")
		(net "C_CPU_RX_PCIE_MGT3_TXN")
	)
	(arc
		(start 76.553822 -6.018276)
		(mid 76.624915 -5.911878)
		(end 76.649834 -5.786374)
		(width 0.14478)
		(layer "B.Cu")
		(net "C_CPU_RX_PCIE_MGT3_TXN")
	)
	(arc
		(start 76.340462 -13.698728)
		(mid 76.371417 -13.543108)
		(end 76.459588 -13.4112)
		(width 0.14478)
		(layer "B.Cu")
		(net "C_CPU_RX_PCIE_MGT3_TXN")
	)
	(arc
		(start 76.37399 -6.210046)
		(mid 76.392346 -6.182692)
		(end 76.414122 -6.157976)
		(width 0.14478)
		(layer "B.Cu")
		(net "C_CPU_RX_PCIE_MGT3_TXN")
	)
	(arc
		(start 76.340208 -6.336538)
		(mid 76.348775 -6.271072)
		(end 76.37399 -6.210046)
		(width 0.14478)
		(layer "B.Cu")
		(net "C_CPU_RX_PCIE_MGT3_TXN")
	)
	(arc
		(start 76.5429 -7.5819)
		(mid 76.39285 -7.357335)
		(end 76.340208 -7.092442)
		(width 0.14478)
		(layer "B.Cu")
		(net "C_CPU_RX_PCIE_MGT3_TXN")
	)
	(arc
		(start 76.9112 -8.345932)
		(mid 76.838692 -7.980555)
		(end 76.6318 -7.6708)
		(width 0.14478)
		(layer "B.Cu")
		(net "C_CPU_RX_PCIE_MGT3_TXN")
	)
	(arc
		(start 76.784962 -14.8336)
		(mid 76.455974 -14.341235)
		(end 76.340462 -13.76045)
		(width 0.14478)
		(layer "B.Cu")
		(net "C_CPU_RX_PCIE_MGT3_TXN")
	)
	(arc
		(start 76.647294 -13.223494)
		(mid 76.842706 -12.930856)
		(end 76.9112 -12.5857)
		(width 0.14478)
		(layer "B.Cu")
		(net "C_CPU_RX_PCIE_MGT3_TXN")
	)
	(segment
		(start 71.877936 -6.15061)
		(end 71.725536 -5.99821)
		(width 0.14478)
		(layer "B.Cu")
		(net "C_CPU_RX_PCIE_MGT2_TXP")
	)
	(segment
		(start 71.649844 -5.815584)
		(end 71.649844 -3.500374)
		(width 0.14478)
		(layer "B.Cu")
		(net "C_CPU_RX_PCIE_MGT2_TXP")
	)
	(segment
		(start 71.57847 -13.76045)
		(end 71.57847 -12.30757)
		(width 0.14478)
		(layer "B.Cu")
		(net "C_CPU_RX_PCIE_MGT2_TXP")
	)
	(segment
		(start 71.790306 -11.795506)
		(end 71.802244 -11.783568)
		(width 0.14478)
		(layer "B.Cu")
		(net "C_CPU_RX_PCIE_MGT2_TXP")
	)
	(segment
		(start 71.959216 -11.4046)
		(end 71.959216 -6.346952)
		(width 0.14478)
		(layer "B.Cu")
		(net "C_CPU_RX_PCIE_MGT2_TXP")
	)
	(arc
		(start 71.57847 -12.30757)
		(mid 71.633423 -12.030452)
		(end 71.790306 -11.795506)
		(width 0.14478)
		(layer "B.Cu")
		(net "C_CPU_RX_PCIE_MGT2_TXP")
	)
	(arc
		(start 71.13397 -14.8336)
		(mid 71.462958 -14.341235)
		(end 71.57847 -13.76045)
		(width 0.14478)
		(layer "B.Cu")
		(net "C_CPU_RX_PCIE_MGT2_TXP")
	)
	(arc
		(start 71.802244 -11.783568)
		(mid 71.918422 -11.609696)
		(end 71.959216 -11.4046)
		(width 0.14478)
		(layer "B.Cu")
		(net "C_CPU_RX_PCIE_MGT2_TXP")
	)
	(arc
		(start 71.725536 -5.99821)
		(mid 71.66955 -5.91442)
		(end 71.649844 -5.815584)
		(width 0.14478)
		(layer "B.Cu")
		(net "C_CPU_RX_PCIE_MGT2_TXP")
	)
	(arc
		(start 71.959216 -6.346952)
		(mid 71.948391 -6.270184)
		(end 71.916798 -6.199378)
		(width 0.14478)
		(layer "B.Cu")
		(net "C_CPU_RX_PCIE_MGT2_TXP")
	)
	(arc
		(start 71.916798 -6.199378)
		(mid 71.898739 -6.1739)
		(end 71.877936 -6.15061)
		(width 0.14478)
		(layer "B.Cu")
		(net "C_CPU_RX_PCIE_MGT2_TXP")
	)
	(segment
		(start 72.0598 -12.065)
		(end 72.071738 -12.053062)
		(width 0.14478)
		(layer "B.Cu")
		(net "C_CPU_RX_PCIE_MGT2_TXN")
	)
	(segment
		(start 72.340216 -11.404346)
		(end 72.340216 -6.34492)
		(width 0.14478)
		(layer "B.Cu")
		(net "C_CPU_RX_PCIE_MGT2_TXN")
	)
	(segment
		(start 71.95947 -13.76045)
		(end 71.95947 -12.307316)
		(width 0.14478)
		(layer "B.Cu")
		(net "C_CPU_RX_PCIE_MGT2_TXN")
	)
	(segment
		(start 72.649842 -5.77723)
		(end 72.649842 -3.500374)
		(width 0.14478)
		(layer "B.Cu")
		(net "C_CPU_RX_PCIE_MGT2_TXN")
	)
	(segment
		(start 72.420226 -6.15188)
		(end 72.547226 -6.02488)
		(width 0.14478)
		(layer "B.Cu")
		(net "C_CPU_RX_PCIE_MGT2_TXN")
	)
	(arc
		(start 72.071738 -12.053062)
		(mid 72.270498 -11.755413)
		(end 72.340216 -11.404346)
		(width 0.14478)
		(layer "B.Cu")
		(net "C_CPU_RX_PCIE_MGT2_TXN")
	)
	(arc
		(start 71.95947 -12.307316)
		(mid 71.985552 -12.176191)
		(end 72.0598 -12.065)
		(width 0.14478)
		(layer "B.Cu")
		(net "C_CPU_RX_PCIE_MGT2_TXN")
	)
	(arc
		(start 72.547226 -6.02488)
		(mid 72.623146 -5.911257)
		(end 72.649842 -5.77723)
		(width 0.14478)
		(layer "B.Cu")
		(net "C_CPU_RX_PCIE_MGT2_TXN")
	)
	(arc
		(start 72.40397 -14.8336)
		(mid 72.074982 -14.341235)
		(end 71.95947 -13.76045)
		(width 0.14478)
		(layer "B.Cu")
		(net "C_CPU_RX_PCIE_MGT2_TXN")
	)
	(arc
		(start 72.384666 -6.195314)
		(mid 72.401322 -6.172676)
		(end 72.420226 -6.15188)
		(width 0.14478)
		(layer "B.Cu")
		(net "C_CPU_RX_PCIE_MGT2_TXN")
	)
	(arc
		(start 72.340216 -6.34492)
		(mid 72.351531 -6.266877)
		(end 72.384666 -6.195314)
		(width 0.14478)
		(layer "B.Cu")
		(net "C_CPU_RX_PCIE_MGT2_TXN")
	)
	(segment
		(start 67.649852 -5.806186)
		(end 67.649852 -3.500374)
		(width 0.14478)
		(layer "B.Cu")
		(net "C_CPU_RX_PCIE_MGT1_TXP")
	)
	(segment
		(start 67.959478 -13.76045)
		(end 67.959478 -6.356096)
		(width 0.14478)
		(layer "B.Cu")
		(net "C_CPU_RX_PCIE_MGT1_TXP")
	)
	(segment
		(start 67.871594 -6.144006)
		(end 67.731894 -6.004306)
		(width 0.14478)
		(layer "B.Cu")
		(net "C_CPU_RX_PCIE_MGT1_TXP")
	)
	(arc
		(start 67.914012 -6.1976)
		(mid 67.89434 -6.169586)
		(end 67.871594 -6.144006)
		(width 0.14478)
		(layer "B.Cu")
		(net "C_CPU_RX_PCIE_MGT1_TXP")
	)
	(arc
		(start 67.514978 -14.8336)
		(mid 67.843966 -14.341235)
		(end 67.959478 -13.76045)
		(width 0.14478)
		(layer "B.Cu")
		(net "C_CPU_RX_PCIE_MGT1_TXP")
	)
	(arc
		(start 67.731894 -6.004306)
		(mid 67.671158 -5.913408)
		(end 67.649852 -5.806186)
		(width 0.14478)
		(layer "B.Cu")
		(net "C_CPU_RX_PCIE_MGT1_TXP")
	)
	(arc
		(start 67.959478 -6.356096)
		(mid 67.947856 -6.27366)
		(end 67.914012 -6.1976)
		(width 0.14478)
		(layer "B.Cu")
		(net "C_CPU_RX_PCIE_MGT1_TXP")
	)
	(segment
		(start 68.340478 -13.82903)
		(end 68.340478 -6.389624)
		(width 0.14478)
		(layer "B.Cu")
		(net "C_CPU_RX_PCIE_MGT1_TXN")
	)
	(segment
		(start 68.784978 -14.8336)
		(end 68.736464 -14.785086)
		(width 0.14478)
		(layer "B.Cu")
		(net "C_CPU_RX_PCIE_MGT1_TXN")
	)
	(segment
		(start 68.451984 -6.120384)
		(end 68.528184 -6.044184)
		(width 0.14478)
		(layer "B.Cu")
		(net "C_CPU_RX_PCIE_MGT1_TXN")
	)
	(segment
		(start 68.64985 -5.75056)
		(end 68.64985 -3.500374)
		(width 0.14478)
		(layer "B.Cu")
		(net "C_CPU_RX_PCIE_MGT1_TXN")
	)
	(arc
		(start 68.39204 -6.197854)
		(mid 68.419502 -6.157176)
		(end 68.451984 -6.120384)
		(width 0.14478)
		(layer "B.Cu")
		(net "C_CPU_RX_PCIE_MGT1_TXN")
	)
	(arc
		(start 68.340478 -6.389624)
		(mid 68.353521 -6.290312)
		(end 68.39204 -6.197854)
		(width 0.14478)
		(layer "B.Cu")
		(net "C_CPU_RX_PCIE_MGT1_TXN")
	)
	(arc
		(start 68.528184 -6.044184)
		(mid 68.618198 -5.909468)
		(end 68.64985 -5.75056)
		(width 0.14478)
		(layer "B.Cu")
		(net "C_CPU_RX_PCIE_MGT1_TXN")
	)
	(arc
		(start 68.736464 -14.785086)
		(mid 68.443373 -14.346444)
		(end 68.340478 -13.82903)
		(width 0.14478)
		(layer "B.Cu")
		(net "C_CPU_RX_PCIE_MGT1_TXN")
	)
	(segment
		(start 62.959234 -12.73683)
		(end 62.959234 -6.394704)
		(width 0.14478)
		(layer "B.Cu")
		(net "C_CPU_RX_PCIE_MGT0_TXP")
	)
	(segment
		(start 62.959488 -13.76045)
		(end 62.959488 -12.737084)
		(width 0.14478)
		(layer "B.Cu")
		(net "C_CPU_RX_PCIE_MGT0_TXP")
	)
	(segment
		(start 62.959488 -12.737084)
		(end 62.959234 -12.73683)
		(width 0.14478)
		(layer "B.Cu")
		(net "C_CPU_RX_PCIE_MGT0_TXP")
	)
	(segment
		(start 62.844172 -6.116828)
		(end 62.742572 -6.015228)
		(width 0.14478)
		(layer "B.Cu")
		(net "C_CPU_RX_PCIE_MGT0_TXP")
	)
	(segment
		(start 62.649862 -5.791454)
		(end 62.649862 -3.500374)
		(width 0.14478)
		(layer "B.Cu")
		(net "C_CPU_RX_PCIE_MGT0_TXP")
	)
	(arc
		(start 62.959234 -6.394704)
		(mid 62.929323 -6.244333)
		(end 62.844172 -6.116828)
		(width 0.14478)
		(layer "B.Cu")
		(net "C_CPU_RX_PCIE_MGT0_TXP")
	)
	(arc
		(start 62.514988 -14.8336)
		(mid 62.843976 -14.341235)
		(end 62.959488 -13.76045)
		(width 0.14478)
		(layer "B.Cu")
		(net "C_CPU_RX_PCIE_MGT0_TXP")
	)
	(arc
		(start 62.742572 -6.015228)
		(mid 62.673971 -5.91256)
		(end 62.649862 -5.791454)
		(width 0.14478)
		(layer "B.Cu")
		(net "C_CPU_RX_PCIE_MGT0_TXP")
	)
	(segment
		(start 63.64986 -5.7658)
		(end 63.64986 -3.500374)
		(width 0.14478)
		(layer "B.Cu")
		(net "C_CPU_RX_PCIE_MGT0_TXN")
	)
	(segment
		(start 63.340488 -13.76045)
		(end 63.340488 -12.737084)
		(width 0.14478)
		(layer "B.Cu")
		(net "C_CPU_RX_PCIE_MGT0_TXN")
	)
	(segment
		(start 63.340234 -12.737338)
		(end 63.340234 -6.405118)
		(width 0.14478)
		(layer "B.Cu")
		(net "C_CPU_RX_PCIE_MGT0_TXN")
	)
	(segment
		(start 63.538862 -6.033262)
		(end 63.539116 -6.032754)
		(width 0.14478)
		(layer "B.Cu")
		(net "C_CPU_RX_PCIE_MGT0_TXN")
	)
	(segment
		(start 63.462662 -6.109462)
		(end 63.538862 -6.033262)
		(width 0.14478)
		(layer "B.Cu")
		(net "C_CPU_RX_PCIE_MGT0_TXN")
	)
	(segment
		(start 63.340488 -12.737084)
		(end 63.340234 -12.737338)
		(width 0.14478)
		(layer "B.Cu")
		(net "C_CPU_RX_PCIE_MGT0_TXN")
	)
	(arc
		(start 63.784988 -14.8336)
		(mid 63.456 -14.341235)
		(end 63.340488 -13.76045)
		(width 0.14478)
		(layer "B.Cu")
		(net "C_CPU_RX_PCIE_MGT0_TXN")
	)
	(arc
		(start 63.539116 -6.032754)
		(mid 63.621037 -5.910289)
		(end 63.64986 -5.7658)
		(width 0.14478)
		(layer "B.Cu")
		(net "C_CPU_RX_PCIE_MGT0_TXN")
	)
	(arc
		(start 63.340234 -6.405118)
		(mid 63.372059 -6.245124)
		(end 63.462662 -6.109462)
		(width 0.14478)
		(layer "B.Cu")
		(net "C_CPU_RX_PCIE_MGT0_TXN")
	)
	(segment
		(start 74.511662 -9.548876)
		(end 74.806048 -9.5504)
		(width 0.14478)
		(layer "F.Cu")
		(net "CPU_TX_PCIE_MGT_3_RXP")
	)
	(segment
		(start 74.806048 -9.5504)
		(end 74.832464 -9.5504)
		(width 0.14478)
		(layer "F.Cu")
		(net "CPU_TX_PCIE_MGT_3_RXP")
	)
	(segment
		(start 73.9648 -6.165342)
		(end 73.9648 -8.99922)
		(width 0.14478)
		(layer "F.Cu")
		(net "CPU_TX_PCIE_MGT_3_RXP")
	)
	(segment
		(start 74.971402 -9.608058)
		(end 75.14209 -9.779)
		(width 0.14478)
		(layer "F.Cu")
		(net "CPU_TX_PCIE_MGT_3_RXP")
	)
	(segment
		(start 73.64984 -3.500374)
		(end 73.64984 -5.539232)
		(width 0.14478)
		(layer "F.Cu")
		(net "CPU_TX_PCIE_MGT_3_RXP")
	)
	(segment
		(start 101.847142 -41.823132)
		(end 101.34727 -41.32326)
		(width 0.09906)
		(layer "F.Cu")
		(net "CPU_TX_PCIE_MGT_3_RXP")
	)
	(segment
		(start 73.760584 -5.80644)
		(end 73.855326 -5.901182)
		(width 0.14478)
		(layer "F.Cu")
		(net "CPU_TX_PCIE_MGT_3_RXP")
	)
	(via
		(at 75.14209 -9.779)
		(size 0.4572)
		(drill 0.2032)
		(layers "F.Cu" "B.Cu")
		(net "CPU_TX_PCIE_MGT_3_RXP")
	)
	(via
		(at 101.34727 -41.32326)
		(size 0.4572)
		(drill 0.2032)
		(layers "F.Cu" "B.Cu")
		(net "CPU_TX_PCIE_MGT_3_RXP")
	)
	(arc
		(start 73.64984 -5.539232)
		(mid 73.678625 -5.683854)
		(end 73.760584 -5.80644)
		(width 0.14478)
		(layer "F.Cu")
		(net "CPU_TX_PCIE_MGT_3_RXP")
	)
	(arc
		(start 74.832464 -9.5504)
		(mid 74.907698 -9.565365)
		(end 74.971402 -9.608058)
		(width 0.14478)
		(layer "F.Cu")
		(net "CPU_TX_PCIE_MGT_3_RXP")
	)
	(arc
		(start 73.9648 -8.99922)
		(mid 74.124804 -9.386896)
		(end 74.511662 -9.548876)
		(width 0.14478)
		(layer "F.Cu")
		(net "CPU_TX_PCIE_MGT_3_RXP")
	)
	(arc
		(start 73.855326 -5.901182)
		(mid 73.936361 -6.022365)
		(end 73.9648 -6.165342)
		(width 0.14478)
		(layer "F.Cu")
		(net "CPU_TX_PCIE_MGT_3_RXP")
	)
	(segment
		(start 73.5838 -10.0711)
		(end 73.5838 -10.64133)
		(width 0.14478)
		(layer "B.Cu")
		(net "CPU_TX_PCIE_MGT_3_RXP")
	)
	(segment
		(start 101.133148 -41.32326)
		(end 101.34727 -41.32326)
		(width 0.09144)
		(layer "B.Cu")
		(net "CPU_TX_PCIE_MGT_3_RXP")
	)
	(segment
		(start 78.6638 -26.695146)
		(end 78.6638 -30.95879)
		(width 0.14478)
		(layer "B.Cu")
		(net "CPU_TX_PCIE_MGT_3_RXP")
	)
	(segment
		(start 97.743264 -40.63365)
		(end 97.766124 -40.63365)
		(width 0.09144)
		(layer "B.Cu")
		(net "CPU_TX_PCIE_MGT_3_RXP")
	)
	(segment
		(start 87.18042 -39.8526)
		(end 96.266254 -39.8526)
		(width 0.14478)
		(layer "B.Cu")
		(net "CPU_TX_PCIE_MGT_3_RXP")
	)
	(segment
		(start 74.620882 -9.5631)
		(end 74.0918 -9.5631)
		(width 0.14478)
		(layer "B.Cu")
		(net "CPU_TX_PCIE_MGT_3_RXP")
	)
	(segment
		(start 97.766124 -40.63365)
		(end 97.866454 -40.73398)
		(width 0.09144)
		(layer "B.Cu")
		(net "CPU_TX_PCIE_MGT_3_RXP")
	)
	(segment
		(start 73.5838 -11.44905)
		(end 73.5838 -18.305526)
		(width 0.14478)
		(layer "B.Cu")
		(net "CPU_TX_PCIE_MGT_3_RXP")
	)
	(segment
		(start 79.326994 -32.560006)
		(end 86.223094 -39.456106)
		(width 0.14478)
		(layer "B.Cu")
		(net "CPU_TX_PCIE_MGT_3_RXP")
	)
	(segment
		(start 96.91624 -40.12184)
		(end 97.351088 -40.556688)
		(width 0.14478)
		(layer "B.Cu")
		(net "CPU_TX_PCIE_MGT_3_RXP")
	)
	(segment
		(start 100.937314 -41.112694)
		(end 100.937314 -41.127426)
		(width 0.09144)
		(layer "B.Cu")
		(net "CPU_TX_PCIE_MGT_3_RXP")
	)
	(segment
		(start 73.8124 -10.86993)
		(end 73.8124 -11.22045)
		(width 0.14478)
		(layer "B.Cu")
		(net "CPU_TX_PCIE_MGT_3_RXP")
	)
	(segment
		(start 97.866454 -40.73398)
		(end 100.5586 -40.73398)
		(width 0.09144)
		(layer "B.Cu")
		(net "CPU_TX_PCIE_MGT_3_RXP")
	)
	(segment
		(start 97.536508 -40.63365)
		(end 97.743264 -40.63365)
		(width 0.14478)
		(layer "B.Cu")
		(net "CPU_TX_PCIE_MGT_3_RXP")
	)
	(segment
		(start 74.424794 -21.460206)
		(end 77.959458 -24.99487)
		(width 0.14478)
		(layer "B.Cu")
		(net "CPU_TX_PCIE_MGT_3_RXP")
	)
	(segment
		(start 74.0156 -19.34845)
		(end 74.0156 -20.4724)
		(width 0.14478)
		(layer "B.Cu")
		(net "CPU_TX_PCIE_MGT_3_RXP")
	)
	(arc
		(start 96.266254 -39.8526)
		(mid 96.617987 -39.92264)
		(end 96.91624 -40.12184)
		(width 0.14478)
		(layer "B.Cu")
		(net "CPU_TX_PCIE_MGT_3_RXP")
	)
	(arc
		(start 74.0156 -20.4724)
		(mid 74.12194 -21.007009)
		(end 74.424794 -21.460206)
		(width 0.14478)
		(layer "B.Cu")
		(net "CPU_TX_PCIE_MGT_3_RXP")
	)
	(arc
		(start 75.14209 -9.779)
		(mid 74.902958 -9.619217)
		(end 74.620882 -9.5631)
		(width 0.14478)
		(layer "B.Cu")
		(net "CPU_TX_PCIE_MGT_3_RXP")
	)
	(arc
		(start 86.223094 -39.456106)
		(mid 86.662319 -39.749587)
		(end 87.18042 -39.8526)
		(width 0.14478)
		(layer "B.Cu")
		(net "CPU_TX_PCIE_MGT_3_RXP")
	)
	(arc
		(start 97.351088 -40.556688)
		(mid 97.436159 -40.61356)
		(end 97.536508 -40.63365)
		(width 0.14478)
		(layer "B.Cu")
		(net "CPU_TX_PCIE_MGT_3_RXP")
	)
	(arc
		(start 73.6981 -11.33475)
		(mid 73.617278 -11.368228)
		(end 73.5838 -11.44905)
		(width 0.14478)
		(layer "B.Cu")
		(net "CPU_TX_PCIE_MGT_3_RXP")
	)
	(arc
		(start 73.5838 -18.305526)
		(mid 73.636603 -18.570984)
		(end 73.787 -18.796)
		(width 0.14478)
		(layer "B.Cu")
		(net "CPU_TX_PCIE_MGT_3_RXP")
	)
	(arc
		(start 78.6638 -30.95879)
		(mid 78.836168 -31.825342)
		(end 79.326994 -32.560006)
		(width 0.14478)
		(layer "B.Cu")
		(net "CPU_TX_PCIE_MGT_3_RXP")
	)
	(arc
		(start 77.959458 -24.99487)
		(mid 78.4807 -25.774963)
		(end 78.6638 -26.695146)
		(width 0.14478)
		(layer "B.Cu")
		(net "CPU_TX_PCIE_MGT_3_RXP")
	)
	(arc
		(start 73.787 -18.796)
		(mid 73.956248 -19.049482)
		(end 74.0156 -19.34845)
		(width 0.14478)
		(layer "B.Cu")
		(net "CPU_TX_PCIE_MGT_3_RXP")
	)
	(arc
		(start 73.8124 -11.22045)
		(mid 73.778922 -11.301272)
		(end 73.6981 -11.33475)
		(width 0.14478)
		(layer "B.Cu")
		(net "CPU_TX_PCIE_MGT_3_RXP")
	)
	(arc
		(start 100.937314 -41.127426)
		(mid 100.994672 -41.265902)
		(end 101.133148 -41.32326)
		(width 0.09144)
		(layer "B.Cu")
		(net "CPU_TX_PCIE_MGT_3_RXP")
	)
	(arc
		(start 100.5586 -40.73398)
		(mid 100.826391 -40.844903)
		(end 100.937314 -41.112694)
		(width 0.09144)
		(layer "B.Cu")
		(net "CPU_TX_PCIE_MGT_3_RXP")
	)
	(arc
		(start 73.6981 -10.75563)
		(mid 73.778922 -10.789108)
		(end 73.8124 -10.86993)
		(width 0.14478)
		(layer "B.Cu")
		(net "CPU_TX_PCIE_MGT_3_RXP")
	)
	(arc
		(start 73.5838 -10.64133)
		(mid 73.617278 -10.722152)
		(end 73.6981 -10.75563)
		(width 0.14478)
		(layer "B.Cu")
		(net "CPU_TX_PCIE_MGT_3_RXP")
	)
	(arc
		(start 74.0918 -9.5631)
		(mid 73.73259 -9.71189)
		(end 73.5838 -10.0711)
		(width 0.14478)
		(layer "B.Cu")
		(net "CPU_TX_PCIE_MGT_3_RXP")
	)
	(segment
		(start 74.649838 -3.500374)
		(end 74.649838 -5.477256)
		(width 0.14478)
		(layer "F.Cu")
		(net "CPU_TX_PCIE_MGT_3_RXN")
	)
	(segment
		(start 74.3458 -6.205474)
		(end 74.3458 -8.99922)
		(width 0.14478)
		(layer "F.Cu")
		(net "CPU_TX_PCIE_MGT_3_RXN")
	)
	(segment
		(start 100.84689 -41.823132)
		(end 100.347018 -41.32326)
		(width 0.09906)
		(layer "F.Cu")
		(net "CPU_TX_PCIE_MGT_3_RXN")
	)
	(segment
		(start 74.807064 -9.1694)
		(end 74.832718 -9.1694)
		(width 0.14478)
		(layer "F.Cu")
		(net "CPU_TX_PCIE_MGT_3_RXN")
	)
	(segment
		(start 74.513694 -9.167876)
		(end 74.807064 -9.1694)
		(width 0.14478)
		(layer "F.Cu")
		(net "CPU_TX_PCIE_MGT_3_RXN")
	)
	(segment
		(start 75.01382 -9.094216)
		(end 75.14209 -8.9662)
		(width 0.14478)
		(layer "F.Cu")
		(net "CPU_TX_PCIE_MGT_3_RXN")
	)
	(segment
		(start 74.49566 -5.849366)
		(end 74.491596 -5.85343)
		(width 0.14478)
		(layer "F.Cu")
		(net "CPU_TX_PCIE_MGT_3_RXN")
	)
	(via
		(at 75.14209 -8.9662)
		(size 0.4572)
		(drill 0.2032)
		(layers "F.Cu" "B.Cu")
		(net "CPU_TX_PCIE_MGT_3_RXN")
	)
	(via
		(at 100.347018 -41.32326)
		(size 0.4572)
		(drill 0.2032)
		(layers "F.Cu" "B.Cu")
		(net "CPU_TX_PCIE_MGT_3_RXN")
	)
	(arc
		(start 74.3458 -8.99922)
		(mid 74.394929 -9.118208)
		(end 74.513694 -9.167876)
		(width 0.14478)
		(layer "F.Cu")
		(net "CPU_TX_PCIE_MGT_3_RXN")
	)
	(arc
		(start 74.832718 -9.1694)
		(mid 74.930741 -9.149808)
		(end 75.01382 -9.094216)
		(width 0.14478)
		(layer "F.Cu")
		(net "CPU_TX_PCIE_MGT_3_RXN")
	)
	(arc
		(start 74.491596 -5.85343)
		(mid 74.383672 -6.014949)
		(end 74.3458 -6.205474)
		(width 0.14478)
		(layer "F.Cu")
		(net "CPU_TX_PCIE_MGT_3_RXN")
	)
	(arc
		(start 74.649838 -5.477256)
		(mid 74.609762 -5.678643)
		(end 74.49566 -5.849366)
		(width 0.14478)
		(layer "F.Cu")
		(net "CPU_TX_PCIE_MGT_3_RXN")
	)
	(segment
		(start 79.0575 -32.8295)
		(end 85.9536 -39.7256)
		(width 0.14478)
		(layer "B.Cu")
		(net "CPU_TX_PCIE_MGT_3_RXN")
	)
	(segment
		(start 73.6346 -19.348196)
		(end 73.6346 -20.472654)
		(width 0.14478)
		(layer "B.Cu")
		(net "CPU_TX_PCIE_MGT_3_RXN")
	)
	(segment
		(start 74.1553 -21.7297)
		(end 77.689964 -25.264364)
		(width 0.14478)
		(layer "B.Cu")
		(net "CPU_TX_PCIE_MGT_3_RXN")
	)
	(segment
		(start 97.743264 -41.01465)
		(end 97.766124 -41.01465)
		(width 0.09144)
		(layer "B.Cu")
		(net "CPU_TX_PCIE_MGT_3_RXN")
	)
	(segment
		(start 73.2028 -10.0711)
		(end 73.2028 -18.30578)
		(width 0.14478)
		(layer "B.Cu")
		(net "CPU_TX_PCIE_MGT_3_RXN")
	)
	(segment
		(start 97.866454 -40.91432)
		(end 100.5586 -40.91432)
		(width 0.09144)
		(layer "B.Cu")
		(net "CPU_TX_PCIE_MGT_3_RXN")
	)
	(segment
		(start 74.620882 -9.1821)
		(end 74.0918 -9.1821)
		(width 0.14478)
		(layer "B.Cu")
		(net "CPU_TX_PCIE_MGT_3_RXN")
	)
	(segment
		(start 87.180674 -40.2336)
		(end 96.266 -40.2336)
		(width 0.14478)
		(layer "B.Cu")
		(net "CPU_TX_PCIE_MGT_3_RXN")
	)
	(segment
		(start 97.766124 -41.01465)
		(end 97.866454 -40.91432)
		(width 0.09144)
		(layer "B.Cu")
		(net "CPU_TX_PCIE_MGT_3_RXN")
	)
	(segment
		(start 96.646746 -40.391334)
		(end 97.081594 -40.826182)
		(width 0.14478)
		(layer "B.Cu")
		(net "CPU_TX_PCIE_MGT_3_RXN")
	)
	(segment
		(start 100.566728 -41.32326)
		(end 100.347018 -41.32326)
		(width 0.09144)
		(layer "B.Cu")
		(net "CPU_TX_PCIE_MGT_3_RXN")
	)
	(segment
		(start 78.2828 -26.6954)
		(end 78.2828 -30.958536)
		(width 0.14478)
		(layer "B.Cu")
		(net "CPU_TX_PCIE_MGT_3_RXN")
	)
	(segment
		(start 97.536762 -41.01465)
		(end 97.743264 -41.01465)
		(width 0.14478)
		(layer "B.Cu")
		(net "CPU_TX_PCIE_MGT_3_RXN")
	)
	(segment
		(start 100.756974 -41.112694)
		(end 100.756974 -41.133014)
		(width 0.09144)
		(layer "B.Cu")
		(net "CPU_TX_PCIE_MGT_3_RXN")
	)
	(arc
		(start 75.14209 -8.9662)
		(mid 74.902958 -9.125983)
		(end 74.620882 -9.1821)
		(width 0.14478)
		(layer "B.Cu")
		(net "CPU_TX_PCIE_MGT_3_RXN")
	)
	(arc
		(start 74.0918 -9.1821)
		(mid 73.463182 -9.442482)
		(end 73.2028 -10.0711)
		(width 0.14478)
		(layer "B.Cu")
		(net "CPU_TX_PCIE_MGT_3_RXN")
	)
	(arc
		(start 78.2828 -30.958536)
		(mid 78.484038 -31.971081)
		(end 79.0575 -32.8295)
		(width 0.14478)
		(layer "B.Cu")
		(net "CPU_TX_PCIE_MGT_3_RXN")
	)
	(arc
		(start 100.756974 -41.133014)
		(mid 100.701252 -41.267538)
		(end 100.566728 -41.32326)
		(width 0.09144)
		(layer "B.Cu")
		(net "CPU_TX_PCIE_MGT_3_RXN")
	)
	(arc
		(start 73.2028 -18.30578)
		(mid 73.284653 -18.716903)
		(end 73.517506 -19.065494)
		(width 0.14478)
		(layer "B.Cu")
		(net "CPU_TX_PCIE_MGT_3_RXN")
	)
	(arc
		(start 73.6346 -20.472654)
		(mid 73.769991 -21.152928)
		(end 74.1553 -21.7297)
		(width 0.14478)
		(layer "B.Cu")
		(net "CPU_TX_PCIE_MGT_3_RXN")
	)
	(arc
		(start 85.9536 -39.7256)
		(mid 86.516602 -40.101663)
		(end 87.180674 -40.2336)
		(width 0.14478)
		(layer "B.Cu")
		(net "CPU_TX_PCIE_MGT_3_RXN")
	)
	(arc
		(start 96.266 -40.2336)
		(mid 96.472067 -40.274589)
		(end 96.646746 -40.391334)
		(width 0.14478)
		(layer "B.Cu")
		(net "CPU_TX_PCIE_MGT_3_RXN")
	)
	(arc
		(start 97.081594 -40.826182)
		(mid 97.290441 -40.965666)
		(end 97.536762 -41.01465)
		(width 0.14478)
		(layer "B.Cu")
		(net "CPU_TX_PCIE_MGT_3_RXN")
	)
	(arc
		(start 100.5586 -40.91432)
		(mid 100.698872 -40.972422)
		(end 100.756974 -41.112694)
		(width 0.09144)
		(layer "B.Cu")
		(net "CPU_TX_PCIE_MGT_3_RXN")
	)
	(arc
		(start 77.689964 -25.264364)
		(mid 78.12872 -25.920915)
		(end 78.2828 -26.6954)
		(width 0.14478)
		(layer "B.Cu")
		(net "CPU_TX_PCIE_MGT_3_RXN")
	)
	(arc
		(start 73.517506 -19.065494)
		(mid 73.604172 -19.195199)
		(end 73.6346 -19.348196)
		(width 0.14478)
		(layer "B.Cu")
		(net "CPU_TX_PCIE_MGT_3_RXN")
	)
	(segment
		(start 70.991476 -9.628378)
		(end 71.142098 -9.779)
		(width 0.14478)
		(layer "F.Cu")
		(net "CPU_TX_PCIE_MGT_2_RXP")
	)
	(segment
		(start 69.80047 -5.846318)
		(end 69.877178 -5.923026)
		(width 0.14478)
		(layer "F.Cu")
		(net "CPU_TX_PCIE_MGT_2_RXP")
	)
	(segment
		(start 99.846892 -42.82313)
		(end 99.34702 -42.323258)
		(width 0.09906)
		(layer "F.Cu")
		(net "CPU_TX_PCIE_MGT_2_RXP")
	)
	(segment
		(start 70.627494 -9.5758)
		(end 70.864476 -9.5758)
		(width 0.14478)
		(layer "F.Cu")
		(net "CPU_TX_PCIE_MGT_2_RXP")
	)
	(segment
		(start 69.977 -6.163818)
		(end 69.977 -8.925306)
		(width 0.14478)
		(layer "F.Cu")
		(net "CPU_TX_PCIE_MGT_2_RXP")
	)
	(segment
		(start 69.649848 -3.500374)
		(end 69.649848 -5.48259)
		(width 0.14478)
		(layer "F.Cu")
		(net "CPU_TX_PCIE_MGT_2_RXP")
	)
	(via
		(at 99.34702 -42.323258)
		(size 0.4572)
		(drill 0.2032)
		(layers "F.Cu" "B.Cu")
		(net "CPU_TX_PCIE_MGT_2_RXP")
	)
	(via
		(at 71.142098 -9.779)
		(size 0.4572)
		(drill 0.2032)
		(layers "F.Cu" "B.Cu")
		(net "CPU_TX_PCIE_MGT_2_RXP")
	)
	(arc
		(start 69.877178 -5.923026)
		(mid 69.95105 -6.033488)
		(end 69.977 -6.163818)
		(width 0.14478)
		(layer "F.Cu")
		(net "CPU_TX_PCIE_MGT_2_RXP")
	)
	(arc
		(start 70.864476 -9.5758)
		(mid 70.933198 -9.58947)
		(end 70.991476 -9.628378)
		(width 0.14478)
		(layer "F.Cu")
		(net "CPU_TX_PCIE_MGT_2_RXP")
	)
	(arc
		(start 69.977 -8.925306)
		(mid 70.167525 -9.385275)
		(end 70.627494 -9.5758)
		(width 0.14478)
		(layer "F.Cu")
		(net "CPU_TX_PCIE_MGT_2_RXP")
	)
	(arc
		(start 69.649848 -5.48259)
		(mid 69.688986 -5.679437)
		(end 69.80047 -5.846318)
		(width 0.14478)
		(layer "F.Cu")
		(net "CPU_TX_PCIE_MGT_2_RXP")
	)
	(segment
		(start 70.9422 -20.2184)
		(end 71.196454 -20.2184)
		(width 0.14478)
		(layer "B.Cu")
		(net "CPU_TX_PCIE_MGT_2_RXP")
	)
	(segment
		(start 85.41512 -40.894)
		(end 95.479108 -40.894)
		(width 0.14478)
		(layer "B.Cu")
		(net "CPU_TX_PCIE_MGT_2_RXP")
	)
	(segment
		(start 98.819462 -41.831514)
		(end 98.835718 -41.84777)
		(width 0.09144)
		(layer "B.Cu")
		(net "CPU_TX_PCIE_MGT_2_RXP")
	)
	(segment
		(start 96.168972 -41.180004)
		(end 96.436942 -41.447974)
		(width 0.14478)
		(layer "B.Cu")
		(net "CPU_TX_PCIE_MGT_2_RXP")
	)
	(segment
		(start 96.87433 -41.62933)
		(end 97.46488 -41.62933)
		(width 0.14478)
		(layer "B.Cu")
		(net "CPU_TX_PCIE_MGT_2_RXP")
	)
	(segment
		(start 70.2564 -11.835638)
		(end 70.2564 -16.936212)
		(width 0.14478)
		(layer "B.Cu")
		(net "CPU_TX_PCIE_MGT_2_RXP")
	)
	(segment
		(start 70.68947 -9.591548)
		(end 70.5612 -9.591548)
		(width 0.14478)
		(layer "B.Cu")
		(net "CPU_TX_PCIE_MGT_2_RXP")
	)
	(segment
		(start 70.2564 -9.896348)
		(end 70.2564 -11.086338)
		(width 0.14478)
		(layer "B.Cu")
		(net "CPU_TX_PCIE_MGT_2_RXP")
	)
	(segment
		(start 77.094334 -33.076388)
		(end 84.5566 -40.5384)
		(width 0.14478)
		(layer "B.Cu")
		(net "CPU_TX_PCIE_MGT_2_RXP")
	)
	(segment
		(start 97.46488 -41.62933)
		(end 97.48774 -41.62933)
		(width 0.09144)
		(layer "B.Cu")
		(net "CPU_TX_PCIE_MGT_2_RXP")
	)
	(segment
		(start 70.42658 -11.256518)
		(end 70.42658 -11.665458)
		(width 0.14478)
		(layer "B.Cu")
		(net "CPU_TX_PCIE_MGT_2_RXP")
	)
	(segment
		(start 76.5556 -26.136854)
		(end 76.5556 -31.7754)
		(width 0.14478)
		(layer "B.Cu")
		(net "CPU_TX_PCIE_MGT_2_RXP")
	)
	(segment
		(start 98.937318 -42.094404)
		(end 98.937318 -42.145458)
		(width 0.09144)
		(layer "B.Cu")
		(net "CPU_TX_PCIE_MGT_2_RXP")
	)
	(segment
		(start 70.2564 -17.675352)
		(end 70.2564 -19.5326)
		(width 0.14478)
		(layer "B.Cu")
		(net "CPU_TX_PCIE_MGT_2_RXP")
	)
	(segment
		(start 97.48774 -41.62933)
		(end 97.58807 -41.72966)
		(width 0.09144)
		(layer "B.Cu")
		(net "CPU_TX_PCIE_MGT_2_RXP")
	)
	(segment
		(start 97.58807 -41.72966)
		(end 98.572574 -41.72966)
		(width 0.09144)
		(layer "B.Cu")
		(net "CPU_TX_PCIE_MGT_2_RXP")
	)
	(segment
		(start 71.855838 -20.49145)
		(end 75.887326 -24.522938)
		(width 0.14478)
		(layer "B.Cu")
		(net "CPU_TX_PCIE_MGT_2_RXP")
	)
	(segment
		(start 70.41642 -17.096232)
		(end 70.41642 -17.515332)
		(width 0.14478)
		(layer "B.Cu")
		(net "CPU_TX_PCIE_MGT_2_RXP")
	)
	(segment
		(start 99.115118 -42.323258)
		(end 99.34702 -42.323258)
		(width 0.09144)
		(layer "B.Cu")
		(net "CPU_TX_PCIE_MGT_2_RXP")
	)
	(arc
		(start 70.34149 -11.171428)
		(mid 70.401658 -11.19635)
		(end 70.42658 -11.256518)
		(width 0.14478)
		(layer "B.Cu")
		(net "CPU_TX_PCIE_MGT_2_RXP")
	)
	(arc
		(start 75.887326 -24.522938)
		(mid 76.381981 -25.263425)
		(end 76.5556 -26.136854)
		(width 0.14478)
		(layer "B.Cu")
		(net "CPU_TX_PCIE_MGT_2_RXP")
	)
	(arc
		(start 70.33641 -17.016222)
		(mid 70.392986 -17.039656)
		(end 70.41642 -17.096232)
		(width 0.14478)
		(layer "B.Cu")
		(net "CPU_TX_PCIE_MGT_2_RXP")
	)
	(arc
		(start 84.5566 -40.5384)
		(mid 84.950492 -40.80159)
		(end 85.41512 -40.894)
		(width 0.14478)
		(layer "B.Cu")
		(net "CPU_TX_PCIE_MGT_2_RXP")
	)
	(arc
		(start 71.196454 -20.2184)
		(mid 71.553309 -20.289347)
		(end 71.855838 -20.49145)
		(width 0.14478)
		(layer "B.Cu")
		(net "CPU_TX_PCIE_MGT_2_RXP")
	)
	(arc
		(start 98.835718 -41.84777)
		(mid 98.911 -41.960999)
		(end 98.937318 -42.094404)
		(width 0.09144)
		(layer "B.Cu")
		(net "CPU_TX_PCIE_MGT_2_RXP")
	)
	(arc
		(start 70.5612 -9.591548)
		(mid 70.345674 -9.680822)
		(end 70.2564 -9.896348)
		(width 0.14478)
		(layer "B.Cu")
		(net "CPU_TX_PCIE_MGT_2_RXP")
	)
	(arc
		(start 76.5556 -31.7754)
		(mid 76.695558 -32.479485)
		(end 77.094334 -33.076388)
		(width 0.14478)
		(layer "B.Cu")
		(net "CPU_TX_PCIE_MGT_2_RXP")
	)
	(arc
		(start 98.937318 -42.145458)
		(mid 98.989394 -42.271182)
		(end 99.115118 -42.323258)
		(width 0.09144)
		(layer "B.Cu")
		(net "CPU_TX_PCIE_MGT_2_RXP")
	)
	(arc
		(start 70.33641 -17.595342)
		(mid 70.279834 -17.618776)
		(end 70.2564 -17.675352)
		(width 0.14478)
		(layer "B.Cu")
		(net "CPU_TX_PCIE_MGT_2_RXP")
	)
	(arc
		(start 71.142098 -9.779)
		(mid 70.934431 -9.640241)
		(end 70.68947 -9.591548)
		(width 0.14478)
		(layer "B.Cu")
		(net "CPU_TX_PCIE_MGT_2_RXP")
	)
	(arc
		(start 70.42658 -11.665458)
		(mid 70.401658 -11.725626)
		(end 70.34149 -11.750548)
		(width 0.14478)
		(layer "B.Cu")
		(net "CPU_TX_PCIE_MGT_2_RXP")
	)
	(arc
		(start 98.572574 -41.72966)
		(mid 98.706167 -41.756011)
		(end 98.819462 -41.831514)
		(width 0.09144)
		(layer "B.Cu")
		(net "CPU_TX_PCIE_MGT_2_RXP")
	)
	(arc
		(start 70.2564 -16.936212)
		(mid 70.279834 -16.992788)
		(end 70.33641 -17.016222)
		(width 0.14478)
		(layer "B.Cu")
		(net "CPU_TX_PCIE_MGT_2_RXP")
	)
	(arc
		(start 70.2564 -19.5326)
		(mid 70.457266 -20.017534)
		(end 70.9422 -20.2184)
		(width 0.14478)
		(layer "B.Cu")
		(net "CPU_TX_PCIE_MGT_2_RXP")
	)
	(arc
		(start 96.436942 -41.447974)
		(mid 96.637588 -41.582198)
		(end 96.87433 -41.62933)
		(width 0.14478)
		(layer "B.Cu")
		(net "CPU_TX_PCIE_MGT_2_RXP")
	)
	(arc
		(start 70.2564 -11.086338)
		(mid 70.281322 -11.146506)
		(end 70.34149 -11.171428)
		(width 0.14478)
		(layer "B.Cu")
		(net "CPU_TX_PCIE_MGT_2_RXP")
	)
	(arc
		(start 95.479108 -40.894)
		(mid 95.852474 -40.968397)
		(end 96.168972 -41.180004)
		(width 0.14478)
		(layer "B.Cu")
		(net "CPU_TX_PCIE_MGT_2_RXP")
	)
	(arc
		(start 70.41642 -17.515332)
		(mid 70.392986 -17.571908)
		(end 70.33641 -17.595342)
		(width 0.14478)
		(layer "B.Cu")
		(net "CPU_TX_PCIE_MGT_2_RXP")
	)
	(arc
		(start 70.34149 -11.750548)
		(mid 70.281322 -11.77547)
		(end 70.2564 -11.835638)
		(width 0.14478)
		(layer "B.Cu")
		(net "CPU_TX_PCIE_MGT_2_RXP")
	)
	(segment
		(start 70.649846 -3.500374)
		(end 70.649846 -5.477256)
		(width 0.14478)
		(layer "F.Cu")
		(net "CPU_TX_PCIE_MGT_2_RXN")
	)
	(segment
		(start 98.846894 -42.82313)
		(end 98.347022 -42.323258)
		(width 0.09906)
		(layer "F.Cu")
		(net "CPU_TX_PCIE_MGT_2_RXN")
	)
	(segment
		(start 70.358 -6.168136)
		(end 70.358 -8.925306)
		(width 0.14478)
		(layer "F.Cu")
		(net "CPU_TX_PCIE_MGT_2_RXN")
	)
	(segment
		(start 70.957186 -9.150858)
		(end 71.142098 -8.9662)
		(width 0.14478)
		(layer "F.Cu")
		(net "CPU_TX_PCIE_MGT_2_RXN")
	)
	(segment
		(start 70.627494 -9.1948)
		(end 70.851522 -9.1948)
		(width 0.14478)
		(layer "F.Cu")
		(net "CPU_TX_PCIE_MGT_2_RXN")
	)
	(segment
		(start 70.495668 -5.849366)
		(end 70.486016 -5.859018)
		(width 0.14478)
		(layer "F.Cu")
		(net "CPU_TX_PCIE_MGT_2_RXN")
	)
	(via
		(at 98.347022 -42.323258)
		(size 0.4572)
		(drill 0.2032)
		(layers "F.Cu" "B.Cu")
		(net "CPU_TX_PCIE_MGT_2_RXN")
	)
	(via
		(at 71.142098 -8.9662)
		(size 0.4572)
		(drill 0.2032)
		(layers "F.Cu" "B.Cu")
		(net "CPU_TX_PCIE_MGT_2_RXN")
	)
	(arc
		(start 70.649846 -5.477256)
		(mid 70.60977 -5.678643)
		(end 70.495668 -5.849366)
		(width 0.14478)
		(layer "F.Cu")
		(net "CPU_TX_PCIE_MGT_2_RXN")
	)
	(arc
		(start 70.358 -8.925306)
		(mid 70.436933 -9.115867)
		(end 70.627494 -9.1948)
		(width 0.14478)
		(layer "F.Cu")
		(net "CPU_TX_PCIE_MGT_2_RXN")
	)
	(arc
		(start 70.851522 -9.1948)
		(mid 70.90872 -9.183329)
		(end 70.957186 -9.150858)
		(width 0.14478)
		(layer "F.Cu")
		(net "CPU_TX_PCIE_MGT_2_RXN")
	)
	(arc
		(start 70.486016 -5.859018)
		(mid 70.391252 -6.000843)
		(end 70.358 -6.168136)
		(width 0.14478)
		(layer "F.Cu")
		(net "CPU_TX_PCIE_MGT_2_RXN")
	)
	(segment
		(start 70.9422 -20.5994)
		(end 71.1962 -20.5994)
		(width 0.14478)
		(layer "B.Cu")
		(net "CPU_TX_PCIE_MGT_2_RXN")
	)
	(segment
		(start 98.756978 -42.094404)
		(end 98.756978 -42.231818)
		(width 0.09144)
		(layer "B.Cu")
		(net "CPU_TX_PCIE_MGT_2_RXN")
	)
	(segment
		(start 96.874076 -42.01033)
		(end 97.46488 -42.01033)
		(width 0.14478)
		(layer "B.Cu")
		(net "CPU_TX_PCIE_MGT_2_RXN")
	)
	(segment
		(start 71.586344 -20.760944)
		(end 75.617832 -24.792432)
		(width 0.14478)
		(layer "B.Cu")
		(net "CPU_TX_PCIE_MGT_2_RXN")
	)
	(segment
		(start 85.415374 -41.275)
		(end 95.478854 -41.275)
		(width 0.14478)
		(layer "B.Cu")
		(net "CPU_TX_PCIE_MGT_2_RXN")
	)
	(segment
		(start 76.1746 -26.1366)
		(end 76.1746 -31.775146)
		(width 0.14478)
		(layer "B.Cu")
		(net "CPU_TX_PCIE_MGT_2_RXN")
	)
	(segment
		(start 69.8754 -9.896348)
		(end 69.8754 -19.5326)
		(width 0.14478)
		(layer "B.Cu")
		(net "CPU_TX_PCIE_MGT_2_RXN")
	)
	(segment
		(start 97.58807 -41.91)
		(end 98.572574 -41.91)
		(width 0.09144)
		(layer "B.Cu")
		(net "CPU_TX_PCIE_MGT_2_RXN")
	)
	(segment
		(start 76.984606 -33.505394)
		(end 84.287106 -40.807894)
		(width 0.14478)
		(layer "B.Cu")
		(net "CPU_TX_PCIE_MGT_2_RXN")
	)
	(segment
		(start 71.142098 -8.9662)
		(end 71.046086 -9.062466)
		(width 0.14478)
		(layer "B.Cu")
		(net "CPU_TX_PCIE_MGT_2_RXN")
	)
	(segment
		(start 97.46488 -42.01033)
		(end 97.48774 -42.01033)
		(width 0.09144)
		(layer "B.Cu")
		(net "CPU_TX_PCIE_MGT_2_RXN")
	)
	(segment
		(start 95.899224 -41.449498)
		(end 96.167448 -41.717468)
		(width 0.14478)
		(layer "B.Cu")
		(net "CPU_TX_PCIE_MGT_2_RXN")
	)
	(segment
		(start 76.82484 -33.346136)
		(end 76.984352 -33.505394)
		(width 0.14478)
		(layer "B.Cu")
		(net "CPU_TX_PCIE_MGT_2_RXN")
	)
	(segment
		(start 76.984352 -33.505394)
		(end 76.984606 -33.505394)
		(width 0.14478)
		(layer "B.Cu")
		(net "CPU_TX_PCIE_MGT_2_RXN")
	)
	(segment
		(start 98.665538 -42.323258)
		(end 98.347022 -42.323258)
		(width 0.09144)
		(layer "B.Cu")
		(net "CPU_TX_PCIE_MGT_2_RXN")
	)
	(segment
		(start 70.6882 -9.210548)
		(end 70.5612 -9.210548)
		(width 0.14478)
		(layer "B.Cu")
		(net "CPU_TX_PCIE_MGT_2_RXN")
	)
	(segment
		(start 98.6917 -41.959276)
		(end 98.707702 -41.975278)
		(width 0.09144)
		(layer "B.Cu")
		(net "CPU_TX_PCIE_MGT_2_RXN")
	)
	(segment
		(start 97.48774 -42.01033)
		(end 97.58807 -41.91)
		(width 0.09144)
		(layer "B.Cu")
		(net "CPU_TX_PCIE_MGT_2_RXN")
	)
	(arc
		(start 71.046086 -9.062466)
		(mid 70.881871 -9.172098)
		(end 70.6882 -9.210548)
		(width 0.14478)
		(layer "B.Cu")
		(net "CPU_TX_PCIE_MGT_2_RXN")
	)
	(arc
		(start 96.167448 -41.717468)
		(mid 96.491637 -41.934177)
		(end 96.874076 -42.01033)
		(width 0.14478)
		(layer "B.Cu")
		(net "CPU_TX_PCIE_MGT_2_RXN")
	)
	(arc
		(start 75.617832 -24.792432)
		(mid 76.029904 -25.409142)
		(end 76.1746 -26.1366)
		(width 0.14478)
		(layer "B.Cu")
		(net "CPU_TX_PCIE_MGT_2_RXN")
	)
	(arc
		(start 71.1962 -20.5994)
		(mid 71.407336 -20.64138)
		(end 71.586344 -20.760944)
		(width 0.14478)
		(layer "B.Cu")
		(net "CPU_TX_PCIE_MGT_2_RXN")
	)
	(arc
		(start 98.707702 -41.975278)
		(mid 98.744168 -42.029948)
		(end 98.756978 -42.094404)
		(width 0.09144)
		(layer "B.Cu")
		(net "CPU_TX_PCIE_MGT_2_RXN")
	)
	(arc
		(start 76.1746 -31.775146)
		(mid 76.343447 -32.625321)
		(end 76.82484 -33.346136)
		(width 0.14478)
		(layer "B.Cu")
		(net "CPU_TX_PCIE_MGT_2_RXN")
	)
	(arc
		(start 69.8754 -19.5326)
		(mid 70.187858 -20.286942)
		(end 70.9422 -20.5994)
		(width 0.14478)
		(layer "B.Cu")
		(net "CPU_TX_PCIE_MGT_2_RXN")
	)
	(arc
		(start 98.756978 -42.231818)
		(mid 98.730196 -42.296476)
		(end 98.665538 -42.323258)
		(width 0.09144)
		(layer "B.Cu")
		(net "CPU_TX_PCIE_MGT_2_RXN")
	)
	(arc
		(start 70.5612 -9.210548)
		(mid 70.076266 -9.411414)
		(end 69.8754 -9.896348)
		(width 0.14478)
		(layer "B.Cu")
		(net "CPU_TX_PCIE_MGT_2_RXN")
	)
	(arc
		(start 84.287106 -40.807894)
		(mid 84.804776 -41.153667)
		(end 85.415374 -41.275)
		(width 0.14478)
		(layer "B.Cu")
		(net "CPU_TX_PCIE_MGT_2_RXN")
	)
	(arc
		(start 98.572574 -41.91)
		(mid 98.637033 -41.922804)
		(end 98.6917 -41.959276)
		(width 0.09144)
		(layer "B.Cu")
		(net "CPU_TX_PCIE_MGT_2_RXN")
	)
	(arc
		(start 95.478854 -41.275)
		(mid 95.706404 -41.32041)
		(end 95.899224 -41.449498)
		(width 0.14478)
		(layer "B.Cu")
		(net "CPU_TX_PCIE_MGT_2_RXN")
	)
	(segment
		(start 66.968624 -9.605518)
		(end 67.142106 -9.779)
		(width 0.14478)
		(layer "F.Cu")
		(net "CPU_TX_PCIE_MGT_1_RXP")
	)
	(segment
		(start 66.55308 -9.5504)
		(end 66.866008 -9.5504)
		(width 0.14478)
		(layer "F.Cu")
		(net "CPU_TX_PCIE_MGT_1_RXP")
	)
	(segment
		(start 66.866008 -9.5504)
		(end 66.866008 -9.5631)
		(width 0.14478)
		(layer "F.Cu")
		(net "CPU_TX_PCIE_MGT_1_RXP")
	)
	(segment
		(start 65.702688 -5.758942)
		(end 65.850516 -5.90677)
		(width 0.14478)
		(layer "F.Cu")
		(net "CPU_TX_PCIE_MGT_1_RXP")
	)
	(segment
		(start 65.649856 -3.500374)
		(end 65.649856 -5.631434)
		(width 0.14478)
		(layer "F.Cu")
		(net "CPU_TX_PCIE_MGT_1_RXP")
	)
	(segment
		(start 65.959228 -6.169152)
		(end 65.959228 -8.937498)
		(width 0.14478)
		(layer "F.Cu")
		(net "CPU_TX_PCIE_MGT_1_RXP")
	)
	(segment
		(start 101.847142 -43.823128)
		(end 101.34727 -43.323256)
		(width 0.09906)
		(layer "F.Cu")
		(net "CPU_TX_PCIE_MGT_1_RXP")
	)
	(via
		(at 101.34727 -43.323256)
		(size 0.4572)
		(drill 0.2032)
		(layers "F.Cu" "B.Cu")
		(net "CPU_TX_PCIE_MGT_1_RXP")
	)
	(via
		(at 67.142106 -9.779)
		(size 0.4572)
		(drill 0.2032)
		(layers "F.Cu" "B.Cu")
		(net "CPU_TX_PCIE_MGT_1_RXP")
	)
	(arc
		(start 65.649856 -5.631434)
		(mid 65.663584 -5.700447)
		(end 65.702688 -5.758942)
		(width 0.14478)
		(layer "F.Cu")
		(net "CPU_TX_PCIE_MGT_1_RXP")
	)
	(arc
		(start 65.850516 -5.90677)
		(mid 65.930953 -6.027152)
		(end 65.959228 -6.169152)
		(width 0.14478)
		(layer "F.Cu")
		(net "CPU_TX_PCIE_MGT_1_RXP")
	)
	(arc
		(start 66.157094 -9.394444)
		(mid 66.340224 -9.510171)
		(end 66.55308 -9.5504)
		(width 0.14478)
		(layer "F.Cu")
		(net "CPU_TX_PCIE_MGT_1_RXP")
	)
	(arc
		(start 65.959228 -8.937498)
		(mid 66.010793 -9.186469)
		(end 66.157094 -9.394444)
		(width 0.14478)
		(layer "F.Cu")
		(net "CPU_TX_PCIE_MGT_1_RXP")
	)
	(arc
		(start 66.866008 -9.5631)
		(mid 66.92151 -9.57414)
		(end 66.968624 -9.605518)
		(width 0.14478)
		(layer "F.Cu")
		(net "CPU_TX_PCIE_MGT_1_RXP")
	)
	(segment
		(start 97.756726 -42.71518)
		(end 100.550218 -42.71518)
		(width 0.09144)
		(layer "B.Cu")
		(net "CPU_TX_PCIE_MGT_1_RXP")
	)
	(segment
		(start 75.1078 -25.946608)
		(end 75.1078 -32.3596)
		(width 0.14478)
		(layer "B.Cu")
		(net "CPU_TX_PCIE_MGT_1_RXP")
	)
	(segment
		(start 97.656396 -42.61485)
		(end 97.756726 -42.71518)
		(width 0.09144)
		(layer "B.Cu")
		(net "CPU_TX_PCIE_MGT_1_RXP")
	)
	(segment
		(start 65.0494 -13.30706)
		(end 65.0494 -14.879066)
		(width 0.14478)
		(layer "B.Cu")
		(net "CPU_TX_PCIE_MGT_1_RXP")
	)
	(segment
		(start 95.4405 -42.3291)
		(end 95.478854 -42.367454)
		(width 0.14478)
		(layer "B.Cu")
		(net "CPU_TX_PCIE_MGT_1_RXP")
	)
	(segment
		(start 75.50277 -33.31337)
		(end 83.8581 -41.6687)
		(width 0.14478)
		(layer "B.Cu")
		(net "CPU_TX_PCIE_MGT_1_RXP")
	)
	(segment
		(start 71.702168 -21.86178)
		(end 74.627994 -24.787606)
		(width 0.14478)
		(layer "B.Cu")
		(net "CPU_TX_PCIE_MGT_1_RXP")
	)
	(segment
		(start 65.532 -12.573)
		(end 65.2272 -12.8778)
		(width 0.14478)
		(layer "B.Cu")
		(net "CPU_TX_PCIE_MGT_1_RXP")
	)
	(segment
		(start 65.5828 -18.9738)
		(end 67.5386 -20.9296)
		(width 0.14478)
		(layer "B.Cu")
		(net "CPU_TX_PCIE_MGT_1_RXP")
	)
	(segment
		(start 100.937314 -43.102276)
		(end 100.937314 -43.127422)
		(width 0.09144)
		(layer "B.Cu")
		(net "CPU_TX_PCIE_MGT_1_RXP")
	)
	(segment
		(start 97.633536 -42.61485)
		(end 97.656396 -42.61485)
		(width 0.09144)
		(layer "B.Cu")
		(net "CPU_TX_PCIE_MGT_1_RXP")
	)
	(segment
		(start 66.620898 -9.5631)
		(end 66.3194 -9.5631)
		(width 0.14478)
		(layer "B.Cu")
		(net "CPU_TX_PCIE_MGT_1_RXP")
	)
	(segment
		(start 101.133148 -43.323256)
		(end 101.34727 -43.323256)
		(width 0.09144)
		(layer "B.Cu")
		(net "CPU_TX_PCIE_MGT_1_RXP")
	)
	(segment
		(start 96.075754 -42.61485)
		(end 97.633536 -42.61485)
		(width 0.14478)
		(layer "B.Cu")
		(net "CPU_TX_PCIE_MGT_1_RXP")
	)
	(segment
		(start 65.0494 -15.691866)
		(end 65.0494 -17.68602)
		(width 0.14478)
		(layer "B.Cu")
		(net "CPU_TX_PCIE_MGT_1_RXP")
	)
	(segment
		(start 83.8581 -41.6687)
		(end 83.88096 -41.691306)
		(width 0.14478)
		(layer "B.Cu")
		(net "CPU_TX_PCIE_MGT_1_RXP")
	)
	(segment
		(start 84.5312 -41.9608)
		(end 94.550738 -41.9608)
		(width 0.14478)
		(layer "B.Cu")
		(net "CPU_TX_PCIE_MGT_1_RXP")
	)
	(segment
		(start 65.28308 -15.112746)
		(end 65.28308 -15.458186)
		(width 0.14478)
		(layer "B.Cu")
		(net "CPU_TX_PCIE_MGT_1_RXP")
	)
	(segment
		(start 65.8876 -9.9949)
		(end 65.8876 -11.71448)
		(width 0.14478)
		(layer "B.Cu")
		(net "CPU_TX_PCIE_MGT_1_RXP")
	)
	(segment
		(start 68.82638 -21.463)
		(end 70.739254 -21.463)
		(width 0.14478)
		(layer "B.Cu")
		(net "CPU_TX_PCIE_MGT_1_RXP")
	)
	(arc
		(start 70.739254 -21.463)
		(mid 71.260327 -21.566706)
		(end 71.702168 -21.86178)
		(width 0.14478)
		(layer "B.Cu")
		(net "CPU_TX_PCIE_MGT_1_RXP")
	)
	(arc
		(start 65.8876 -11.71448)
		(mid 65.795196 -12.179118)
		(end 65.532 -12.573)
		(width 0.14478)
		(layer "B.Cu")
		(net "CPU_TX_PCIE_MGT_1_RXP")
	)
	(arc
		(start 65.16624 -14.995906)
		(mid 65.248858 -15.030128)
		(end 65.28308 -15.112746)
		(width 0.14478)
		(layer "B.Cu")
		(net "CPU_TX_PCIE_MGT_1_RXP")
	)
	(arc
		(start 100.550218 -42.71518)
		(mid 100.823936 -42.828558)
		(end 100.937314 -43.102276)
		(width 0.09144)
		(layer "B.Cu")
		(net "CPU_TX_PCIE_MGT_1_RXP")
	)
	(arc
		(start 65.0494 -14.879066)
		(mid 65.083622 -14.961684)
		(end 65.16624 -14.995906)
		(width 0.14478)
		(layer "B.Cu")
		(net "CPU_TX_PCIE_MGT_1_RXP")
	)
	(arc
		(start 65.16624 -15.575026)
		(mid 65.083622 -15.609248)
		(end 65.0494 -15.691866)
		(width 0.14478)
		(layer "B.Cu")
		(net "CPU_TX_PCIE_MGT_1_RXP")
	)
	(arc
		(start 100.937314 -43.127422)
		(mid 100.994672 -43.265898)
		(end 101.133148 -43.323256)
		(width 0.09144)
		(layer "B.Cu")
		(net "CPU_TX_PCIE_MGT_1_RXP")
	)
	(arc
		(start 66.3194 -9.5631)
		(mid 66.014071 -9.689571)
		(end 65.8876 -9.9949)
		(width 0.14478)
		(layer "B.Cu")
		(net "CPU_TX_PCIE_MGT_1_RXP")
	)
	(arc
		(start 67.142106 -9.779)
		(mid 66.902974 -9.619217)
		(end 66.620898 -9.5631)
		(width 0.14478)
		(layer "B.Cu")
		(net "CPU_TX_PCIE_MGT_1_RXP")
	)
	(arc
		(start 65.28308 -15.458186)
		(mid 65.248858 -15.540804)
		(end 65.16624 -15.575026)
		(width 0.14478)
		(layer "B.Cu")
		(net "CPU_TX_PCIE_MGT_1_RXP")
	)
	(arc
		(start 83.88096 -41.691306)
		(mid 84.179278 -41.890728)
		(end 84.5312 -41.9608)
		(width 0.14478)
		(layer "B.Cu")
		(net "CPU_TX_PCIE_MGT_1_RXP")
	)
	(arc
		(start 94.550738 -41.9608)
		(mid 95.032271 -42.056413)
		(end 95.4405 -42.3291)
		(width 0.14478)
		(layer "B.Cu")
		(net "CPU_TX_PCIE_MGT_1_RXP")
	)
	(arc
		(start 95.478854 -42.367454)
		(mid 95.752713 -42.550471)
		(end 96.075754 -42.61485)
		(width 0.14478)
		(layer "B.Cu")
		(net "CPU_TX_PCIE_MGT_1_RXP")
	)
	(arc
		(start 65.0494 -17.68602)
		(mid 65.188029 -18.382955)
		(end 65.5828 -18.9738)
		(width 0.14478)
		(layer "B.Cu")
		(net "CPU_TX_PCIE_MGT_1_RXP")
	)
	(arc
		(start 75.1078 -32.3596)
		(mid 75.210452 -32.875755)
		(end 75.50277 -33.31337)
		(width 0.14478)
		(layer "B.Cu")
		(net "CPU_TX_PCIE_MGT_1_RXP")
	)
	(arc
		(start 74.627994 -24.787606)
		(mid 74.983189 -25.319376)
		(end 75.1078 -25.946608)
		(width 0.14478)
		(layer "B.Cu")
		(net "CPU_TX_PCIE_MGT_1_RXP")
	)
	(arc
		(start 65.2272 -12.8778)
		(mid 65.095605 -13.074746)
		(end 65.0494 -13.30706)
		(width 0.14478)
		(layer "B.Cu")
		(net "CPU_TX_PCIE_MGT_1_RXP")
	)
	(arc
		(start 67.5386 -20.9296)
		(mid 68.129438 -21.324386)
		(end 68.82638 -21.463)
		(width 0.14478)
		(layer "B.Cu")
		(net "CPU_TX_PCIE_MGT_1_RXP")
	)
	(segment
		(start 66.5226 -5.8166)
		(end 66.432176 -5.907024)
		(width 0.14478)
		(layer "F.Cu")
		(net "CPU_TX_PCIE_MGT_1_RXN")
	)
	(segment
		(start 66.340228 -6.12902)
		(end 66.340228 -8.937498)
		(width 0.14478)
		(layer "F.Cu")
		(net "CPU_TX_PCIE_MGT_1_RXN")
	)
	(segment
		(start 66.552826 -9.1694)
		(end 66.878962 -9.1694)
		(width 0.14478)
		(layer "F.Cu")
		(net "CPU_TX_PCIE_MGT_1_RXN")
	)
	(segment
		(start 100.84689 -43.823128)
		(end 100.347018 -43.323256)
		(width 0.09906)
		(layer "F.Cu")
		(net "CPU_TX_PCIE_MGT_1_RXN")
	)
	(segment
		(start 66.649854 -3.500374)
		(end 66.649854 -5.50926)
		(width 0.14478)
		(layer "F.Cu")
		(net "CPU_TX_PCIE_MGT_1_RXN")
	)
	(segment
		(start 66.981324 -9.126982)
		(end 67.142106 -8.9662)
		(width 0.14478)
		(layer "F.Cu")
		(net "CPU_TX_PCIE_MGT_1_RXN")
	)
	(via
		(at 100.347018 -43.323256)
		(size 0.4572)
		(drill 0.2032)
		(layers "F.Cu" "B.Cu")
		(net "CPU_TX_PCIE_MGT_1_RXN")
	)
	(via
		(at 67.142106 -8.9662)
		(size 0.4572)
		(drill 0.2032)
		(layers "F.Cu" "B.Cu")
		(net "CPU_TX_PCIE_MGT_1_RXN")
	)
	(arc
		(start 66.649854 -5.50926)
		(mid 66.616773 -5.675572)
		(end 66.5226 -5.8166)
		(width 0.14478)
		(layer "F.Cu")
		(net "CPU_TX_PCIE_MGT_1_RXN")
	)
	(arc
		(start 66.432176 -5.907024)
		(mid 66.36412 -6.008877)
		(end 66.340228 -6.12902)
		(width 0.14478)
		(layer "F.Cu")
		(net "CPU_TX_PCIE_MGT_1_RXN")
	)
	(arc
		(start 66.417698 -9.11606)
		(mid 66.480179 -9.155594)
		(end 66.552826 -9.1694)
		(width 0.14478)
		(layer "F.Cu")
		(net "CPU_TX_PCIE_MGT_1_RXN")
	)
	(arc
		(start 66.340228 -8.937498)
		(mid 66.360425 -9.034825)
		(end 66.417698 -9.11606)
		(width 0.14478)
		(layer "F.Cu")
		(net "CPU_TX_PCIE_MGT_1_RXN")
	)
	(arc
		(start 66.878962 -9.1694)
		(mid 66.934367 -9.158379)
		(end 66.981324 -9.126982)
		(width 0.14478)
		(layer "F.Cu")
		(net "CPU_TX_PCIE_MGT_1_RXN")
	)
	(segment
		(start 96.076008 -42.99585)
		(end 97.633536 -42.99585)
		(width 0.14478)
		(layer "B.Cu")
		(net "CPU_TX_PCIE_MGT_1_RXN")
	)
	(segment
		(start 75.233276 -33.582864)
		(end 83.588606 -41.938194)
		(width 0.14478)
		(layer "B.Cu")
		(net "CPU_TX_PCIE_MGT_1_RXN")
	)
	(segment
		(start 68.826634 -21.844)
		(end 70.739 -21.844)
		(width 0.14478)
		(layer "B.Cu")
		(net "CPU_TX_PCIE_MGT_1_RXN")
	)
	(segment
		(start 97.756726 -42.89552)
		(end 100.550218 -42.89552)
		(width 0.09144)
		(layer "B.Cu")
		(net "CPU_TX_PCIE_MGT_1_RXN")
	)
	(segment
		(start 100.56114 -43.323256)
		(end 100.347018 -43.323256)
		(width 0.09144)
		(layer "B.Cu")
		(net "CPU_TX_PCIE_MGT_1_RXN")
	)
	(segment
		(start 65.262506 -12.303506)
		(end 64.957706 -12.608306)
		(width 0.14478)
		(layer "B.Cu")
		(net "CPU_TX_PCIE_MGT_1_RXN")
	)
	(segment
		(start 95.171006 -42.598594)
		(end 95.20936 -42.636948)
		(width 0.14478)
		(layer "B.Cu")
		(net "CPU_TX_PCIE_MGT_1_RXN")
	)
	(segment
		(start 71.432674 -22.131274)
		(end 74.3585 -25.0571)
		(width 0.14478)
		(layer "B.Cu")
		(net "CPU_TX_PCIE_MGT_1_RXN")
	)
	(segment
		(start 83.588606 -41.938194)
		(end 83.612228 -41.961562)
		(width 0.14478)
		(layer "B.Cu")
		(net "CPU_TX_PCIE_MGT_1_RXN")
	)
	(segment
		(start 97.656396 -42.99585)
		(end 97.756726 -42.89552)
		(width 0.09144)
		(layer "B.Cu")
		(net "CPU_TX_PCIE_MGT_1_RXN")
	)
	(segment
		(start 64.6684 -13.30706)
		(end 64.6684 -17.685766)
		(width 0.14478)
		(layer "B.Cu")
		(net "CPU_TX_PCIE_MGT_1_RXN")
	)
	(segment
		(start 74.7268 -25.946354)
		(end 74.7268 -32.359346)
		(width 0.14478)
		(layer "B.Cu")
		(net "CPU_TX_PCIE_MGT_1_RXN")
	)
	(segment
		(start 66.620898 -9.1821)
		(end 66.3194 -9.1821)
		(width 0.14478)
		(layer "B.Cu")
		(net "CPU_TX_PCIE_MGT_1_RXN")
	)
	(segment
		(start 97.633536 -42.99585)
		(end 97.656396 -42.99585)
		(width 0.09144)
		(layer "B.Cu")
		(net "CPU_TX_PCIE_MGT_1_RXN")
	)
	(segment
		(start 84.530946 -42.3418)
		(end 94.550992 -42.3418)
		(width 0.14478)
		(layer "B.Cu")
		(net "CPU_TX_PCIE_MGT_1_RXN")
	)
	(segment
		(start 65.313306 -19.243294)
		(end 67.269106 -21.199094)
		(width 0.14478)
		(layer "B.Cu")
		(net "CPU_TX_PCIE_MGT_1_RXN")
	)
	(segment
		(start 100.756974 -43.102276)
		(end 100.756974 -43.127422)
		(width 0.09144)
		(layer "B.Cu")
		(net "CPU_TX_PCIE_MGT_1_RXN")
	)
	(segment
		(start 65.5066 -9.9949)
		(end 65.5066 -11.714226)
		(width 0.14478)
		(layer "B.Cu")
		(net "CPU_TX_PCIE_MGT_1_RXN")
	)
	(arc
		(start 67.269106 -21.199094)
		(mid 67.983722 -21.676462)
		(end 68.826634 -21.844)
		(width 0.14478)
		(layer "B.Cu")
		(net "CPU_TX_PCIE_MGT_1_RXN")
	)
	(arc
		(start 70.739 -21.844)
		(mid 71.114407 -21.918655)
		(end 71.432674 -22.131274)
		(width 0.14478)
		(layer "B.Cu")
		(net "CPU_TX_PCIE_MGT_1_RXN")
	)
	(arc
		(start 100.756974 -43.127422)
		(mid 100.699616 -43.265898)
		(end 100.56114 -43.323256)
		(width 0.09144)
		(layer "B.Cu")
		(net "CPU_TX_PCIE_MGT_1_RXN")
	)
	(arc
		(start 74.3585 -25.0571)
		(mid 74.631112 -25.465093)
		(end 74.7268 -25.946354)
		(width 0.14478)
		(layer "B.Cu")
		(net "CPU_TX_PCIE_MGT_1_RXN")
	)
	(arc
		(start 64.957706 -12.608306)
		(mid 64.743577 -12.928912)
		(end 64.6684 -13.30706)
		(width 0.14478)
		(layer "B.Cu")
		(net "CPU_TX_PCIE_MGT_1_RXN")
	)
	(arc
		(start 94.550992 -42.3418)
		(mid 94.886532 -42.408543)
		(end 95.171006 -42.598594)
		(width 0.14478)
		(layer "B.Cu")
		(net "CPU_TX_PCIE_MGT_1_RXN")
	)
	(arc
		(start 95.20936 -42.636948)
		(mid 95.606981 -42.90263)
		(end 96.076008 -42.99585)
		(width 0.14478)
		(layer "B.Cu")
		(net "CPU_TX_PCIE_MGT_1_RXN")
	)
	(arc
		(start 83.612228 -41.961562)
		(mid 84.033824 -42.242914)
		(end 84.530946 -42.3418)
		(width 0.14478)
		(layer "B.Cu")
		(net "CPU_TX_PCIE_MGT_1_RXN")
	)
	(arc
		(start 67.142106 -8.9662)
		(mid 66.902974 -9.125983)
		(end 66.620898 -9.1821)
		(width 0.14478)
		(layer "B.Cu")
		(net "CPU_TX_PCIE_MGT_1_RXN")
	)
	(arc
		(start 66.3194 -9.1821)
		(mid 65.744664 -9.420164)
		(end 65.5066 -9.9949)
		(width 0.14478)
		(layer "B.Cu")
		(net "CPU_TX_PCIE_MGT_1_RXN")
	)
	(arc
		(start 65.5066 -11.714226)
		(mid 65.443163 -12.033144)
		(end 65.262506 -12.303506)
		(width 0.14478)
		(layer "B.Cu")
		(net "CPU_TX_PCIE_MGT_1_RXN")
	)
	(arc
		(start 100.550218 -42.89552)
		(mid 100.696417 -42.956077)
		(end 100.756974 -43.102276)
		(width 0.09144)
		(layer "B.Cu")
		(net "CPU_TX_PCIE_MGT_1_RXN")
	)
	(arc
		(start 74.7268 -32.359346)
		(mid 74.858322 -33.021493)
		(end 75.233276 -33.582864)
		(width 0.14478)
		(layer "B.Cu")
		(net "CPU_TX_PCIE_MGT_1_RXN")
	)
	(arc
		(start 64.6684 -17.685766)
		(mid 64.835899 -18.528694)
		(end 65.313306 -19.243294)
		(width 0.14478)
		(layer "B.Cu")
		(net "CPU_TX_PCIE_MGT_1_RXN")
	)
	(segment
		(start 65.4558 -11.1506)
		(end 64.9224 -10.6172)
		(width 0.14478)
		(layer "F.Cu")
		(net "CPU_TX_PCIE_MGT_0_RXP")
	)
	(segment
		(start 74.7522 -12.0142)
		(end 67.540632 -12.0142)
		(width 0.14478)
		(layer "F.Cu")
		(net "CPU_TX_PCIE_MGT_0_RXP")
	)
	(segment
		(start 63.634366 -10.0838)
		(end 63.084964 -10.0838)
		(width 0.14478)
		(layer "F.Cu")
		(net "CPU_TX_PCIE_MGT_0_RXP")
	)
	(segment
		(start 60.649866 -5.51307)
		(end 60.649866 -3.500374)
		(width 0.14478)
		(layer "F.Cu")
		(net "CPU_TX_PCIE_MGT_0_RXP")
	)
	(segment
		(start 60.816998 -5.862828)
		(end 60.779152 -5.824982)
		(width 0.14478)
		(layer "F.Cu")
		(net "CPU_TX_PCIE_MGT_0_RXP")
	)
	(segment
		(start 75.14209 -12.2174)
		(end 75.070716 -12.14628)
		(width 0.14478)
		(layer "F.Cu")
		(net "CPU_TX_PCIE_MGT_0_RXP")
	)
	(segment
		(start 60.96 -7.963154)
		(end 60.96 -6.208014)
		(width 0.14478)
		(layer "F.Cu")
		(net "CPU_TX_PCIE_MGT_0_RXP")
	)
	(segment
		(start 62.223142 -9.72693)
		(end 61.313822 -8.81761)
		(width 0.14478)
		(layer "F.Cu")
		(net "CPU_TX_PCIE_MGT_0_RXP")
	)
	(segment
		(start 99.846892 -40.823134)
		(end 99.34702 -40.323262)
		(width 0.09906)
		(layer "F.Cu")
		(net "CPU_TX_PCIE_MGT_0_RXP")
	)
	(via
		(at 75.14209 -12.2174)
		(size 0.4572)
		(drill 0.2032)
		(layers "F.Cu" "B.Cu")
		(net "CPU_TX_PCIE_MGT_0_RXP")
	)
	(via
		(at 99.34702 -40.323262)
		(size 0.4572)
		(drill 0.2032)
		(layers "F.Cu" "B.Cu")
		(net "CPU_TX_PCIE_MGT_0_RXP")
	)
	(arc
		(start 64.9224 -10.6172)
		(mid 64.331444 -10.222366)
		(end 63.634366 -10.0838)
		(width 0.14478)
		(layer "F.Cu")
		(net "CPU_TX_PCIE_MGT_0_RXP")
	)
	(arc
		(start 63.084964 -10.0838)
		(mid 62.618537 -9.991116)
		(end 62.223142 -9.72693)
		(width 0.14478)
		(layer "F.Cu")
		(net "CPU_TX_PCIE_MGT_0_RXP")
	)
	(arc
		(start 61.313822 -8.81761)
		(mid 61.05196 -8.425567)
		(end 60.96 -7.963154)
		(width 0.14478)
		(layer "F.Cu")
		(net "CPU_TX_PCIE_MGT_0_RXP")
	)
	(arc
		(start 60.779152 -5.824982)
		(mid 60.683478 -5.68189)
		(end 60.649866 -5.51307)
		(width 0.14478)
		(layer "F.Cu")
		(net "CPU_TX_PCIE_MGT_0_RXP")
	)
	(arc
		(start 67.540632 -12.0142)
		(mid 66.412355 -11.789696)
		(end 65.4558 -11.1506)
		(width 0.14478)
		(layer "F.Cu")
		(net "CPU_TX_PCIE_MGT_0_RXP")
	)
	(arc
		(start 60.96 -6.208014)
		(mid 60.922839 -6.021193)
		(end 60.816998 -5.862828)
		(width 0.14478)
		(layer "F.Cu")
		(net "CPU_TX_PCIE_MGT_0_RXP")
	)
	(arc
		(start 75.070716 -12.14628)
		(mid 74.924595 -12.048552)
		(end 74.7522 -12.0142)
		(width 0.14478)
		(layer "F.Cu")
		(net "CPU_TX_PCIE_MGT_0_RXP")
	)
	(segment
		(start 74.740262 -18.276062)
		(end 74.904092 -18.439892)
		(width 0.14478)
		(layer "B.Cu")
		(net "CPU_TX_PCIE_MGT_0_RXP")
	)
	(segment
		(start 97.559622 -39.37889)
		(end 97.559622 -39.482776)
		(width 0.09144)
		(layer "B.Cu")
		(net "CPU_TX_PCIE_MGT_0_RXP")
	)
	(segment
		(start 96.671892 -38.49116)
		(end 97.54362 -39.362888)
		(width 0.14478)
		(layer "B.Cu")
		(net "CPU_TX_PCIE_MGT_0_RXP")
	)
	(segment
		(start 99.133152 -40.323262)
		(end 99.34702 -40.323262)
		(width 0.09144)
		(layer "B.Cu")
		(net "CPU_TX_PCIE_MGT_0_RXP")
	)
	(segment
		(start 98.937318 -40.112696)
		(end 98.937318 -40.127428)
		(width 0.09144)
		(layer "B.Cu")
		(net "CPU_TX_PCIE_MGT_0_RXP")
	)
	(segment
		(start 74.6252 -12.15898)
		(end 74.6252 -17.9578)
		(width 0.14478)
		(layer "B.Cu")
		(net "CPU_TX_PCIE_MGT_0_RXP")
	)
	(segment
		(start 76.03871 -21.375878)
		(end 76.039218 -21.37537)
		(width 0.14478)
		(layer "B.Cu")
		(net "CPU_TX_PCIE_MGT_0_RXP")
	)
	(segment
		(start 97.586292 -39.547292)
		(end 97.652586 -39.613586)
		(width 0.09144)
		(layer "B.Cu")
		(net "CPU_TX_PCIE_MGT_0_RXP")
	)
	(segment
		(start 80.2894 -26.736548)
		(end 80.2894 -30.812232)
		(width 0.14478)
		(layer "B.Cu")
		(net "CPU_TX_PCIE_MGT_0_RXP")
	)
	(segment
		(start 76.14285 -21.37537)
		(end 76.44892 -21.68144)
		(width 0.14478)
		(layer "B.Cu")
		(net "CPU_TX_PCIE_MGT_0_RXP")
	)
	(segment
		(start 97.9678 -39.744142)
		(end 98.568764 -39.744142)
		(width 0.09144)
		(layer "B.Cu")
		(net "CPU_TX_PCIE_MGT_0_RXP")
	)
	(segment
		(start 75.14209 -12.2174)
		(end 75.05827 -12.13358)
		(width 0.14478)
		(layer "B.Cu")
		(net "CPU_TX_PCIE_MGT_0_RXP")
	)
	(segment
		(start 75.2094 -19.177254)
		(end 75.2094 -20.066)
		(width 0.14478)
		(layer "B.Cu")
		(net "CPU_TX_PCIE_MGT_0_RXP")
	)
	(segment
		(start 87.376 -37.9222)
		(end 95.298514 -37.9222)
		(width 0.14478)
		(layer "B.Cu")
		(net "CPU_TX_PCIE_MGT_0_RXP")
	)
	(segment
		(start 80.6831 -31.7627)
		(end 86.46541 -37.54501)
		(width 0.14478)
		(layer "B.Cu")
		(net "CPU_TX_PCIE_MGT_0_RXP")
	)
	(segment
		(start 76.448412 -21.889212)
		(end 79.5782 -25.019)
		(width 0.14478)
		(layer "B.Cu")
		(net "CPU_TX_PCIE_MGT_0_RXP")
	)
	(segment
		(start 76.44892 -21.785072)
		(end 76.448412 -21.78558)
		(width 0.14478)
		(layer "B.Cu")
		(net "CPU_TX_PCIE_MGT_0_RXP")
	)
	(segment
		(start 97.54362 -39.362888)
		(end 97.559622 -39.37889)
		(width 0.09144)
		(layer "B.Cu")
		(net "CPU_TX_PCIE_MGT_0_RXP")
	)
	(segment
		(start 75.622404 -21.063204)
		(end 75.935078 -21.375878)
		(width 0.14478)
		(layer "B.Cu")
		(net "CPU_TX_PCIE_MGT_0_RXP")
	)
	(arc
		(start 76.44892 -21.68144)
		(mid 76.470309 -21.733256)
		(end 76.44892 -21.785072)
		(width 0.14478)
		(layer "B.Cu")
		(net "CPU_TX_PCIE_MGT_0_RXP")
	)
	(arc
		(start 97.652586 -39.613586)
		(mid 97.797207 -39.710219)
		(end 97.9678 -39.744142)
		(width 0.09144)
		(layer "B.Cu")
		(net "CPU_TX_PCIE_MGT_0_RXP")
	)
	(arc
		(start 79.5782 -25.019)
		(mid 80.104624 -25.807034)
		(end 80.2894 -26.736548)
		(width 0.14478)
		(layer "B.Cu")
		(net "CPU_TX_PCIE_MGT_0_RXP")
	)
	(arc
		(start 74.76998 -12.0142)
		(mid 74.667605 -12.056605)
		(end 74.6252 -12.15898)
		(width 0.14478)
		(layer "B.Cu")
		(net "CPU_TX_PCIE_MGT_0_RXP")
	)
	(arc
		(start 75.935078 -21.375878)
		(mid 75.986894 -21.397267)
		(end 76.03871 -21.375878)
		(width 0.14478)
		(layer "B.Cu")
		(net "CPU_TX_PCIE_MGT_0_RXP")
	)
	(arc
		(start 95.298514 -37.9222)
		(mid 96.0418 -38.070067)
		(end 96.671892 -38.49116)
		(width 0.14478)
		(layer "B.Cu")
		(net "CPU_TX_PCIE_MGT_0_RXP")
	)
	(arc
		(start 76.039218 -21.37537)
		(mid 76.091034 -21.353981)
		(end 76.14285 -21.37537)
		(width 0.14478)
		(layer "B.Cu")
		(net "CPU_TX_PCIE_MGT_0_RXP")
	)
	(arc
		(start 74.904092 -18.439892)
		(mid 75.130135 -18.778184)
		(end 75.2094 -19.177254)
		(width 0.14478)
		(layer "B.Cu")
		(net "CPU_TX_PCIE_MGT_0_RXP")
	)
	(arc
		(start 74.661522 -18.154396)
		(mid 74.694466 -18.219386)
		(end 74.740262 -18.276062)
		(width 0.14478)
		(layer "B.Cu")
		(net "CPU_TX_PCIE_MGT_0_RXP")
	)
	(arc
		(start 86.46541 -37.54501)
		(mid 86.883192 -37.824163)
		(end 87.376 -37.9222)
		(width 0.14478)
		(layer "B.Cu")
		(net "CPU_TX_PCIE_MGT_0_RXP")
	)
	(arc
		(start 97.559622 -39.482776)
		(mid 97.566548 -39.517686)
		(end 97.586292 -39.547292)
		(width 0.09144)
		(layer "B.Cu")
		(net "CPU_TX_PCIE_MGT_0_RXP")
	)
	(arc
		(start 80.2894 -30.812232)
		(mid 80.391719 -31.326623)
		(end 80.6831 -31.7627)
		(width 0.14478)
		(layer "B.Cu")
		(net "CPU_TX_PCIE_MGT_0_RXP")
	)
	(arc
		(start 75.05827 -12.13358)
		(mid 74.926001 -12.045201)
		(end 74.76998 -12.0142)
		(width 0.14478)
		(layer "B.Cu")
		(net "CPU_TX_PCIE_MGT_0_RXP")
	)
	(arc
		(start 75.2094 -20.066)
		(mid 75.316731 -20.605677)
		(end 75.622404 -21.063204)
		(width 0.14478)
		(layer "B.Cu")
		(net "CPU_TX_PCIE_MGT_0_RXP")
	)
	(arc
		(start 98.937318 -40.127428)
		(mid 98.994676 -40.265904)
		(end 99.133152 -40.323262)
		(width 0.09144)
		(layer "B.Cu")
		(net "CPU_TX_PCIE_MGT_0_RXP")
	)
	(arc
		(start 74.6252 -17.9578)
		(mid 74.634374 -18.05776)
		(end 74.661522 -18.154396)
		(width 0.14478)
		(layer "B.Cu")
		(net "CPU_TX_PCIE_MGT_0_RXP")
	)
	(arc
		(start 76.448412 -21.78558)
		(mid 76.427023 -21.837396)
		(end 76.448412 -21.889212)
		(width 0.14478)
		(layer "B.Cu")
		(net "CPU_TX_PCIE_MGT_0_RXP")
	)
	(arc
		(start 98.568764 -39.744142)
		(mid 98.829371 -39.852089)
		(end 98.937318 -40.112696)
		(width 0.09144)
		(layer "B.Cu")
		(net "CPU_TX_PCIE_MGT_0_RXP")
	)
	(segment
		(start 61.53912 -5.805932)
		(end 61.478668 -5.866384)
		(width 0.14478)
		(layer "F.Cu")
		(net "CPU_TX_PCIE_MGT_0_RXN")
	)
	(segment
		(start 67.540886 -11.6332)
		(end 74.7014 -11.6332)
		(width 0.14478)
		(layer "F.Cu")
		(net "CPU_TX_PCIE_MGT_0_RXN")
	)
	(segment
		(start 75.063604 -11.48334)
		(end 75.14209 -11.4046)
		(width 0.14478)
		(layer "F.Cu")
		(net "CPU_TX_PCIE_MGT_0_RXN")
	)
	(segment
		(start 61.649864 -3.500374)
		(end 61.649864 -5.538724)
		(width 0.14478)
		(layer "F.Cu")
		(net "CPU_TX_PCIE_MGT_0_RXN")
	)
	(segment
		(start 61.341 -6.19887)
		(end 61.341 -7.963154)
		(width 0.14478)
		(layer "F.Cu")
		(net "CPU_TX_PCIE_MGT_0_RXN")
	)
	(segment
		(start 65.191894 -10.347706)
		(end 65.725294 -10.881106)
		(width 0.14478)
		(layer "F.Cu")
		(net "CPU_TX_PCIE_MGT_0_RXN")
	)
	(segment
		(start 61.583316 -8.548116)
		(end 62.492636 -9.457436)
		(width 0.14478)
		(layer "F.Cu")
		(net "CPU_TX_PCIE_MGT_0_RXN")
	)
	(segment
		(start 98.846894 -40.823134)
		(end 98.347022 -40.323262)
		(width 0.09906)
		(layer "F.Cu")
		(net "CPU_TX_PCIE_MGT_0_RXN")
	)
	(segment
		(start 63.084964 -9.7028)
		(end 63.634366 -9.7028)
		(width 0.14478)
		(layer "F.Cu")
		(net "CPU_TX_PCIE_MGT_0_RXN")
	)
	(via
		(at 98.347022 -40.323262)
		(size 0.4572)
		(drill 0.2032)
		(layers "F.Cu" "B.Cu")
		(net "CPU_TX_PCIE_MGT_0_RXN")
	)
	(via
		(at 75.14209 -11.4046)
		(size 0.4572)
		(drill 0.2032)
		(layers "F.Cu" "B.Cu")
		(net "CPU_TX_PCIE_MGT_0_RXN")
	)
	(arc
		(start 62.492636 -9.457436)
		(mid 62.764398 -9.639022)
		(end 63.084964 -9.7028)
		(width 0.14478)
		(layer "F.Cu")
		(net "CPU_TX_PCIE_MGT_0_RXN")
	)
	(arc
		(start 61.478668 -5.866384)
		(mid 61.376794 -6.018944)
		(end 61.341 -6.19887)
		(width 0.14478)
		(layer "F.Cu")
		(net "CPU_TX_PCIE_MGT_0_RXN")
	)
	(arc
		(start 65.725294 -10.881106)
		(mid 66.558295 -11.437699)
		(end 67.540886 -11.6332)
		(width 0.14478)
		(layer "F.Cu")
		(net "CPU_TX_PCIE_MGT_0_RXN")
	)
	(arc
		(start 63.634366 -9.7028)
		(mid 64.477294 -9.870299)
		(end 65.191894 -10.347706)
		(width 0.14478)
		(layer "F.Cu")
		(net "CPU_TX_PCIE_MGT_0_RXN")
	)
	(arc
		(start 61.649864 -5.538724)
		(mid 61.621079 -5.683346)
		(end 61.53912 -5.805932)
		(width 0.14478)
		(layer "F.Cu")
		(net "CPU_TX_PCIE_MGT_0_RXN")
	)
	(arc
		(start 74.7014 -11.6332)
		(mid 74.897412 -11.594304)
		(end 75.063604 -11.48334)
		(width 0.14478)
		(layer "F.Cu")
		(net "CPU_TX_PCIE_MGT_0_RXN")
	)
	(arc
		(start 61.341 -7.963154)
		(mid 61.403973 -8.27974)
		(end 61.583316 -8.548116)
		(width 0.14478)
		(layer "F.Cu")
		(net "CPU_TX_PCIE_MGT_0_RXN")
	)
	(segment
		(start 97.290128 -39.648384)
		(end 97.394014 -39.648384)
		(width 0.09144)
		(layer "B.Cu")
		(net "CPU_TX_PCIE_MGT_0_RXN")
	)
	(segment
		(start 79.9084 -26.736294)
		(end 79.9084 -30.812486)
		(width 0.14478)
		(layer "B.Cu")
		(net "CPU_TX_PCIE_MGT_0_RXN")
	)
	(segment
		(start 87.375746 -38.3032)
		(end 95.298514 -38.3032)
		(width 0.14478)
		(layer "B.Cu")
		(net "CPU_TX_PCIE_MGT_0_RXN")
	)
	(segment
		(start 74.2442 -12.15898)
		(end 74.2442 -17.958054)
		(width 0.14478)
		(layer "B.Cu")
		(net "CPU_TX_PCIE_MGT_0_RXN")
	)
	(segment
		(start 80.413606 -32.032194)
		(end 86.195916 -37.814504)
		(width 0.14478)
		(layer "B.Cu")
		(net "CPU_TX_PCIE_MGT_0_RXN")
	)
	(segment
		(start 96.402398 -38.760654)
		(end 97.274126 -39.632382)
		(width 0.14478)
		(layer "B.Cu")
		(net "CPU_TX_PCIE_MGT_0_RXN")
	)
	(segment
		(start 97.274126 -39.632382)
		(end 97.290128 -39.648384)
		(width 0.09144)
		(layer "B.Cu")
		(net "CPU_TX_PCIE_MGT_0_RXN")
	)
	(segment
		(start 97.9678 -39.924482)
		(end 98.568764 -39.924482)
		(width 0.09144)
		(layer "B.Cu")
		(net "CPU_TX_PCIE_MGT_0_RXN")
	)
	(segment
		(start 74.470768 -18.545556)
		(end 74.634598 -18.709386)
		(width 0.14478)
		(layer "B.Cu")
		(net "CPU_TX_PCIE_MGT_0_RXN")
	)
	(segment
		(start 74.8284 -19.177)
		(end 74.8284 -20.066254)
		(width 0.14478)
		(layer "B.Cu")
		(net "CPU_TX_PCIE_MGT_0_RXN")
	)
	(segment
		(start 75.14209 -11.4046)
		(end 75.014836 -11.5316)
		(width 0.14478)
		(layer "B.Cu")
		(net "CPU_TX_PCIE_MGT_0_RXN")
	)
	(segment
		(start 75.35291 -21.332698)
		(end 79.308706 -25.288494)
		(width 0.14478)
		(layer "B.Cu")
		(net "CPU_TX_PCIE_MGT_0_RXN")
	)
	(segment
		(start 98.756978 -40.112696)
		(end 98.756978 -40.133016)
		(width 0.09144)
		(layer "B.Cu")
		(net "CPU_TX_PCIE_MGT_0_RXN")
	)
	(segment
		(start 97.45853 -39.675054)
		(end 97.524824 -39.741348)
		(width 0.09144)
		(layer "B.Cu")
		(net "CPU_TX_PCIE_MGT_0_RXN")
	)
	(segment
		(start 98.566732 -40.323262)
		(end 98.347022 -40.323262)
		(width 0.09144)
		(layer "B.Cu")
		(net "CPU_TX_PCIE_MGT_0_RXN")
	)
	(arc
		(start 79.9084 -30.812486)
		(mid 80.039686 -31.472596)
		(end 80.413606 -32.032194)
		(width 0.14478)
		(layer "B.Cu")
		(net "CPU_TX_PCIE_MGT_0_RXN")
	)
	(arc
		(start 74.305414 -18.290032)
		(mid 74.374572 -18.426543)
		(end 74.470768 -18.545556)
		(width 0.14478)
		(layer "B.Cu")
		(net "CPU_TX_PCIE_MGT_0_RXN")
	)
	(arc
		(start 75.014836 -11.5316)
		(mid 74.90251 -11.606747)
		(end 74.76998 -11.6332)
		(width 0.14478)
		(layer "B.Cu")
		(net "CPU_TX_PCIE_MGT_0_RXN")
	)
	(arc
		(start 95.298514 -38.3032)
		(mid 95.895944 -38.422148)
		(end 96.402398 -38.760654)
		(width 0.14478)
		(layer "B.Cu")
		(net "CPU_TX_PCIE_MGT_0_RXN")
	)
	(arc
		(start 86.195916 -37.814504)
		(mid 86.737241 -38.176142)
		(end 87.375746 -38.3032)
		(width 0.14478)
		(layer "B.Cu")
		(net "CPU_TX_PCIE_MGT_0_RXN")
	)
	(arc
		(start 74.634598 -18.709386)
		(mid 74.778059 -18.923901)
		(end 74.8284 -19.177)
		(width 0.14478)
		(layer "B.Cu")
		(net "CPU_TX_PCIE_MGT_0_RXN")
	)
	(arc
		(start 74.2442 -17.958054)
		(mid 74.259687 -18.126829)
		(end 74.305414 -18.290032)
		(width 0.14478)
		(layer "B.Cu")
		(net "CPU_TX_PCIE_MGT_0_RXN")
	)
	(arc
		(start 97.394014 -39.648384)
		(mid 97.428924 -39.65531)
		(end 97.45853 -39.675054)
		(width 0.09144)
		(layer "B.Cu")
		(net "CPU_TX_PCIE_MGT_0_RXN")
	)
	(arc
		(start 98.756978 -40.133016)
		(mid 98.701256 -40.26754)
		(end 98.566732 -40.323262)
		(width 0.09144)
		(layer "B.Cu")
		(net "CPU_TX_PCIE_MGT_0_RXN")
	)
	(arc
		(start 97.524824 -39.741348)
		(mid 97.728107 -39.876928)
		(end 97.9678 -39.924482)
		(width 0.09144)
		(layer "B.Cu")
		(net "CPU_TX_PCIE_MGT_0_RXN")
	)
	(arc
		(start 79.308706 -25.288494)
		(mid 79.752548 -25.95275)
		(end 79.9084 -26.736294)
		(width 0.14478)
		(layer "B.Cu")
		(net "CPU_TX_PCIE_MGT_0_RXN")
	)
	(arc
		(start 74.76998 -11.6332)
		(mid 74.398197 -11.787197)
		(end 74.2442 -12.15898)
		(width 0.14478)
		(layer "B.Cu")
		(net "CPU_TX_PCIE_MGT_0_RXN")
	)
	(arc
		(start 74.8284 -20.066254)
		(mid 74.964781 -20.751597)
		(end 75.35291 -21.332698)
		(width 0.14478)
		(layer "B.Cu")
		(net "CPU_TX_PCIE_MGT_0_RXN")
	)
	(arc
		(start 98.568764 -39.924482)
		(mid 98.701851 -39.979609)
		(end 98.756978 -40.112696)
		(width 0.09144)
		(layer "B.Cu")
		(net "CPU_TX_PCIE_MGT_0_RXN")
	)
	(segment
		(start 101.847142 -39.823136)
		(end 101.34727 -39.323264)
		(width 0.09906)
		(layer "F.Cu")
		(net "CPU_RX_PCIE_MGT3_TXP")
	)
	(segment
		(start 79.159354 -21.704808)
		(end 79.121 -21.6662)
		(width 0.14478)
		(layer "B.Cu")
		(net "CPU_RX_PCIE_MGT3_TXP")
	)
	(segment
		(start 75.959462 -17.930368)
		(end 75.959462 -16.97355)
		(width 0.14478)
		(layer "B.Cu")
		(net "CPU_RX_PCIE_MGT3_TXP")
	)
	(segment
		(start 79.121 -21.6662)
		(end 76.3651 -18.9103)
		(width 0.14478)
		(layer "B.Cu")
		(net "CPU_RX_PCIE_MGT3_TXP")
	)
	(arc
		(start 79.375 -22.225)
		(mid 79.318905 -21.943461)
		(end 79.159354 -21.704808)
		(width 0.14478)
		(layer "B.Cu")
		(net "CPU_RX_PCIE_MGT3_TXP")
	)
	(arc
		(start 75.959462 -16.97355)
		(mid 75.843938 -16.39277)
		(end 75.514962 -15.9004)
		(width 0.14478)
		(layer "B.Cu")
		(net "CPU_RX_PCIE_MGT3_TXP")
	)
	(arc
		(start 76.3651 -18.9103)
		(mid 76.064801 -18.460688)
		(end 75.959462 -17.930368)
		(width 0.14478)
		(layer "B.Cu")
		(net "CPU_RX_PCIE_MGT3_TXP")
	)
	(segment
		(start 80.015588 -22.523958)
		(end 79.901288 -22.409658)
		(width 0.15748)
		(layer "In7.Cu")
		(net "CPU_RX_PCIE_MGT3_TXP")
	)
	(segment
		(start 84.80044 -39.933626)
		(end 80.561434 -35.694874)
		(width 0.15748)
		(layer "In7.Cu")
		(net "CPU_RX_PCIE_MGT3_TXP")
	)
	(segment
		(start 79.455518 -22.225)
		(end 79.375 -22.225)
		(width 0.15748)
		(layer "In7.Cu")
		(net "CPU_RX_PCIE_MGT3_TXP")
	)
	(segment
		(start 100.942394 -39.437564)
		(end 100.942394 -39.599362)
		(width 0.1143)
		(layer "In7.Cu")
		(net "CPU_RX_PCIE_MGT3_TXP")
	)
	(segment
		(start 100.007928 -39.90594)
		(end 99.891596 -39.924736)
		(width 0.1143)
		(layer "In7.Cu")
		(net "CPU_RX_PCIE_MGT3_TXP")
	)
	(segment
		(start 100.637594 -39.904162)
		(end 100.031296 -39.904162)
		(width 0.1143)
		(layer "In7.Cu")
		(net "CPU_RX_PCIE_MGT3_TXP")
	)
	(segment
		(start 99.777804 -39.93388)
		(end 98.105468 -39.93388)
		(width 0.1143)
		(layer "In7.Cu")
		(net "CPU_RX_PCIE_MGT3_TXP")
	)
	(segment
		(start 96.476312 -40.3606)
		(end 86.172802 -40.3606)
		(width 0.15748)
		(layer "In7.Cu")
		(net "CPU_RX_PCIE_MGT3_TXP")
	)
	(segment
		(start 97.333562 -40.29075)
		(end 96.712786 -40.29075)
		(width 0.1143)
		(layer "In7.Cu")
		(net "CPU_RX_PCIE_MGT3_TXP")
	)
	(segment
		(start 80.15478 -34.386774)
		(end 80.15478 -22.840442)
		(width 0.15748)
		(layer "In7.Cu")
		(net "CPU_RX_PCIE_MGT3_TXP")
	)
	(segment
		(start 97.6884 -40.1066)
		(end 97.6249 -40.1701)
		(width 0.1143)
		(layer "In7.Cu")
		(net "CPU_RX_PCIE_MGT3_TXP")
	)
	(segment
		(start 101.34727 -39.323264)
		(end 101.056694 -39.323264)
		(width 0.1143)
		(layer "In7.Cu")
		(net "CPU_RX_PCIE_MGT3_TXP")
	)
	(arc
		(start 96.601788 -40.314372)
		(mid 96.581806 -40.324126)
		(end 96.562672 -40.335454)
		(width 0.1143)
		(layer "In7.Cu")
		(net "CPU_RX_PCIE_MGT3_TXP")
	)
	(arc
		(start 80.15478 -22.840442)
		(mid 80.147076 -22.761575)
		(end 80.124046 -22.685756)
		(width 0.15748)
		(layer "In7.Cu")
		(net "CPU_RX_PCIE_MGT3_TXP")
	)
	(arc
		(start 101.056694 -39.323264)
		(mid 100.975872 -39.356742)
		(end 100.942394 -39.437564)
		(width 0.1143)
		(layer "In7.Cu")
		(net "CPU_RX_PCIE_MGT3_TXP")
	)
	(arc
		(start 85.014308 -40.087804)
		(mid 84.901141 -40.019361)
		(end 84.80044 -39.933626)
		(width 0.15748)
		(layer "In7.Cu")
		(net "CPU_RX_PCIE_MGT3_TXP")
	)
	(arc
		(start 98.105468 -39.93388)
		(mid 97.879766 -39.978775)
		(end 97.6884 -40.1066)
		(width 0.1143)
		(layer "In7.Cu")
		(net "CPU_RX_PCIE_MGT3_TXP")
	)
	(arc
		(start 97.6249 -40.1701)
		(mid 97.491233 -40.259413)
		(end 97.333562 -40.29075)
		(width 0.1143)
		(layer "In7.Cu")
		(net "CPU_RX_PCIE_MGT3_TXP")
	)
	(arc
		(start 99.891596 -39.924736)
		(mid 99.834883 -39.931592)
		(end 99.777804 -39.93388)
		(width 0.1143)
		(layer "In7.Cu")
		(net "CPU_RX_PCIE_MGT3_TXP")
	)
	(arc
		(start 86.172802 -40.3606)
		(mid 85.577693 -40.29155)
		(end 85.014308 -40.087804)
		(width 0.15748)
		(layer "In7.Cu")
		(net "CPU_RX_PCIE_MGT3_TXP")
	)
	(arc
		(start 100.031296 -39.904162)
		(mid 100.01958 -39.90463)
		(end 100.007928 -39.90594)
		(width 0.1143)
		(layer "In7.Cu")
		(net "CPU_RX_PCIE_MGT3_TXP")
	)
	(arc
		(start 80.124046 -22.685756)
		(mid 80.077756 -22.599535)
		(end 80.015588 -22.523958)
		(width 0.15748)
		(layer "In7.Cu")
		(net "CPU_RX_PCIE_MGT3_TXP")
	)
	(arc
		(start 80.561434 -35.694874)
		(mid 80.474919 -35.592608)
		(end 80.406494 -35.47745)
		(width 0.15748)
		(layer "In7.Cu")
		(net "CPU_RX_PCIE_MGT3_TXP")
	)
	(arc
		(start 96.562672 -40.335454)
		(mid 96.521324 -40.354316)
		(end 96.476312 -40.3606)
		(width 0.1143)
		(layer "In7.Cu")
		(net "CPU_RX_PCIE_MGT3_TXP")
	)
	(arc
		(start 79.901288 -22.409658)
		(mid 79.696767 -22.273001)
		(end 79.455518 -22.225)
		(width 0.15748)
		(layer "In7.Cu")
		(net "CPU_RX_PCIE_MGT3_TXP")
	)
	(arc
		(start 96.712786 -40.29075)
		(mid 96.656061 -40.2968)
		(end 96.601788 -40.314372)
		(width 0.1143)
		(layer "In7.Cu")
		(net "CPU_RX_PCIE_MGT3_TXP")
	)
	(arc
		(start 80.406494 -35.47745)
		(mid 80.218519 -34.946445)
		(end 80.15478 -34.386774)
		(width 0.15748)
		(layer "In7.Cu")
		(net "CPU_RX_PCIE_MGT3_TXP")
	)
	(arc
		(start 100.942394 -39.599362)
		(mid 100.85312 -39.814888)
		(end 100.637594 -39.904162)
		(width 0.1143)
		(layer "In7.Cu")
		(net "CPU_RX_PCIE_MGT3_TXP")
	)
	(segment
		(start 100.84689 -39.823136)
		(end 100.347018 -39.323264)
		(width 0.09906)
		(layer "F.Cu")
		(net "CPU_RX_PCIE_MGT3_TXN")
	)
	(segment
		(start 79.427578 -21.434044)
		(end 79.415894 -21.422106)
		(width 0.14478)
		(layer "B.Cu")
		(net "CPU_RX_PCIE_MGT3_TXN")
	)
	(segment
		(start 76.340462 -17.930622)
		(end 76.340462 -16.97355)
		(width 0.14478)
		(layer "B.Cu")
		(net "CPU_RX_PCIE_MGT3_TXN")
	)
	(segment
		(start 79.415894 -21.422106)
		(end 76.634594 -18.640806)
		(width 0.14478)
		(layer "B.Cu")
		(net "CPU_RX_PCIE_MGT3_TXN")
	)
	(arc
		(start 79.949802 -21.650198)
		(mid 79.667183 -21.594075)
		(end 79.427578 -21.434044)
		(width 0.14478)
		(layer "B.Cu")
		(net "CPU_RX_PCIE_MGT3_TXN")
	)
	(arc
		(start 76.634594 -18.640806)
		(mid 76.416878 -18.314971)
		(end 76.340462 -17.930622)
		(width 0.14478)
		(layer "B.Cu")
		(net "CPU_RX_PCIE_MGT3_TXN")
	)
	(arc
		(start 76.340462 -16.97355)
		(mid 76.455986 -16.39277)
		(end 76.784962 -15.9004)
		(width 0.14478)
		(layer "B.Cu")
		(net "CPU_RX_PCIE_MGT3_TXN")
	)
	(segment
		(start 85.03412 -39.7002)
		(end 84.270342 -38.936422)
		(width 0.15748)
		(layer "In7.Cu")
		(net "CPU_RX_PCIE_MGT3_TXN")
	)
	(segment
		(start 99.974146 -39.718234)
		(end 99.861116 -39.736522)
		(width 0.1143)
		(layer "In7.Cu")
		(net "CPU_RX_PCIE_MGT3_TXN")
	)
	(segment
		(start 81.175352 -35.841432)
		(end 80.795114 -35.461194)
		(width 0.15748)
		(layer "In7.Cu")
		(net "CPU_RX_PCIE_MGT3_TXN")
	)
	(segment
		(start 100.637594 -39.713662)
		(end 100.031042 -39.713662)
		(width 0.1143)
		(layer "In7.Cu")
		(net "CPU_RX_PCIE_MGT3_TXN")
	)
	(segment
		(start 92.214954 -40.0304)
		(end 88.285066 -40.0304)
		(width 0.15748)
		(layer "In7.Cu")
		(net "CPU_RX_PCIE_MGT3_TXN")
	)
	(segment
		(start 83.70951 -38.37559)
		(end 81.737708 -36.403788)
		(width 0.15748)
		(layer "In7.Cu")
		(net "CPU_RX_PCIE_MGT3_TXN")
	)
	(segment
		(start 97.333816 -40.10025)
		(end 96.71304 -40.10025)
		(width 0.1143)
		(layer "In7.Cu")
		(net "CPU_RX_PCIE_MGT3_TXN")
	)
	(segment
		(start 79.949802 -21.765006)
		(end 79.949802 -21.650198)
		(width 0.15748)
		(layer "In7.Cu")
		(net "CPU_RX_PCIE_MGT3_TXN")
	)
	(segment
		(start 99.778058 -39.74338)
		(end 98.105468 -39.74338)
		(width 0.1143)
		(layer "In7.Cu")
		(net "CPU_RX_PCIE_MGT3_TXN")
	)
	(segment
		(start 87.490046 -40.0304)
		(end 86.172548 -40.0304)
		(width 0.15748)
		(layer "In7.Cu")
		(net "CPU_RX_PCIE_MGT3_TXN")
	)
	(segment
		(start 97.553526 -39.97198)
		(end 97.553272 -39.971726)
		(width 0.1143)
		(layer "In7.Cu")
		(net "CPU_RX_PCIE_MGT3_TXN")
	)
	(segment
		(start 96.476312 -40.0304)
		(end 93.009974 -40.0304)
		(width 0.15748)
		(layer "In7.Cu")
		(net "CPU_RX_PCIE_MGT3_TXN")
	)
	(segment
		(start 81.737708 -36.170108)
		(end 81.409032 -35.841432)
		(width 0.15748)
		(layer "In7.Cu")
		(net "CPU_RX_PCIE_MGT3_TXN")
	)
	(segment
		(start 80.48498 -34.38652)
		(end 80.48498 -22.840442)
		(width 0.15748)
		(layer "In7.Cu")
		(net "CPU_RX_PCIE_MGT3_TXN")
	)
	(segment
		(start 80.249268 -22.290532)
		(end 80.109568 -22.150832)
		(width 0.15748)
		(layer "In7.Cu")
		(net "CPU_RX_PCIE_MGT3_TXN")
	)
	(segment
		(start 84.270342 -38.70579)
		(end 83.940142 -38.37559)
		(width 0.15748)
		(layer "In7.Cu")
		(net "CPU_RX_PCIE_MGT3_TXN")
	)
	(segment
		(start 88.119966 -39.8653)
		(end 87.655146 -39.8653)
		(width 0.15748)
		(layer "In7.Cu")
		(net "CPU_RX_PCIE_MGT3_TXN")
	)
	(segment
		(start 100.751894 -39.437564)
		(end 100.751894 -39.599362)
		(width 0.1143)
		(layer "In7.Cu")
		(net "CPU_RX_PCIE_MGT3_TXN")
	)
	(segment
		(start 100.347018 -39.323264)
		(end 100.637594 -39.323264)
		(width 0.1143)
		(layer "In7.Cu")
		(net "CPU_RX_PCIE_MGT3_TXN")
	)
	(segment
		(start 97.490026 -40.035226)
		(end 97.490026 -40.03548)
		(width 0.1143)
		(layer "In7.Cu")
		(net "CPU_RX_PCIE_MGT3_TXN")
	)
	(segment
		(start 97.553272 -39.971726)
		(end 97.490026 -40.035226)
		(width 0.1143)
		(layer "In7.Cu")
		(net "CPU_RX_PCIE_MGT3_TXN")
	)
	(segment
		(start 92.844874 -39.8653)
		(end 92.380054 -39.8653)
		(width 0.15748)
		(layer "In7.Cu")
		(net "CPU_RX_PCIE_MGT3_TXN")
	)
	(arc
		(start 98.105468 -39.74338)
		(mid 97.806782 -39.80281)
		(end 97.553526 -39.97198)
		(width 0.1143)
		(layer "In7.Cu")
		(net "CPU_RX_PCIE_MGT3_TXN")
	)
	(arc
		(start 99.861116 -39.736522)
		(mid 99.819724 -39.74161)
		(end 99.778058 -39.74338)
		(width 0.1143)
		(layer "In7.Cu")
		(net "CPU_RX_PCIE_MGT3_TXN")
	)
	(arc
		(start 100.751894 -39.599362)
		(mid 100.718416 -39.680184)
		(end 100.637594 -39.713662)
		(width 0.1143)
		(layer "In7.Cu")
		(net "CPU_RX_PCIE_MGT3_TXN")
	)
	(arc
		(start 100.031042 -39.713662)
		(mid 100.002502 -39.714806)
		(end 99.974146 -39.718234)
		(width 0.1143)
		(layer "In7.Cu")
		(net "CPU_RX_PCIE_MGT3_TXN")
	)
	(arc
		(start 92.297504 -39.94785)
		(mid 92.273326 -40.006222)
		(end 92.214954 -40.0304)
		(width 0.15748)
		(layer "In7.Cu")
		(net "CPU_RX_PCIE_MGT3_TXN")
	)
	(arc
		(start 81.292192 -35.841432)
		(mid 81.233772 -35.86563)
		(end 81.175352 -35.841432)
		(width 0.15748)
		(layer "In7.Cu")
		(net "CPU_RX_PCIE_MGT3_TXN")
	)
	(arc
		(start 92.927424 -39.94785)
		(mid 92.903246 -39.889478)
		(end 92.844874 -39.8653)
		(width 0.15748)
		(layer "In7.Cu")
		(net "CPU_RX_PCIE_MGT3_TXN")
	)
	(arc
		(start 88.285066 -40.0304)
		(mid 88.226694 -40.006222)
		(end 88.202516 -39.94785)
		(width 0.15748)
		(layer "In7.Cu")
		(net "CPU_RX_PCIE_MGT3_TXN")
	)
	(arc
		(start 96.712532 -40.10025)
		(mid 96.616623 -40.11032)
		(end 96.524826 -40.139874)
		(width 0.1143)
		(layer "In7.Cu")
		(net "CPU_RX_PCIE_MGT3_TXN")
	)
	(arc
		(start 97.490026 -40.03548)
		(mid 97.418343 -40.083344)
		(end 97.333816 -40.10025)
		(width 0.1143)
		(layer "In7.Cu")
		(net "CPU_RX_PCIE_MGT3_TXN")
	)
	(arc
		(start 87.572596 -39.94785)
		(mid 87.548418 -40.006222)
		(end 87.490046 -40.0304)
		(width 0.15748)
		(layer "In7.Cu")
		(net "CPU_RX_PCIE_MGT3_TXN")
	)
	(arc
		(start 87.655146 -39.8653)
		(mid 87.596774 -39.889478)
		(end 87.572596 -39.94785)
		(width 0.15748)
		(layer "In7.Cu")
		(net "CPU_RX_PCIE_MGT3_TXN")
	)
	(arc
		(start 83.940142 -38.37559)
		(mid 83.882484 -38.351707)
		(end 83.824826 -38.37559)
		(width 0.15748)
		(layer "In7.Cu")
		(net "CPU_RX_PCIE_MGT3_TXN")
	)
	(arc
		(start 84.270342 -38.936422)
		(mid 84.246459 -38.878764)
		(end 84.270342 -38.821106)
		(width 0.15748)
		(layer "In7.Cu")
		(net "CPU_RX_PCIE_MGT3_TXN")
	)
	(arc
		(start 80.4291 -22.559264)
		(mid 80.352374 -22.416071)
		(end 80.249268 -22.290532)
		(width 0.15748)
		(layer "In7.Cu")
		(net "CPU_RX_PCIE_MGT3_TXN")
	)
	(arc
		(start 92.380054 -39.8653)
		(mid 92.321682 -39.889478)
		(end 92.297504 -39.94785)
		(width 0.15748)
		(layer "In7.Cu")
		(net "CPU_RX_PCIE_MGT3_TXN")
	)
	(arc
		(start 81.737708 -36.286948)
		(mid 81.761906 -36.228528)
		(end 81.737708 -36.170108)
		(width 0.15748)
		(layer "In7.Cu")
		(net "CPU_RX_PCIE_MGT3_TXN")
	)
	(arc
		(start 80.795114 -35.461194)
		(mid 80.743922 -35.400746)
		(end 80.70342 -35.33267)
		(width 0.15748)
		(layer "In7.Cu")
		(net "CPU_RX_PCIE_MGT3_TXN")
	)
	(arc
		(start 93.009974 -40.0304)
		(mid 92.951602 -40.006222)
		(end 92.927424 -39.94785)
		(width 0.15748)
		(layer "In7.Cu")
		(net "CPU_RX_PCIE_MGT3_TXN")
	)
	(arc
		(start 85.161882 -39.792402)
		(mid 85.094269 -39.751471)
		(end 85.03412 -39.7002)
		(width 0.15748)
		(layer "In7.Cu")
		(net "CPU_RX_PCIE_MGT3_TXN")
	)
	(arc
		(start 81.737708 -36.403788)
		(mid 81.71351 -36.345368)
		(end 81.737708 -36.286948)
		(width 0.15748)
		(layer "In7.Cu")
		(net "CPU_RX_PCIE_MGT3_TXN")
	)
	(arc
		(start 84.270342 -38.821106)
		(mid 84.294225 -38.763448)
		(end 84.270342 -38.70579)
		(width 0.15748)
		(layer "In7.Cu")
		(net "CPU_RX_PCIE_MGT3_TXN")
	)
	(arc
		(start 86.172548 -40.0304)
		(mid 85.653379 -39.970141)
		(end 85.161882 -39.792402)
		(width 0.15748)
		(layer "In7.Cu")
		(net "CPU_RX_PCIE_MGT3_TXN")
	)
	(arc
		(start 88.202516 -39.94785)
		(mid 88.178338 -39.889478)
		(end 88.119966 -39.8653)
		(width 0.15748)
		(layer "In7.Cu")
		(net "CPU_RX_PCIE_MGT3_TXN")
	)
	(arc
		(start 96.524826 -40.139874)
		(mid 96.554961 -40.060991)
		(end 96.476312 -40.0304)
		(width 0.1143)
		(layer "In7.Cu")
		(net "CPU_RX_PCIE_MGT3_TXN")
	)
	(arc
		(start 80.48498 -22.840442)
		(mid 80.470919 -22.697096)
		(end 80.4291 -22.559264)
		(width 0.15748)
		(layer "In7.Cu")
		(net "CPU_RX_PCIE_MGT3_TXN")
	)
	(arc
		(start 81.409032 -35.841432)
		(mid 81.350612 -35.817234)
		(end 81.292192 -35.841432)
		(width 0.15748)
		(layer "In7.Cu")
		(net "CPU_RX_PCIE_MGT3_TXN")
	)
	(arc
		(start 80.109568 -22.150832)
		(mid 79.991288 -21.973814)
		(end 79.949802 -21.765006)
		(width 0.15748)
		(layer "In7.Cu")
		(net "CPU_RX_PCIE_MGT3_TXN")
	)
	(arc
		(start 83.824826 -38.37559)
		(mid 83.767168 -38.399473)
		(end 83.70951 -38.37559)
		(width 0.15748)
		(layer "In7.Cu")
		(net "CPU_RX_PCIE_MGT3_TXN")
	)
	(arc
		(start 96.71304 -40.10025)
		(mid 96.712786 -40.10025)
		(end 96.712532 -40.10025)
		(width 0.1143)
		(layer "In7.Cu")
		(net "CPU_RX_PCIE_MGT3_TXN")
	)
	(arc
		(start 80.70342 -35.33267)
		(mid 80.540317 -34.872034)
		(end 80.48498 -34.38652)
		(width 0.15748)
		(layer "In7.Cu")
		(net "CPU_RX_PCIE_MGT3_TXN")
	)
	(arc
		(start 100.637594 -39.323264)
		(mid 100.718416 -39.356742)
		(end 100.751894 -39.437564)
		(width 0.1143)
		(layer "In7.Cu")
		(net "CPU_RX_PCIE_MGT3_TXN")
	)
	(segment
		(start 99.846892 -38.823138)
		(end 99.34702 -38.323266)
		(width 0.09906)
		(layer "F.Cu")
		(net "CPU_RX_PCIE_MGT2_TXP")
	)
	(segment
		(start 71.57847 -16.97355)
		(end 71.57847 -17.879822)
		(width 0.14478)
		(layer "B.Cu")
		(net "CPU_RX_PCIE_MGT2_TXP")
	)
	(segment
		(start 71.80707 -18.431764)
		(end 71.80707 -18.858992)
		(width 0.14478)
		(layer "B.Cu")
		(net "CPU_RX_PCIE_MGT2_TXP")
	)
	(arc
		(start 71.57847 -17.879822)
		(mid 71.621113 -18.09382)
		(end 71.7423 -18.2753)
		(width 0.14478)
		(layer "B.Cu")
		(net "CPU_RX_PCIE_MGT2_TXP")
	)
	(arc
		(start 71.13397 -15.9004)
		(mid 71.462958 -16.392765)
		(end 71.57847 -16.97355)
		(width 0.14478)
		(layer "B.Cu")
		(net "CPU_RX_PCIE_MGT2_TXP")
	)
	(arc
		(start 71.80707 -18.858992)
		(mid 71.750961 -19.141071)
		(end 71.59117 -19.3802)
		(width 0.14478)
		(layer "B.Cu")
		(net "CPU_RX_PCIE_MGT2_TXP")
	)
	(arc
		(start 71.7423 -18.2753)
		(mid 71.790266 -18.347086)
		(end 71.80707 -18.431764)
		(width 0.14478)
		(layer "B.Cu")
		(net "CPU_RX_PCIE_MGT2_TXP")
	)
	(segment
		(start 96.782382 -38.819582)
		(end 96.5581 -38.5953)
		(width 0.15748)
		(layer "In7.Cu")
		(net "CPU_RX_PCIE_MGT2_TXP")
	)
	(segment
		(start 96.098106 -38.4048)
		(end 86.68131 -38.4048)
		(width 0.15748)
		(layer "In7.Cu")
		(net "CPU_RX_PCIE_MGT2_TXP")
	)
	(segment
		(start 82.257646 -34.861246)
		(end 82.257646 -34.8615)
		(width 0.15748)
		(layer "In7.Cu")
		(net "CPU_RX_PCIE_MGT2_TXP")
	)
	(segment
		(start 97.55505 -38.93566)
		(end 97.4852 -39.00551)
		(width 0.1143)
		(layer "In7.Cu")
		(net "CPU_RX_PCIE_MGT2_TXP")
	)
	(segment
		(start 99.34702 -38.323266)
		(end 99.056698 -38.323266)
		(width 0.1143)
		(layer "In7.Cu")
		(net "CPU_RX_PCIE_MGT2_TXP")
	)
	(segment
		(start 82.192114 -34.795968)
		(end 82.192114 -34.795714)
		(width 0.15748)
		(layer "In7.Cu")
		(net "CPU_RX_PCIE_MGT2_TXP")
	)
	(segment
		(start 98.942398 -38.437566)
		(end 98.942398 -38.599364)
		(width 0.1143)
		(layer "In7.Cu")
		(net "CPU_RX_PCIE_MGT2_TXP")
	)
	(segment
		(start 82.257646 -34.8615)
		(end 82.192114 -34.795968)
		(width 0.15748)
		(layer "In7.Cu")
		(net "CPU_RX_PCIE_MGT2_TXP")
	)
	(segment
		(start 81.191608 -20.5486)
		(end 72.46747 -20.5486)
		(width 0.15748)
		(layer "In7.Cu")
		(net "CPU_RX_PCIE_MGT2_TXP")
	)
	(segment
		(start 85.1789 -37.7825)
		(end 82.257646 -34.861246)
		(width 0.15748)
		(layer "In7.Cu")
		(net "CPU_RX_PCIE_MGT2_TXP")
	)
	(segment
		(start 97.456752 -39.00551)
		(end 97.2312 -39.00551)
		(width 0.15748)
		(layer "In7.Cu")
		(net "CPU_RX_PCIE_MGT2_TXP")
	)
	(segment
		(start 71.83247 -19.9136)
		(end 71.83247 -19.6215)
		(width 0.15748)
		(layer "In7.Cu")
		(net "CPU_RX_PCIE_MGT2_TXP")
	)
	(segment
		(start 98.606102 -38.93566)
		(end 97.55505 -38.93566)
		(width 0.1143)
		(layer "In7.Cu")
		(net "CPU_RX_PCIE_MGT2_TXP")
	)
	(segment
		(start 71.83247 -19.6215)
		(end 71.59117 -19.3802)
		(width 0.15748)
		(layer "In7.Cu")
		(net "CPU_RX_PCIE_MGT2_TXP")
	)
	(segment
		(start 81.6356 -33.452054)
		(end 81.6356 -20.992592)
		(width 0.15748)
		(layer "In7.Cu")
		(net "CPU_RX_PCIE_MGT2_TXP")
	)
	(segment
		(start 97.4852 -39.00551)
		(end 97.456752 -39.00551)
		(width 0.1143)
		(layer "In7.Cu")
		(net "CPU_RX_PCIE_MGT2_TXP")
	)
	(arc
		(start 96.5581 -38.5953)
		(mid 96.347053 -38.454283)
		(end 96.098106 -38.4048)
		(width 0.15748)
		(layer "In7.Cu")
		(net "CPU_RX_PCIE_MGT2_TXP")
	)
	(arc
		(start 82.192114 -34.795714)
		(mid 81.780222 -34.179224)
		(end 81.6356 -33.452054)
		(width 0.15748)
		(layer "In7.Cu")
		(net "CPU_RX_PCIE_MGT2_TXP")
	)
	(arc
		(start 97.2312 -39.00551)
		(mid 96.988293 -38.957193)
		(end 96.782382 -38.819582)
		(width 0.15748)
		(layer "In7.Cu")
		(net "CPU_RX_PCIE_MGT2_TXP")
	)
	(arc
		(start 86.68131 -38.4048)
		(mid 85.868244 -38.243013)
		(end 85.1789 -37.7825)
		(width 0.15748)
		(layer "In7.Cu")
		(net "CPU_RX_PCIE_MGT2_TXP")
	)
	(arc
		(start 99.056698 -38.323266)
		(mid 98.975876 -38.356744)
		(end 98.942398 -38.437566)
		(width 0.1143)
		(layer "In7.Cu")
		(net "CPU_RX_PCIE_MGT2_TXP")
	)
	(arc
		(start 98.942398 -38.599364)
		(mid 98.843899 -38.837161)
		(end 98.606102 -38.93566)
		(width 0.1143)
		(layer "In7.Cu")
		(net "CPU_RX_PCIE_MGT2_TXP")
	)
	(arc
		(start 81.6356 -20.992592)
		(mid 81.505558 -20.678642)
		(end 81.191608 -20.5486)
		(width 0.15748)
		(layer "In7.Cu")
		(net "CPU_RX_PCIE_MGT2_TXP")
	)
	(arc
		(start 72.46747 -20.5486)
		(mid 72.018457 -20.362613)
		(end 71.83247 -19.9136)
		(width 0.15748)
		(layer "In7.Cu")
		(net "CPU_RX_PCIE_MGT2_TXP")
	)
	(segment
		(start 98.846894 -38.823138)
		(end 98.347022 -38.323266)
		(width 0.09906)
		(layer "F.Cu")
		(net "CPU_RX_PCIE_MGT2_TXN")
	)
	(segment
		(start 72.18807 -18.432018)
		(end 72.18807 -18.858992)
		(width 0.14478)
		(layer "B.Cu")
		(net "CPU_RX_PCIE_MGT2_TXN")
	)
	(segment
		(start 71.95947 -16.97355)
		(end 71.95947 -17.879568)
		(width 0.14478)
		(layer "B.Cu")
		(net "CPU_RX_PCIE_MGT2_TXN")
	)
	(arc
		(start 72.40397 -15.9004)
		(mid 72.074982 -16.392765)
		(end 71.95947 -16.97355)
		(width 0.14478)
		(layer "B.Cu")
		(net "CPU_RX_PCIE_MGT2_TXN")
	)
	(arc
		(start 72.011794 -18.005806)
		(mid 72.142343 -18.20137)
		(end 72.18807 -18.432018)
		(width 0.14478)
		(layer "B.Cu")
		(net "CPU_RX_PCIE_MGT2_TXN")
	)
	(arc
		(start 72.18807 -18.858992)
		(mid 72.244179 -19.141071)
		(end 72.40397 -19.3802)
		(width 0.14478)
		(layer "B.Cu")
		(net "CPU_RX_PCIE_MGT2_TXN")
	)
	(arc
		(start 71.95947 -17.879568)
		(mid 71.973062 -17.947901)
		(end 72.011794 -18.005806)
		(width 0.14478)
		(layer "B.Cu")
		(net "CPU_RX_PCIE_MGT2_TXN")
	)
	(segment
		(start 97.4852 -38.67531)
		(end 97.456752 -38.67531)
		(width 0.1143)
		(layer "In7.Cu")
		(net "CPU_RX_PCIE_MGT2_TXN")
	)
	(segment
		(start 81.191608 -20.2184)
		(end 80.65516 -20.2184)
		(width 0.15748)
		(layer "In7.Cu")
		(net "CPU_RX_PCIE_MGT2_TXN")
	)
	(segment
		(start 96.96958 -38.53942)
		(end 96.969326 -38.53942)
		(width 0.15748)
		(layer "In7.Cu")
		(net "CPU_RX_PCIE_MGT2_TXN")
	)
	(segment
		(start 97.456752 -38.67531)
		(end 97.231454 -38.67531)
		(width 0.15748)
		(layer "In7.Cu")
		(net "CPU_RX_PCIE_MGT2_TXN")
	)
	(segment
		(start 96.969326 -38.53942)
		(end 96.791526 -38.36162)
		(width 0.15748)
		(layer "In7.Cu")
		(net "CPU_RX_PCIE_MGT2_TXN")
	)
	(segment
		(start 73.42378 -20.04822)
		(end 72.96404 -20.04822)
		(width 0.15748)
		(layer "In7.Cu")
		(net "CPU_RX_PCIE_MGT2_TXN")
	)
	(segment
		(start 96.097852 -38.0746)
		(end 86.681564 -38.0746)
		(width 0.15748)
		(layer "In7.Cu")
		(net "CPU_RX_PCIE_MGT2_TXN")
	)
	(segment
		(start 83.974432 -35.990022)
		(end 83.974178 -35.990276)
		(width 0.15748)
		(layer "In7.Cu")
		(net "CPU_RX_PCIE_MGT2_TXN")
	)
	(segment
		(start 84.419694 -36.435792)
		(end 84.419948 -36.435538)
		(width 0.15748)
		(layer "In7.Cu")
		(net "CPU_RX_PCIE_MGT2_TXN")
	)
	(segment
		(start 72.16267 -19.6215)
		(end 72.40397 -19.3802)
		(width 0.15748)
		(layer "In7.Cu")
		(net "CPU_RX_PCIE_MGT2_TXN")
	)
	(segment
		(start 79.85506 -20.2184)
		(end 77.14996 -20.2184)
		(width 0.15748)
		(layer "In7.Cu")
		(net "CPU_RX_PCIE_MGT2_TXN")
	)
	(segment
		(start 80.48498 -20.04822)
		(end 80.02524 -20.04822)
		(width 0.15748)
		(layer "In7.Cu")
		(net "CPU_RX_PCIE_MGT2_TXN")
	)
	(segment
		(start 97.55505 -38.74516)
		(end 97.4852 -38.67531)
		(width 0.1143)
		(layer "In7.Cu")
		(net "CPU_RX_PCIE_MGT2_TXN")
	)
	(segment
		(start 97.016062 -38.585902)
		(end 96.96958 -38.53942)
		(width 0.15748)
		(layer "In7.Cu")
		(net "CPU_RX_PCIE_MGT2_TXN")
	)
	(segment
		(start 76.34986 -20.2184)
		(end 73.59396 -20.2184)
		(width 0.15748)
		(layer "In7.Cu")
		(net "CPU_RX_PCIE_MGT2_TXN")
	)
	(segment
		(start 84.419948 -36.315142)
		(end 84.094828 -35.990022)
		(width 0.15748)
		(layer "In7.Cu")
		(net "CPU_RX_PCIE_MGT2_TXN")
	)
	(segment
		(start 81.9658 -33.4518)
		(end 81.9658 -20.992592)
		(width 0.15748)
		(layer "In7.Cu")
		(net "CPU_RX_PCIE_MGT2_TXN")
	)
	(segment
		(start 98.347022 -38.323266)
		(end 98.637598 -38.323266)
		(width 0.1143)
		(layer "In7.Cu")
		(net "CPU_RX_PCIE_MGT2_TXN")
	)
	(segment
		(start 83.853782 -35.990276)
		(end 82.425794 -34.562288)
		(width 0.15748)
		(layer "In7.Cu")
		(net "CPU_RX_PCIE_MGT2_TXN")
	)
	(segment
		(start 85.412326 -37.54882)
		(end 84.419694 -36.556188)
		(width 0.15748)
		(layer "In7.Cu")
		(net "CPU_RX_PCIE_MGT2_TXN")
	)
	(segment
		(start 72.16267 -19.9136)
		(end 72.16267 -19.6215)
		(width 0.15748)
		(layer "In7.Cu")
		(net "CPU_RX_PCIE_MGT2_TXN")
	)
	(segment
		(start 72.79386 -20.2184)
		(end 72.46747 -20.2184)
		(width 0.15748)
		(layer "In7.Cu")
		(net "CPU_RX_PCIE_MGT2_TXN")
	)
	(segment
		(start 98.751898 -38.437566)
		(end 98.751898 -38.599364)
		(width 0.1143)
		(layer "In7.Cu")
		(net "CPU_RX_PCIE_MGT2_TXN")
	)
	(segment
		(start 76.97978 -20.04822)
		(end 76.52004 -20.04822)
		(width 0.15748)
		(layer "In7.Cu")
		(net "CPU_RX_PCIE_MGT2_TXN")
	)
	(segment
		(start 98.606102 -38.74516)
		(end 97.55505 -38.74516)
		(width 0.1143)
		(layer "In7.Cu")
		(net "CPU_RX_PCIE_MGT2_TXN")
	)
	(arc
		(start 73.59396 -20.2184)
		(mid 73.533792 -20.193478)
		(end 73.50887 -20.13331)
		(width 0.15748)
		(layer "In7.Cu")
		(net "CPU_RX_PCIE_MGT2_TXN")
	)
	(arc
		(start 97.231454 -38.67531)
		(mid 97.114841 -38.652078)
		(end 97.016062 -38.585902)
		(width 0.15748)
		(layer "In7.Cu")
		(net "CPU_RX_PCIE_MGT2_TXN")
	)
	(arc
		(start 82.425794 -34.562288)
		(mid 82.08536 -34.052792)
		(end 81.9658 -33.4518)
		(width 0.15748)
		(layer "In7.Cu")
		(net "CPU_RX_PCIE_MGT2_TXN")
	)
	(arc
		(start 76.43495 -20.13331)
		(mid 76.410028 -20.193478)
		(end 76.34986 -20.2184)
		(width 0.15748)
		(layer "In7.Cu")
		(net "CPU_RX_PCIE_MGT2_TXN")
	)
	(arc
		(start 79.94015 -20.13331)
		(mid 79.915228 -20.193478)
		(end 79.85506 -20.2184)
		(width 0.15748)
		(layer "In7.Cu")
		(net "CPU_RX_PCIE_MGT2_TXN")
	)
	(arc
		(start 80.57007 -20.13331)
		(mid 80.545148 -20.073142)
		(end 80.48498 -20.04822)
		(width 0.15748)
		(layer "In7.Cu")
		(net "CPU_RX_PCIE_MGT2_TXN")
	)
	(arc
		(start 80.02524 -20.04822)
		(mid 79.965072 -20.073142)
		(end 79.94015 -20.13331)
		(width 0.15748)
		(layer "In7.Cu")
		(net "CPU_RX_PCIE_MGT2_TXN")
	)
	(arc
		(start 72.96404 -20.04822)
		(mid 72.903872 -20.073142)
		(end 72.87895 -20.13331)
		(width 0.15748)
		(layer "In7.Cu")
		(net "CPU_RX_PCIE_MGT2_TXN")
	)
	(arc
		(start 72.46747 -20.2184)
		(mid 72.251944 -20.129126)
		(end 72.16267 -19.9136)
		(width 0.15748)
		(layer "In7.Cu")
		(net "CPU_RX_PCIE_MGT2_TXN")
	)
	(arc
		(start 98.751898 -38.599364)
		(mid 98.709195 -38.702457)
		(end 98.606102 -38.74516)
		(width 0.1143)
		(layer "In7.Cu")
		(net "CPU_RX_PCIE_MGT2_TXN")
	)
	(arc
		(start 98.637598 -38.323266)
		(mid 98.71842 -38.356744)
		(end 98.751898 -38.437566)
		(width 0.1143)
		(layer "In7.Cu")
		(net "CPU_RX_PCIE_MGT2_TXN")
	)
	(arc
		(start 83.974178 -35.990276)
		(mid 83.91398 -36.015211)
		(end 83.853782 -35.990276)
		(width 0.15748)
		(layer "In7.Cu")
		(net "CPU_RX_PCIE_MGT2_TXN")
	)
	(arc
		(start 96.791526 -38.36162)
		(mid 96.473236 -38.149131)
		(end 96.097852 -38.0746)
		(width 0.15748)
		(layer "In7.Cu")
		(net "CPU_RX_PCIE_MGT2_TXN")
	)
	(arc
		(start 76.52004 -20.04822)
		(mid 76.459872 -20.073142)
		(end 76.43495 -20.13331)
		(width 0.15748)
		(layer "In7.Cu")
		(net "CPU_RX_PCIE_MGT2_TXN")
	)
	(arc
		(start 84.419948 -36.435538)
		(mid 84.444883 -36.37534)
		(end 84.419948 -36.315142)
		(width 0.15748)
		(layer "In7.Cu")
		(net "CPU_RX_PCIE_MGT2_TXN")
	)
	(arc
		(start 80.65516 -20.2184)
		(mid 80.594992 -20.193478)
		(end 80.57007 -20.13331)
		(width 0.15748)
		(layer "In7.Cu")
		(net "CPU_RX_PCIE_MGT2_TXN")
	)
	(arc
		(start 84.419694 -36.556188)
		(mid 84.394759 -36.49599)
		(end 84.419694 -36.435792)
		(width 0.15748)
		(layer "In7.Cu")
		(net "CPU_RX_PCIE_MGT2_TXN")
	)
	(arc
		(start 73.50887 -20.13331)
		(mid 73.483948 -20.073142)
		(end 73.42378 -20.04822)
		(width 0.15748)
		(layer "In7.Cu")
		(net "CPU_RX_PCIE_MGT2_TXN")
	)
	(arc
		(start 72.87895 -20.13331)
		(mid 72.854028 -20.193478)
		(end 72.79386 -20.2184)
		(width 0.15748)
		(layer "In7.Cu")
		(net "CPU_RX_PCIE_MGT2_TXN")
	)
	(arc
		(start 86.681564 -38.0746)
		(mid 85.99464 -37.937962)
		(end 85.412326 -37.54882)
		(width 0.15748)
		(layer "In7.Cu")
		(net "CPU_RX_PCIE_MGT2_TXN")
	)
	(arc
		(start 77.14996 -20.2184)
		(mid 77.089792 -20.193478)
		(end 77.06487 -20.13331)
		(width 0.15748)
		(layer "In7.Cu")
		(net "CPU_RX_PCIE_MGT2_TXN")
	)
	(arc
		(start 77.06487 -20.13331)
		(mid 77.039948 -20.073142)
		(end 76.97978 -20.04822)
		(width 0.15748)
		(layer "In7.Cu")
		(net "CPU_RX_PCIE_MGT2_TXN")
	)
	(arc
		(start 84.094828 -35.990022)
		(mid 84.03463 -35.965087)
		(end 83.974432 -35.990022)
		(width 0.15748)
		(layer "In7.Cu")
		(net "CPU_RX_PCIE_MGT2_TXN")
	)
	(arc
		(start 81.9658 -20.992592)
		(mid 81.739044 -20.445156)
		(end 81.191608 -20.2184)
		(width 0.15748)
		(layer "In7.Cu")
		(net "CPU_RX_PCIE_MGT2_TXN")
	)
	(segment
		(start 101.847142 -37.82314)
		(end 101.34727 -37.323268)
		(width 0.09906)
		(layer "F.Cu")
		(net "CPU_RX_PCIE_MGT1_TXP")
	)
	(segment
		(start 67.959478 -16.97355)
		(end 67.959478 -18.858992)
		(width 0.14478)
		(layer "B.Cu")
		(net "CPU_RX_PCIE_MGT1_TXP")
	)
	(arc
		(start 67.514978 -15.9004)
		(mid 67.843966 -16.392765)
		(end 67.959478 -16.97355)
		(width 0.14478)
		(layer "B.Cu")
		(net "CPU_RX_PCIE_MGT1_TXP")
	)
	(arc
		(start 67.959478 -18.858992)
		(mid 67.903369 -19.141071)
		(end 67.743578 -19.3802)
		(width 0.14478)
		(layer "B.Cu")
		(net "CPU_RX_PCIE_MGT1_TXP")
	)
	(segment
		(start 81.487264 -18.4658)
		(end 74.959718 -18.4658)
		(width 0.15748)
		(layer "In7.Cu")
		(net "CPU_RX_PCIE_MGT1_TXP")
	)
	(segment
		(start 67.984878 -19.1389)
		(end 67.743578 -19.3802)
		(width 0.15748)
		(layer "In7.Cu")
		(net "CPU_RX_PCIE_MGT1_TXP")
	)
	(segment
		(start 100.90658 -37.173154)
		(end 100.90658 -37.056314)
		(width 0.1143)
		(layer "In7.Cu")
		(net "CPU_RX_PCIE_MGT1_TXP")
	)
	(segment
		(start 99.645724 -36.7157)
		(end 97.897188 -36.7157)
		(width 0.1143)
		(layer "In7.Cu")
		(net "CPU_RX_PCIE_MGT1_TXP")
	)
	(segment
		(start 97.815908 -36.708588)
		(end 97.618804 -36.674552)
		(width 0.1143)
		(layer "In7.Cu")
		(net "CPU_RX_PCIE_MGT1_TXP")
	)
	(segment
		(start 95.678752 -36.59505)
		(end 88.144858 -36.59505)
		(width 0.15748)
		(layer "In7.Cu")
		(net "CPU_RX_PCIE_MGT1_TXP")
	)
	(segment
		(start 97.505012 -36.6649)
		(end 95.878396 -36.6649)
		(width 0.1143)
		(layer "In7.Cu")
		(net "CPU_RX_PCIE_MGT1_TXP")
	)
	(segment
		(start 100.101146 -36.7411)
		(end 100.100638 -36.740592)
		(width 0.1143)
		(layer "In7.Cu")
		(net "CPU_RX_PCIE_MGT1_TXP")
	)
	(segment
		(start 95.77705 -36.6649)
		(end 95.7072 -36.59505)
		(width 0.1143)
		(layer "In7.Cu")
		(net "CPU_RX_PCIE_MGT1_TXP")
	)
	(segment
		(start 83.57108 -31.900876)
		(end 83.57108 -20.549616)
		(width 0.15748)
		(layer "In7.Cu")
		(net "CPU_RX_PCIE_MGT1_TXP")
	)
	(segment
		(start 95.7072 -36.59505)
		(end 95.678752 -36.59505)
		(width 0.1143)
		(layer "In7.Cu")
		(net "CPU_RX_PCIE_MGT1_TXP")
	)
	(segment
		(start 101.34727 -37.323268)
		(end 101.056694 -37.323268)
		(width 0.1143)
		(layer "In7.Cu")
		(net "CPU_RX_PCIE_MGT1_TXP")
	)
	(segment
		(start 74.089768 -18.23212)
		(end 68.478654 -18.23212)
		(width 0.15748)
		(layer "In7.Cu")
		(net "CPU_RX_PCIE_MGT1_TXP")
	)
	(segment
		(start 100.591366 -36.7411)
		(end 100.101146 -36.7411)
		(width 0.1143)
		(layer "In7.Cu")
		(net "CPU_RX_PCIE_MGT1_TXP")
	)
	(segment
		(start 87.77859 -36.48075)
		(end 83.734148 -32.436308)
		(width 0.15748)
		(layer "In7.Cu")
		(net "CPU_RX_PCIE_MGT1_TXP")
	)
	(segment
		(start 67.984878 -18.770854)
		(end 67.984878 -19.1389)
		(width 0.15748)
		(layer "In7.Cu")
		(net "CPU_RX_PCIE_MGT1_TXP")
	)
	(segment
		(start 100.100638 -36.740592)
		(end 100.10013 -36.7411)
		(width 0.1143)
		(layer "In7.Cu")
		(net "CPU_RX_PCIE_MGT1_TXP")
	)
	(arc
		(start 68.004436 -18.605246)
		(mid 67.989742 -18.687469)
		(end 67.984878 -18.770854)
		(width 0.15748)
		(layer "In7.Cu")
		(net "CPU_RX_PCIE_MGT1_TXP")
	)
	(arc
		(start 88.144858 -36.59505)
		(mid 88.028199 -36.58665)
		(end 87.913972 -36.561522)
		(width 0.15748)
		(layer "In7.Cu")
		(net "CPU_RX_PCIE_MGT1_TXP")
	)
	(arc
		(start 99.891596 -36.72967)
		(mid 99.768856 -36.71923)
		(end 99.645724 -36.7157)
		(width 0.1143)
		(layer "In7.Cu")
		(net "CPU_RX_PCIE_MGT1_TXP")
	)
	(arc
		(start 83.57108 -20.549616)
		(mid 82.960744 -19.076136)
		(end 81.487264 -18.4658)
		(width 0.15748)
		(layer "In7.Cu")
		(net "CPU_RX_PCIE_MGT1_TXP")
	)
	(arc
		(start 74.690224 -18.39341)
		(mid 74.400642 -18.273122)
		(end 74.089768 -18.23212)
		(width 0.15748)
		(layer "In7.Cu")
		(net "CPU_RX_PCIE_MGT1_TXP")
	)
	(arc
		(start 100.90658 -37.056314)
		(mid 100.814256 -36.833424)
		(end 100.591366 -36.7411)
		(width 0.1143)
		(layer "In7.Cu")
		(net "CPU_RX_PCIE_MGT1_TXP")
	)
	(arc
		(start 68.478654 -18.23212)
		(mid 68.176872 -18.336508)
		(end 68.004436 -18.605246)
		(width 0.15748)
		(layer "In7.Cu")
		(net "CPU_RX_PCIE_MGT1_TXP")
	)
	(arc
		(start 100.10013 -36.7411)
		(mid 99.995698 -36.738391)
		(end 99.891596 -36.72967)
		(width 0.1143)
		(layer "In7.Cu")
		(net "CPU_RX_PCIE_MGT1_TXP")
	)
	(arc
		(start 95.779336 -36.675314)
		(mid 95.782815 -36.669081)
		(end 95.77705 -36.6649)
		(width 0.1143)
		(layer "In7.Cu")
		(net "CPU_RX_PCIE_MGT1_TXP")
	)
	(arc
		(start 83.647788 -32.304482)
		(mid 83.590443 -32.106288)
		(end 83.57108 -31.900876)
		(width 0.15748)
		(layer "In7.Cu")
		(net "CPU_RX_PCIE_MGT1_TXP")
	)
	(arc
		(start 101.056694 -37.323268)
		(mid 100.950547 -37.279301)
		(end 100.90658 -37.173154)
		(width 0.1143)
		(layer "In7.Cu")
		(net "CPU_RX_PCIE_MGT1_TXP")
	)
	(arc
		(start 97.618804 -36.674552)
		(mid 97.562114 -36.6673)
		(end 97.505012 -36.6649)
		(width 0.1143)
		(layer "In7.Cu")
		(net "CPU_RX_PCIE_MGT1_TXP")
	)
	(arc
		(start 83.734148 -32.436308)
		(mid 83.684198 -32.374833)
		(end 83.647788 -32.304482)
		(width 0.15748)
		(layer "In7.Cu")
		(net "CPU_RX_PCIE_MGT1_TXP")
	)
	(arc
		(start 74.959718 -18.4658)
		(mid 74.820196 -18.447384)
		(end 74.690224 -18.39341)
		(width 0.15748)
		(layer "In7.Cu")
		(net "CPU_RX_PCIE_MGT1_TXP")
	)
	(arc
		(start 95.878396 -36.6649)
		(mid 95.828589 -36.667473)
		(end 95.779336 -36.675314)
		(width 0.1143)
		(layer "In7.Cu")
		(net "CPU_RX_PCIE_MGT1_TXP")
	)
	(arc
		(start 87.913972 -36.561522)
		(mid 87.841237 -36.52959)
		(end 87.77859 -36.48075)
		(width 0.15748)
		(layer "In7.Cu")
		(net "CPU_RX_PCIE_MGT1_TXP")
	)
	(arc
		(start 97.897188 -36.7157)
		(mid 97.856397 -36.713868)
		(end 97.815908 -36.708588)
		(width 0.1143)
		(layer "In7.Cu")
		(net "CPU_RX_PCIE_MGT1_TXP")
	)
	(segment
		(start 100.84689 -37.82314)
		(end 100.347018 -37.323268)
		(width 0.09906)
		(layer "F.Cu")
		(net "CPU_RX_PCIE_MGT1_TXN")
	)
	(segment
		(start 68.340478 -16.97355)
		(end 68.340478 -18.858992)
		(width 0.14478)
		(layer "B.Cu")
		(net "CPU_RX_PCIE_MGT1_TXN")
	)
	(arc
		(start 68.784978 -15.9004)
		(mid 68.45599 -16.392765)
		(end 68.340478 -16.97355)
		(width 0.14478)
		(layer "B.Cu")
		(net "CPU_RX_PCIE_MGT1_TXN")
	)
	(arc
		(start 68.340478 -18.858992)
		(mid 68.396587 -19.141071)
		(end 68.556378 -19.3802)
		(width 0.14478)
		(layer "B.Cu")
		(net "CPU_RX_PCIE_MGT1_TXN")
	)
	(segment
		(start 79.944976 -18.96364)
		(end 79.482696 -18.96364)
		(width 0.15748)
		(layer "In7.Cu")
		(net "CPU_RX_PCIE_MGT1_TXN")
	)
	(segment
		(start 68.315078 -18.7706)
		(end 68.315078 -19.1389)
		(width 0.15748)
		(layer "In7.Cu")
		(net "CPU_RX_PCIE_MGT1_TXN")
	)
	(segment
		(start 100.591366 -36.9316)
		(end 100.100638 -36.9316)
		(width 0.1143)
		(layer "In7.Cu")
		(net "CPU_RX_PCIE_MGT1_TXN")
	)
	(segment
		(start 97.783396 -36.896294)
		(end 97.586546 -36.862512)
		(width 0.1143)
		(layer "In7.Cu")
		(net "CPU_RX_PCIE_MGT1_TXN")
	)
	(segment
		(start 69.680074 -18.56232)
		(end 68.478654 -18.56232)
		(width 0.15748)
		(layer "In7.Cu")
		(net "CPU_RX_PCIE_MGT1_TXN")
	)
	(segment
		(start 100.347018 -37.323268)
		(end 100.565966 -37.323268)
		(width 0.1143)
		(layer "In7.Cu")
		(net "CPU_RX_PCIE_MGT1_TXN")
	)
	(segment
		(start 70.309994 -18.73504)
		(end 69.852794 -18.73504)
		(width 0.15748)
		(layer "In7.Cu")
		(net "CPU_RX_PCIE_MGT1_TXN")
	)
	(segment
		(start 99.64547 -36.9062)
		(end 97.897188 -36.9062)
		(width 0.1143)
		(layer "In7.Cu")
		(net "CPU_RX_PCIE_MGT1_TXN")
	)
	(segment
		(start 83.24088 -26.85923)
		(end 83.24088 -22.255226)
		(width 0.15748)
		(layer "In7.Cu")
		(net "CPU_RX_PCIE_MGT1_TXN")
	)
	(segment
		(start 95.641922 -36.92525)
		(end 88.145112 -36.92525)
		(width 0.15748)
		(layer "In7.Cu")
		(net "CPU_RX_PCIE_MGT1_TXN")
	)
	(segment
		(start 83.07832 -27.48915)
		(end 83.07832 -27.02179)
		(width 0.15748)
		(layer "In7.Cu")
		(net "CPU_RX_PCIE_MGT1_TXN")
	)
	(segment
		(start 83.24088 -31.90113)
		(end 83.24088 -27.65171)
		(width 0.15748)
		(layer "In7.Cu")
		(net "CPU_RX_PCIE_MGT1_TXN")
	)
	(segment
		(start 100.71608 -37.173154)
		(end 100.71608 -37.056314)
		(width 0.1143)
		(layer "In7.Cu")
		(net "CPU_RX_PCIE_MGT1_TXN")
	)
	(segment
		(start 76.134976 -18.96364)
		(end 75.672696 -18.96364)
		(width 0.15748)
		(layer "In7.Cu")
		(net "CPU_RX_PCIE_MGT1_TXN")
	)
	(segment
		(start 81.487264 -18.796)
		(end 80.112616 -18.796)
		(width 0.15748)
		(layer "In7.Cu")
		(net "CPU_RX_PCIE_MGT1_TXN")
	)
	(segment
		(start 83.07832 -22.092666)
		(end 83.07832 -21.625306)
		(width 0.15748)
		(layer "In7.Cu")
		(net "CPU_RX_PCIE_MGT1_TXN")
	)
	(segment
		(start 75.505056 -18.796)
		(end 74.959972 -18.796)
		(width 0.15748)
		(layer "In7.Cu")
		(net "CPU_RX_PCIE_MGT1_TXN")
	)
	(segment
		(start 68.315078 -19.1389)
		(end 68.556378 -19.3802)
		(width 0.15748)
		(layer "In7.Cu")
		(net "CPU_RX_PCIE_MGT1_TXN")
	)
	(segment
		(start 74.089514 -18.56232)
		(end 70.482714 -18.56232)
		(width 0.15748)
		(layer "In7.Cu")
		(net "CPU_RX_PCIE_MGT1_TXN")
	)
	(segment
		(start 97.505266 -36.8554)
		(end 95.87865 -36.8554)
		(width 0.1143)
		(layer "In7.Cu")
		(net "CPU_RX_PCIE_MGT1_TXN")
	)
	(segment
		(start 83.24088 -21.462746)
		(end 83.24088 -20.549616)
		(width 0.15748)
		(layer "In7.Cu")
		(net "CPU_RX_PCIE_MGT1_TXN")
	)
	(segment
		(start 79.315056 -18.796)
		(end 76.302616 -18.796)
		(width 0.15748)
		(layer "In7.Cu")
		(net "CPU_RX_PCIE_MGT1_TXN")
	)
	(segment
		(start 87.54491 -36.714176)
		(end 83.500468 -32.669988)
		(width 0.15748)
		(layer "In7.Cu")
		(net "CPU_RX_PCIE_MGT1_TXN")
	)
	(arc
		(start 97.586546 -36.862512)
		(mid 97.546058 -36.857224)
		(end 97.505266 -36.8554)
		(width 0.1143)
		(layer "In7.Cu")
		(net "CPU_RX_PCIE_MGT1_TXN")
	)
	(arc
		(start 70.396354 -18.64868)
		(mid 70.37106 -18.709746)
		(end 70.309994 -18.73504)
		(width 0.15748)
		(layer "In7.Cu")
		(net "CPU_RX_PCIE_MGT1_TXN")
	)
	(arc
		(start 76.302616 -18.796)
		(mid 76.243346 -18.82055)
		(end 76.218796 -18.87982)
		(width 0.15748)
		(layer "In7.Cu")
		(net "CPU_RX_PCIE_MGT1_TXN")
	)
	(arc
		(start 95.72752 -36.900104)
		(mid 95.686538 -36.918859)
		(end 95.641922 -36.92525)
		(width 0.1143)
		(layer "In7.Cu")
		(net "CPU_RX_PCIE_MGT1_TXN")
	)
	(arc
		(start 97.897188 -36.9062)
		(mid 97.840081 -36.903668)
		(end 97.783396 -36.896294)
		(width 0.1143)
		(layer "In7.Cu")
		(net "CPU_RX_PCIE_MGT1_TXN")
	)
	(arc
		(start 99.87026 -36.919154)
		(mid 99.758048 -36.909504)
		(end 99.64547 -36.9062)
		(width 0.1143)
		(layer "In7.Cu")
		(net "CPU_RX_PCIE_MGT1_TXN")
	)
	(arc
		(start 68.478654 -18.56232)
		(mid 68.381148 -18.595937)
		(end 68.325492 -18.682716)
		(width 0.15748)
		(layer "In7.Cu")
		(net "CPU_RX_PCIE_MGT1_TXN")
	)
	(arc
		(start 83.1596 -26.94051)
		(mid 83.217074 -26.916704)
		(end 83.24088 -26.85923)
		(width 0.15748)
		(layer "In7.Cu")
		(net "CPU_RX_PCIE_MGT1_TXN")
	)
	(arc
		(start 68.325492 -18.682716)
		(mid 68.317686 -18.72635)
		(end 68.315078 -18.7706)
		(width 0.15748)
		(layer "In7.Cu")
		(net "CPU_RX_PCIE_MGT1_TXN")
	)
	(arc
		(start 80.028796 -18.87982)
		(mid 80.004246 -18.93909)
		(end 79.944976 -18.96364)
		(width 0.15748)
		(layer "In7.Cu")
		(net "CPU_RX_PCIE_MGT1_TXN")
	)
	(arc
		(start 83.07832 -21.625306)
		(mid 83.102126 -21.567832)
		(end 83.1596 -21.544026)
		(width 0.15748)
		(layer "In7.Cu")
		(net "CPU_RX_PCIE_MGT1_TXN")
	)
	(arc
		(start 83.500468 -32.669988)
		(mid 83.407888 -32.555914)
		(end 83.340448 -32.425386)
		(width 0.15748)
		(layer "In7.Cu")
		(net "CPU_RX_PCIE_MGT1_TXN")
	)
	(arc
		(start 69.852794 -18.73504)
		(mid 69.791728 -18.709746)
		(end 69.766434 -18.64868)
		(width 0.15748)
		(layer "In7.Cu")
		(net "CPU_RX_PCIE_MGT1_TXN")
	)
	(arc
		(start 74.959972 -18.796)
		(mid 74.734605 -18.766434)
		(end 74.524616 -18.679414)
		(width 0.15748)
		(layer "In7.Cu")
		(net "CPU_RX_PCIE_MGT1_TXN")
	)
	(arc
		(start 83.07832 -27.02179)
		(mid 83.102126 -26.964316)
		(end 83.1596 -26.94051)
		(width 0.15748)
		(layer "In7.Cu")
		(net "CPU_RX_PCIE_MGT1_TXN")
	)
	(arc
		(start 100.100638 -36.9316)
		(mid 99.985269 -36.928709)
		(end 99.87026 -36.919154)
		(width 0.1143)
		(layer "In7.Cu")
		(net "CPU_RX_PCIE_MGT1_TXN")
	)
	(arc
		(start 79.398876 -18.87982)
		(mid 79.374326 -18.82055)
		(end 79.315056 -18.796)
		(width 0.15748)
		(layer "In7.Cu")
		(net "CPU_RX_PCIE_MGT1_TXN")
	)
	(arc
		(start 100.565966 -37.323268)
		(mid 100.672113 -37.279301)
		(end 100.71608 -37.173154)
		(width 0.1143)
		(layer "In7.Cu")
		(net "CPU_RX_PCIE_MGT1_TXN")
	)
	(arc
		(start 79.482696 -18.96364)
		(mid 79.423426 -18.93909)
		(end 79.398876 -18.87982)
		(width 0.15748)
		(layer "In7.Cu")
		(net "CPU_RX_PCIE_MGT1_TXN")
	)
	(arc
		(start 74.524616 -18.679414)
		(mid 74.314796 -18.592142)
		(end 74.089514 -18.56232)
		(width 0.15748)
		(layer "In7.Cu")
		(net "CPU_RX_PCIE_MGT1_TXN")
	)
	(arc
		(start 75.672696 -18.96364)
		(mid 75.613426 -18.93909)
		(end 75.588876 -18.87982)
		(width 0.15748)
		(layer "In7.Cu")
		(net "CPU_RX_PCIE_MGT1_TXN")
	)
	(arc
		(start 80.112616 -18.796)
		(mid 80.053346 -18.82055)
		(end 80.028796 -18.87982)
		(width 0.15748)
		(layer "In7.Cu")
		(net "CPU_RX_PCIE_MGT1_TXN")
	)
	(arc
		(start 100.71608 -37.056314)
		(mid 100.679552 -36.968128)
		(end 100.591366 -36.9316)
		(width 0.1143)
		(layer "In7.Cu")
		(net "CPU_RX_PCIE_MGT1_TXN")
	)
	(arc
		(start 83.340448 -32.425386)
		(mid 83.266028 -32.167938)
		(end 83.24088 -31.90113)
		(width 0.15748)
		(layer "In7.Cu")
		(net "CPU_RX_PCIE_MGT1_TXN")
	)
	(arc
		(start 83.1596 -27.57043)
		(mid 83.102126 -27.546624)
		(end 83.07832 -27.48915)
		(width 0.15748)
		(layer "In7.Cu")
		(net "CPU_RX_PCIE_MGT1_TXN")
	)
	(arc
		(start 88.145112 -36.92525)
		(mid 87.980724 -36.913533)
		(end 87.819738 -36.87826)
		(width 0.15748)
		(layer "In7.Cu")
		(net "CPU_RX_PCIE_MGT1_TXN")
	)
	(arc
		(start 76.218796 -18.87982)
		(mid 76.194246 -18.93909)
		(end 76.134976 -18.96364)
		(width 0.15748)
		(layer "In7.Cu")
		(net "CPU_RX_PCIE_MGT1_TXN")
	)
	(arc
		(start 83.24088 -20.549616)
		(mid 82.727258 -19.309622)
		(end 81.487264 -18.796)
		(width 0.15748)
		(layer "In7.Cu")
		(net "CPU_RX_PCIE_MGT1_TXN")
	)
	(arc
		(start 83.24088 -27.65171)
		(mid 83.217074 -27.594236)
		(end 83.1596 -27.57043)
		(width 0.15748)
		(layer "In7.Cu")
		(net "CPU_RX_PCIE_MGT1_TXN")
	)
	(arc
		(start 87.819738 -36.87826)
		(mid 87.672081 -36.813376)
		(end 87.54491 -36.714176)
		(width 0.15748)
		(layer "In7.Cu")
		(net "CPU_RX_PCIE_MGT1_TXN")
	)
	(arc
		(start 70.482714 -18.56232)
		(mid 70.421648 -18.587614)
		(end 70.396354 -18.64868)
		(width 0.15748)
		(layer "In7.Cu")
		(net "CPU_RX_PCIE_MGT1_TXN")
	)
	(arc
		(start 83.1596 -21.544026)
		(mid 83.217074 -21.52022)
		(end 83.24088 -21.462746)
		(width 0.15748)
		(layer "In7.Cu")
		(net "CPU_RX_PCIE_MGT1_TXN")
	)
	(arc
		(start 69.766434 -18.64868)
		(mid 69.74114 -18.587614)
		(end 69.680074 -18.56232)
		(width 0.15748)
		(layer "In7.Cu")
		(net "CPU_RX_PCIE_MGT1_TXN")
	)
	(arc
		(start 83.1596 -22.173946)
		(mid 83.102126 -22.15014)
		(end 83.07832 -22.092666)
		(width 0.15748)
		(layer "In7.Cu")
		(net "CPU_RX_PCIE_MGT1_TXN")
	)
	(arc
		(start 95.87865 -36.8554)
		(mid 95.799841 -36.866799)
		(end 95.72752 -36.900104)
		(width 0.1143)
		(layer "In7.Cu")
		(net "CPU_RX_PCIE_MGT1_TXN")
	)
	(arc
		(start 83.24088 -22.255226)
		(mid 83.217074 -22.197752)
		(end 83.1596 -22.173946)
		(width 0.15748)
		(layer "In7.Cu")
		(net "CPU_RX_PCIE_MGT1_TXN")
	)
	(arc
		(start 75.588876 -18.87982)
		(mid 75.564326 -18.82055)
		(end 75.505056 -18.796)
		(width 0.15748)
		(layer "In7.Cu")
		(net "CPU_RX_PCIE_MGT1_TXN")
	)
	(segment
		(start 99.846892 -36.823142)
		(end 99.34702 -36.32327)
		(width 0.09906)
		(layer "F.Cu")
		(net "CPU_RX_PCIE_MGT0_TXP")
	)
	(segment
		(start 62.959488 -18.858992)
		(end 62.959488 -16.73098)
		(width 0.14478)
		(layer "B.Cu")
		(net "CPU_RX_PCIE_MGT0_TXP")
	)
	(segment
		(start 62.686438 -16.07185)
		(end 62.514988 -15.9004)
		(width 0.14478)
		(layer "B.Cu")
		(net "CPU_RX_PCIE_MGT0_TXP")
	)
	(arc
		(start 62.743588 -19.3802)
		(mid 62.903371 -19.141068)
		(end 62.959488 -18.858992)
		(width 0.14478)
		(layer "B.Cu")
		(net "CPU_RX_PCIE_MGT0_TXP")
	)
	(arc
		(start 62.959488 -16.73098)
		(mid 62.88853 -16.37425)
		(end 62.686438 -16.07185)
		(width 0.14478)
		(layer "B.Cu")
		(net "CPU_RX_PCIE_MGT0_TXP")
	)
	(segment
		(start 98.908362 -36.174934)
		(end 98.908362 -36.049712)
		(width 0.1143)
		(layer "In7.Cu")
		(net "CPU_RX_PCIE_MGT0_TXP")
	)
	(segment
		(start 88.069674 -34.348674)
		(end 85.154008 -31.433008)
		(width 0.15748)
		(layer "In7.Cu")
		(net "CPU_RX_PCIE_MGT0_TXP")
	)
	(segment
		(start 95.37192 -34.5694)
		(end 88.760554 -34.5694)
		(width 0.15748)
		(layer "In7.Cu")
		(net "CPU_RX_PCIE_MGT0_TXP")
	)
	(segment
		(start 98.58248 -35.72256)
		(end 98.22688 -35.72256)
		(width 0.1143)
		(layer "In7.Cu")
		(net "CPU_RX_PCIE_MGT0_TXP")
	)
	(segment
		(start 84.9503 -30.87751)
		(end 84.9503 -19.48688)
		(width 0.15748)
		(layer "In7.Cu")
		(net "CPU_RX_PCIE_MGT0_TXP")
	)
	(segment
		(start 62.984888 -18.415254)
		(end 62.984888 -19.073622)
		(width 0.15748)
		(layer "In7.Cu")
		(net "CPU_RX_PCIE_MGT0_TXP")
	)
	(segment
		(start 97.979992 -35.620198)
		(end 97.52076 -35.160966)
		(width 0.1143)
		(layer "In7.Cu")
		(net "CPU_RX_PCIE_MGT0_TXP")
	)
	(segment
		(start 96.261174 -34.63925)
		(end 95.517462 -34.63925)
		(width 0.1143)
		(layer "In7.Cu")
		(net "CPU_RX_PCIE_MGT0_TXP")
	)
	(segment
		(start 99.34702 -36.32327)
		(end 99.056698 -36.32327)
		(width 0.1143)
		(layer "In7.Cu")
		(net "CPU_RX_PCIE_MGT0_TXP")
	)
	(segment
		(start 82.10042 -16.637)
		(end 64.846454 -16.637)
		(width 0.15748)
		(layer "In7.Cu")
		(net "CPU_RX_PCIE_MGT0_TXP")
	)
	(segment
		(start 62.93866 -19.185128)
		(end 62.743588 -19.3802)
		(width 0.15748)
		(layer "In7.Cu")
		(net "CPU_RX_PCIE_MGT0_TXP")
	)
	(segment
		(start 63.92672 -16.9799)
		(end 63.281306 -17.625568)
		(width 0.15748)
		(layer "In7.Cu")
		(net "CPU_RX_PCIE_MGT0_TXP")
	)
	(segment
		(start 95.400368 -34.5694)
		(end 95.37192 -34.5694)
		(width 0.1143)
		(layer "In7.Cu")
		(net "CPU_RX_PCIE_MGT0_TXP")
	)
	(segment
		(start 95.43669 -34.605722)
		(end 95.400368 -34.5694)
		(width 0.1143)
		(layer "In7.Cu")
		(net "CPU_RX_PCIE_MGT0_TXP")
	)
	(arc
		(start 98.916744 -36.22421)
		(mid 98.915287 -36.220039)
		(end 98.91395 -36.215828)
		(width 0.1143)
		(layer "In7.Cu")
		(net "CPU_RX_PCIE_MGT0_TXP")
	)
	(arc
		(start 88.197944 -34.440114)
		(mid 88.129983 -34.39976)
		(end 88.069674 -34.348674)
		(width 0.15748)
		(layer "In7.Cu")
		(net "CPU_RX_PCIE_MGT0_TXP")
	)
	(arc
		(start 95.517462 -34.63925)
		(mid 95.473736 -34.630534)
		(end 95.43669 -34.605722)
		(width 0.1143)
		(layer "In7.Cu")
		(net "CPU_RX_PCIE_MGT0_TXP")
	)
	(arc
		(start 98.22688 -35.72256)
		(mid 98.093282 -35.695892)
		(end 97.979992 -35.620198)
		(width 0.1143)
		(layer "In7.Cu")
		(net "CPU_RX_PCIE_MGT0_TXP")
	)
	(arc
		(start 88.760554 -34.5694)
		(mid 88.471904 -34.536705)
		(end 88.197944 -34.440114)
		(width 0.15748)
		(layer "In7.Cu")
		(net "CPU_RX_PCIE_MGT0_TXP")
	)
	(arc
		(start 85.154008 -31.433008)
		(mid 85.102854 -31.372611)
		(end 85.062568 -31.304484)
		(width 0.15748)
		(layer "In7.Cu")
		(net "CPU_RX_PCIE_MGT0_TXP")
	)
	(arc
		(start 97.52076 -35.160966)
		(mid 96.942844 -34.774848)
		(end 96.261174 -34.63925)
		(width 0.1143)
		(layer "In7.Cu")
		(net "CPU_RX_PCIE_MGT0_TXP")
	)
	(arc
		(start 64.120014 -16.831564)
		(mid 64.018511 -16.899404)
		(end 63.92672 -16.9799)
		(width 0.15748)
		(layer "In7.Cu")
		(net "CPU_RX_PCIE_MGT0_TXP")
	)
	(arc
		(start 64.846454 -16.637)
		(mid 64.470422 -16.686432)
		(end 64.120014 -16.831564)
		(width 0.15748)
		(layer "In7.Cu")
		(net "CPU_RX_PCIE_MGT0_TXP")
	)
	(arc
		(start 99.056698 -36.32327)
		(mid 98.970977 -36.295994)
		(end 98.916744 -36.22421)
		(width 0.1143)
		(layer "In7.Cu")
		(net "CPU_RX_PCIE_MGT0_TXP")
	)
	(arc
		(start 98.91395 -36.215828)
		(mid 98.90972 -36.195577)
		(end 98.908362 -36.174934)
		(width 0.1143)
		(layer "In7.Cu")
		(net "CPU_RX_PCIE_MGT0_TXP")
	)
	(arc
		(start 84.9503 -19.48688)
		(mid 84.115589 -17.471711)
		(end 82.10042 -16.637)
		(width 0.15748)
		(layer "In7.Cu")
		(net "CPU_RX_PCIE_MGT0_TXP")
	)
	(arc
		(start 63.128652 -17.832324)
		(mid 63.021269 -18.115031)
		(end 62.984888 -18.415254)
		(width 0.15748)
		(layer "In7.Cu")
		(net "CPU_RX_PCIE_MGT0_TXP")
	)
	(arc
		(start 84.96808 -31.033974)
		(mid 84.954817 -30.95624)
		(end 84.9503 -30.87751)
		(width 0.15748)
		(layer "In7.Cu")
		(net "CPU_RX_PCIE_MGT0_TXP")
	)
	(arc
		(start 62.984888 -19.073622)
		(mid 62.972866 -19.13397)
		(end 62.93866 -19.185128)
		(width 0.15748)
		(layer "In7.Cu")
		(net "CPU_RX_PCIE_MGT0_TXP")
	)
	(arc
		(start 98.908362 -36.049712)
		(mid 98.81299 -35.81883)
		(end 98.58248 -35.72256)
		(width 0.1143)
		(layer "In7.Cu")
		(net "CPU_RX_PCIE_MGT0_TXP")
	)
	(arc
		(start 85.062568 -31.304484)
		(mid 85.007691 -31.171895)
		(end 84.96808 -31.033974)
		(width 0.15748)
		(layer "In7.Cu")
		(net "CPU_RX_PCIE_MGT0_TXP")
	)
	(arc
		(start 63.281306 -17.625568)
		(mid 63.197171 -17.723182)
		(end 63.128652 -17.832324)
		(width 0.15748)
		(layer "In7.Cu")
		(net "CPU_RX_PCIE_MGT0_TXP")
	)
	(segment
		(start 98.846894 -36.823142)
		(end 98.347022 -36.32327)
		(width 0.09906)
		(layer "F.Cu")
		(net "CPU_RX_PCIE_MGT0_TXN")
	)
	(segment
		(start 63.340488 -16.97355)
		(end 63.340488 -18.858992)
		(width 0.14478)
		(layer "B.Cu")
		(net "CPU_RX_PCIE_MGT0_TXN")
	)
	(arc
		(start 63.340488 -18.858992)
		(mid 63.396597 -19.141071)
		(end 63.556388 -19.3802)
		(width 0.14478)
		(layer "B.Cu")
		(net "CPU_RX_PCIE_MGT0_TXN")
	)
	(arc
		(start 63.784988 -15.9004)
		(mid 63.456 -16.392765)
		(end 63.340488 -16.97355)
		(width 0.14478)
		(layer "B.Cu")
		(net "CPU_RX_PCIE_MGT0_TXN")
	)
	(segment
		(start 95.400368 -34.8996)
		(end 95.37192 -34.8996)
		(width 0.1143)
		(layer "In7.Cu")
		(net "CPU_RX_PCIE_MGT0_TXN")
	)
	(segment
		(start 95.43669 -34.863278)
		(end 95.400368 -34.8996)
		(width 0.1143)
		(layer "In7.Cu")
		(net "CPU_RX_PCIE_MGT0_TXN")
	)
	(segment
		(start 72.734424 -16.9672)
		(end 69.975984 -16.9672)
		(width 0.15748)
		(layer "In7.Cu")
		(net "CPU_RX_PCIE_MGT0_TXN")
	)
	(segment
		(start 69.808344 -17.13484)
		(end 69.346064 -17.13484)
		(width 0.15748)
		(layer "In7.Cu")
		(net "CPU_RX_PCIE_MGT0_TXN")
	)
	(segment
		(start 98.581972 -35.91306)
		(end 98.22688 -35.91306)
		(width 0.1143)
		(layer "In7.Cu")
		(net "CPU_RX_PCIE_MGT0_TXN")
	)
	(segment
		(start 63.315088 -18.415)
		(end 63.315088 -18.84934)
		(width 0.15748)
		(layer "In7.Cu")
		(net "CPU_RX_PCIE_MGT0_TXN")
	)
	(segment
		(start 98.717862 -36.186618)
		(end 98.717862 -36.049712)
		(width 0.1143)
		(layer "In7.Cu")
		(net "CPU_RX_PCIE_MGT0_TXN")
	)
	(segment
		(start 66.262504 -17.1323)
		(end 65.797684 -17.1323)
		(width 0.15748)
		(layer "In7.Cu")
		(net "CPU_RX_PCIE_MGT0_TXN")
	)
	(segment
		(start 87.835994 -34.5821)
		(end 84.920582 -31.666688)
		(width 0.15748)
		(layer "In7.Cu")
		(net "CPU_RX_PCIE_MGT0_TXN")
	)
	(segment
		(start 96.26092 -34.82975)
		(end 95.517462 -34.82975)
		(width 0.1143)
		(layer "In7.Cu")
		(net "CPU_RX_PCIE_MGT0_TXN")
	)
	(segment
		(start 77.936344 -17.13484)
		(end 77.474064 -17.13484)
		(width 0.15748)
		(layer "In7.Cu")
		(net "CPU_RX_PCIE_MGT0_TXN")
	)
	(segment
		(start 97.845118 -35.755072)
		(end 97.38614 -35.29584)
		(width 0.1143)
		(layer "In7.Cu")
		(net "CPU_RX_PCIE_MGT0_TXN")
	)
	(segment
		(start 65.632584 -16.9672)
		(end 64.8462 -16.9672)
		(width 0.15748)
		(layer "In7.Cu")
		(net "CPU_RX_PCIE_MGT0_TXN")
	)
	(segment
		(start 73.364344 -17.13484)
		(end 72.902064 -17.13484)
		(width 0.15748)
		(layer "In7.Cu")
		(net "CPU_RX_PCIE_MGT0_TXN")
	)
	(segment
		(start 95.37192 -34.8996)
		(end 88.760554 -34.8996)
		(width 0.15748)
		(layer "In7.Cu")
		(net "CPU_RX_PCIE_MGT0_TXN")
	)
	(segment
		(start 81.492344 -17.13484)
		(end 81.030064 -17.13484)
		(width 0.15748)
		(layer "In7.Cu")
		(net "CPU_RX_PCIE_MGT0_TXN")
	)
	(segment
		(start 63.519812 -19.343624)
		(end 63.556388 -19.3802)
		(width 0.15748)
		(layer "In7.Cu")
		(net "CPU_RX_PCIE_MGT0_TXN")
	)
	(segment
		(start 77.306424 -16.9672)
		(end 73.531984 -16.9672)
		(width 0.15748)
		(layer "In7.Cu")
		(net "CPU_RX_PCIE_MGT0_TXN")
	)
	(segment
		(start 69.178424 -16.9672)
		(end 66.427604 -16.9672)
		(width 0.15748)
		(layer "In7.Cu")
		(net "CPU_RX_PCIE_MGT0_TXN")
	)
	(segment
		(start 64.1604 -17.21358)
		(end 63.514732 -17.859248)
		(width 0.15748)
		(layer "In7.Cu")
		(net "CPU_RX_PCIE_MGT0_TXN")
	)
	(segment
		(start 82.10042 -16.9672)
		(end 81.659984 -16.9672)
		(width 0.15748)
		(layer "In7.Cu")
		(net "CPU_RX_PCIE_MGT0_TXN")
	)
	(segment
		(start 98.347022 -36.32327)
		(end 98.580448 -36.32327)
		(width 0.1143)
		(layer "In7.Cu")
		(net "CPU_RX_PCIE_MGT0_TXN")
	)
	(segment
		(start 84.6201 -30.877764)
		(end 84.6201 -19.48688)
		(width 0.15748)
		(layer "In7.Cu")
		(net "CPU_RX_PCIE_MGT0_TXN")
	)
	(segment
		(start 80.862424 -16.9672)
		(end 78.103984 -16.9672)
		(width 0.15748)
		(layer "In7.Cu")
		(net "CPU_RX_PCIE_MGT0_TXN")
	)
	(arc
		(start 97.38614 -35.29584)
		(mid 96.869885 -34.950889)
		(end 96.26092 -34.82975)
		(width 0.1143)
		(layer "In7.Cu")
		(net "CPU_RX_PCIE_MGT0_TXN")
	)
	(arc
		(start 88.760554 -34.8996)
		(mid 88.397901 -34.858564)
		(end 88.053672 -34.737294)
		(width 0.15748)
		(layer "In7.Cu")
		(net "CPU_RX_PCIE_MGT0_TXN")
	)
	(arc
		(start 69.892164 -17.05102)
		(mid 69.867614 -17.11029)
		(end 69.808344 -17.13484)
		(width 0.15748)
		(layer "In7.Cu")
		(net "CPU_RX_PCIE_MGT0_TXN")
	)
	(arc
		(start 81.576164 -17.05102)
		(mid 81.551614 -17.11029)
		(end 81.492344 -17.13484)
		(width 0.15748)
		(layer "In7.Cu")
		(net "CPU_RX_PCIE_MGT0_TXN")
	)
	(arc
		(start 69.346064 -17.13484)
		(mid 69.286794 -17.11029)
		(end 69.262244 -17.05102)
		(width 0.15748)
		(layer "In7.Cu")
		(net "CPU_RX_PCIE_MGT0_TXN")
	)
	(arc
		(start 84.920582 -31.666688)
		(mid 84.833655 -31.563885)
		(end 84.765134 -31.447994)
		(width 0.15748)
		(layer "In7.Cu")
		(net "CPU_RX_PCIE_MGT0_TXN")
	)
	(arc
		(start 73.531984 -16.9672)
		(mid 73.472714 -16.99175)
		(end 73.448164 -17.05102)
		(width 0.15748)
		(layer "In7.Cu")
		(net "CPU_RX_PCIE_MGT0_TXN")
	)
	(arc
		(start 81.659984 -16.9672)
		(mid 81.600714 -16.99175)
		(end 81.576164 -17.05102)
		(width 0.15748)
		(layer "In7.Cu")
		(net "CPU_RX_PCIE_MGT0_TXN")
	)
	(arc
		(start 65.797684 -17.1323)
		(mid 65.739312 -17.108122)
		(end 65.715134 -17.04975)
		(width 0.15748)
		(layer "In7.Cu")
		(net "CPU_RX_PCIE_MGT0_TXN")
	)
	(arc
		(start 63.514732 -17.859248)
		(mid 63.463071 -17.919209)
		(end 63.421006 -17.986248)
		(width 0.15748)
		(layer "In7.Cu")
		(net "CPU_RX_PCIE_MGT0_TXN")
	)
	(arc
		(start 81.030064 -17.13484)
		(mid 80.970794 -17.11029)
		(end 80.946244 -17.05102)
		(width 0.15748)
		(layer "In7.Cu")
		(net "CPU_RX_PCIE_MGT0_TXN")
	)
	(arc
		(start 78.103984 -16.9672)
		(mid 78.044714 -16.99175)
		(end 78.020164 -17.05102)
		(width 0.15748)
		(layer "In7.Cu")
		(net "CPU_RX_PCIE_MGT0_TXN")
	)
	(arc
		(start 72.818244 -17.05102)
		(mid 72.793694 -16.99175)
		(end 72.734424 -16.9672)
		(width 0.15748)
		(layer "In7.Cu")
		(net "CPU_RX_PCIE_MGT0_TXN")
	)
	(arc
		(start 66.427604 -16.9672)
		(mid 66.369232 -16.991378)
		(end 66.345054 -17.04975)
		(width 0.15748)
		(layer "In7.Cu")
		(net "CPU_RX_PCIE_MGT0_TXN")
	)
	(arc
		(start 69.262244 -17.05102)
		(mid 69.237694 -16.99175)
		(end 69.178424 -16.9672)
		(width 0.15748)
		(layer "In7.Cu")
		(net "CPU_RX_PCIE_MGT0_TXN")
	)
	(arc
		(start 78.020164 -17.05102)
		(mid 77.995614 -17.11029)
		(end 77.936344 -17.13484)
		(width 0.15748)
		(layer "In7.Cu")
		(net "CPU_RX_PCIE_MGT0_TXN")
	)
	(arc
		(start 80.946244 -17.05102)
		(mid 80.921694 -16.99175)
		(end 80.862424 -16.9672)
		(width 0.15748)
		(layer "In7.Cu")
		(net "CPU_RX_PCIE_MGT0_TXN")
	)
	(arc
		(start 63.315088 -18.84934)
		(mid 63.368297 -19.116839)
		(end 63.519812 -19.343624)
		(width 0.15748)
		(layer "In7.Cu")
		(net "CPU_RX_PCIE_MGT0_TXN")
	)
	(arc
		(start 77.390244 -17.05102)
		(mid 77.365694 -16.99175)
		(end 77.306424 -16.9672)
		(width 0.15748)
		(layer "In7.Cu")
		(net "CPU_RX_PCIE_MGT0_TXN")
	)
	(arc
		(start 69.975984 -16.9672)
		(mid 69.916714 -16.99175)
		(end 69.892164 -17.05102)
		(width 0.15748)
		(layer "In7.Cu")
		(net "CPU_RX_PCIE_MGT0_TXN")
	)
	(arc
		(start 95.517462 -34.82975)
		(mid 95.473736 -34.838466)
		(end 95.43669 -34.863278)
		(width 0.1143)
		(layer "In7.Cu")
		(net "CPU_RX_PCIE_MGT0_TXN")
	)
	(arc
		(start 66.345054 -17.04975)
		(mid 66.320876 -17.108122)
		(end 66.262504 -17.1323)
		(width 0.15748)
		(layer "In7.Cu")
		(net "CPU_RX_PCIE_MGT0_TXN")
	)
	(arc
		(start 84.646008 -31.10738)
		(mid 84.626627 -30.993297)
		(end 84.6201 -30.877764)
		(width 0.15748)
		(layer "In7.Cu")
		(net "CPU_RX_PCIE_MGT0_TXN")
	)
	(arc
		(start 64.285368 -17.117568)
		(mid 64.219752 -17.161495)
		(end 64.1604 -17.21358)
		(width 0.15748)
		(layer "In7.Cu")
		(net "CPU_RX_PCIE_MGT0_TXN")
	)
	(arc
		(start 84.6201 -19.48688)
		(mid 83.882103 -17.705197)
		(end 82.10042 -16.9672)
		(width 0.15748)
		(layer "In7.Cu")
		(net "CPU_RX_PCIE_MGT0_TXN")
	)
	(arc
		(start 72.902064 -17.13484)
		(mid 72.842794 -17.11029)
		(end 72.818244 -17.05102)
		(width 0.15748)
		(layer "In7.Cu")
		(net "CPU_RX_PCIE_MGT0_TXN")
	)
	(arc
		(start 73.448164 -17.05102)
		(mid 73.423614 -17.11029)
		(end 73.364344 -17.13484)
		(width 0.15748)
		(layer "In7.Cu")
		(net "CPU_RX_PCIE_MGT0_TXN")
	)
	(arc
		(start 64.8462 -16.9672)
		(mid 64.555883 -17.005449)
		(end 64.285368 -17.117568)
		(width 0.15748)
		(layer "In7.Cu")
		(net "CPU_RX_PCIE_MGT0_TXN")
	)
	(arc
		(start 77.474064 -17.13484)
		(mid 77.414794 -17.11029)
		(end 77.390244 -17.05102)
		(width 0.15748)
		(layer "In7.Cu")
		(net "CPU_RX_PCIE_MGT0_TXN")
	)
	(arc
		(start 84.765134 -31.447994)
		(mid 84.695966 -31.281047)
		(end 84.646008 -31.10738)
		(width 0.15748)
		(layer "In7.Cu")
		(net "CPU_RX_PCIE_MGT0_TXN")
	)
	(arc
		(start 98.677984 -36.282884)
		(mid 98.707496 -36.238717)
		(end 98.717862 -36.186618)
		(width 0.1143)
		(layer "In7.Cu")
		(net "CPU_RX_PCIE_MGT0_TXN")
	)
	(arc
		(start 88.053672 -34.737294)
		(mid 87.938359 -34.668781)
		(end 87.835994 -34.5821)
		(width 0.15748)
		(layer "In7.Cu")
		(net "CPU_RX_PCIE_MGT0_TXN")
	)
	(arc
		(start 98.580448 -36.32327)
		(mid 98.633228 -36.312771)
		(end 98.677984 -36.282884)
		(width 0.1143)
		(layer "In7.Cu")
		(net "CPU_RX_PCIE_MGT0_TXN")
	)
	(arc
		(start 98.22688 -35.91306)
		(mid 98.020273 -35.872057)
		(end 97.845118 -35.755072)
		(width 0.1143)
		(layer "In7.Cu")
		(net "CPU_RX_PCIE_MGT0_TXN")
	)
	(arc
		(start 65.715134 -17.04975)
		(mid 65.690956 -16.991378)
		(end 65.632584 -16.9672)
		(width 0.15748)
		(layer "In7.Cu")
		(net "CPU_RX_PCIE_MGT0_TXN")
	)
	(arc
		(start 98.717862 -36.049712)
		(mid 98.678107 -35.953354)
		(end 98.581972 -35.91306)
		(width 0.1143)
		(layer "In7.Cu")
		(net "CPU_RX_PCIE_MGT0_TXN")
	)
	(arc
		(start 63.421006 -17.986248)
		(mid 63.341931 -18.194172)
		(end 63.315088 -18.415)
		(width 0.15748)
		(layer "In7.Cu")
		(net "CPU_RX_PCIE_MGT0_TXN")
	)
	(segment
		(start 61.849 -12.3571)
		(end 61.849 -15.0368)
		(width 0.11938)
		(layer "F.Cu")
		(net "CARD_PRESENT")
	)
	(segment
		(start 62.7126 -15.9004)
		(end 63.784988 -15.9004)
		(width 0.11938)
		(layer "F.Cu")
		(net "CARD_PRESENT")
	)
	(segment
		(start 61.849 -15.0368)
		(end 62.7126 -15.9004)
		(width 0.11938)
		(layer "F.Cu")
		(net "CARD_PRESENT")
	)
	(via
		(at 61.849 -12.3571)
		(size 0.4572)
		(drill 0.2032)
		(layers "F.Cu" "B.Cu")
		(net "CARD_PRESENT")
	)
	(via
		(at 47.9806 -13.95984)
		(size 0.508)
		(drill 0.254)
		(layers "F.Cu" "B.Cu")
		(net "CARD_PRESENT")
	)
	(segment
		(start 47.36084 -15.29588)
		(end 47.36084 -12.485624)
		(width 0.11938)
		(layer "B.Cu")
		(net "CARD_PRESENT")
	)
	(segment
		(start 47.9806 -15.1765)
		(end 47.9806 -13.95984)
		(width 0.11938)
		(layer "B.Cu")
		(net "CARD_PRESENT")
	)
	(segment
		(start 45.649896 -10.77468)
		(end 45.649896 -3.995674)
		(width 0.11938)
		(layer "B.Cu")
		(net "CARD_PRESENT")
	)
	(segment
		(start 47.36084 -12.485624)
		(end 45.649896 -10.77468)
		(width 0.11938)
		(layer "B.Cu")
		(net "CARD_PRESENT")
	)
	(segment
		(start 47.86122 -15.29588)
		(end 47.9806 -15.1765)
		(width 0.11938)
		(layer "B.Cu")
		(net "CARD_PRESENT")
	)
	(segment
		(start 47.36084 -15.29588)
		(end 47.86122 -15.29588)
		(width 0.11938)
		(layer "B.Cu")
		(net "CARD_PRESENT")
	)
	(segment
		(start 50.63744 -11.303)
		(end 59.817 -11.303)
		(width 0.127)
		(layer "In7.Cu")
		(net "CARD_PRESENT")
	)
	(segment
		(start 60.8711 -12.3571)
		(end 61.849 -12.3571)
		(width 0.127)
		(layer "In7.Cu")
		(net "CARD_PRESENT")
	)
	(segment
		(start 47.9806 -13.95984)
		(end 50.63744 -11.303)
		(width 0.127)
		(layer "In7.Cu")
		(net "CARD_PRESENT")
	)
	(segment
		(start 59.817 -11.303)
		(end 60.8711 -12.3571)
		(width 0.127)
		(layer "In7.Cu")
		(net "CARD_PRESENT")
	)
	(segment
		(start 78.5622 -85.598)
		(end 78.140306 -85.176106)
		(width 0.11938)
		(layer "F.Cu")
		(net "BNO080_I2C_SDA")
	)
	(segment
		(start 84.22259 -79.60741)
		(end 84.22259 -79.776066)
		(width 0.11938)
		(layer "F.Cu")
		(net "BNO080_I2C_SDA")
	)
	(segment
		(start 85.979 -76.327)
		(end 85.725 -76.581)
		(width 0.11938)
		(layer "F.Cu")
		(net "BNO080_I2C_SDA")
	)
	(segment
		(start 80.137 -84.708746)
		(end 79.247746 -85.598)
		(width 0.11938)
		(layer "F.Cu")
		(net "BNO080_I2C_SDA")
	)
	(segment
		(start 84.56168 -80.115156)
		(end 84.56168 -80.283812)
		(width 0.11938)
		(layer "F.Cu")
		(net "BNO080_I2C_SDA")
	)
	(segment
		(start 81.4705 -80.4545)
		(end 80.137 -81.788)
		(width 0.11938)
		(layer "F.Cu")
		(net "BNO080_I2C_SDA")
	)
	(segment
		(start 89.9668 -76.327)
		(end 85.979 -76.327)
		(width 0.11938)
		(layer "F.Cu")
		(net "BNO080_I2C_SDA")
	)
	(segment
		(start 80.137 -81.788)
		(end 80.137 -84.708746)
		(width 0.11938)
		(layer "F.Cu")
		(net "BNO080_I2C_SDA")
	)
	(segment
		(start 85.725 -76.581)
		(end 85.725 -78.105)
		(width 0.11938)
		(layer "F.Cu")
		(net "BNO080_I2C_SDA")
	)
	(segment
		(start 83.610196 -80.219804)
		(end 83.3755 -80.4545)
		(width 0.11938)
		(layer "F.Cu")
		(net "BNO080_I2C_SDA")
	)
	(segment
		(start 84.117942 -80.558894)
		(end 83.778852 -80.219804)
		(width 0.11938)
		(layer "F.Cu")
		(net "BNO080_I2C_SDA")
	)
	(segment
		(start 85.725 -78.105)
		(end 84.22259 -79.60741)
		(width 0.11938)
		(layer "F.Cu")
		(net "BNO080_I2C_SDA")
	)
	(segment
		(start 83.3755 -80.4545)
		(end 81.4705 -80.4545)
		(width 0.11938)
		(layer "F.Cu")
		(net "BNO080_I2C_SDA")
	)
	(segment
		(start 79.247746 -85.598)
		(end 78.5622 -85.598)
		(width 0.11938)
		(layer "F.Cu")
		(net "BNO080_I2C_SDA")
	)
	(segment
		(start 84.286598 -80.558894)
		(end 84.117942 -80.558894)
		(width 0.11938)
		(layer "F.Cu")
		(net "BNO080_I2C_SDA")
	)
	(segment
		(start 84.22259 -79.776066)
		(end 84.56168 -80.115156)
		(width 0.11938)
		(layer "F.Cu")
		(net "BNO080_I2C_SDA")
	)
	(segment
		(start 78.140306 -85.176106)
		(end 77.2795 -85.176106)
		(width 0.11938)
		(layer "F.Cu")
		(net "BNO080_I2C_SDA")
	)
	(segment
		(start 83.778852 -80.219804)
		(end 83.610196 -80.219804)
		(width 0.11938)
		(layer "F.Cu")
		(net "BNO080_I2C_SDA")
	)
	(segment
		(start 84.56168 -80.283812)
		(end 84.286598 -80.558894)
		(width 0.11938)
		(layer "F.Cu")
		(net "BNO080_I2C_SDA")
	)
	(segment
		(start 90.424 -76.7842)
		(end 89.9668 -76.327)
		(width 0.11938)
		(layer "F.Cu")
		(net "BNO080_I2C_SDA")
	)
	(via
		(at 90.424 -76.7842)
		(size 0.508)
		(drill 0.254)
		(layers "F.Cu" "B.Cu")
		(net "BNO080_I2C_SDA")
	)
	(segment
		(start 85.471 -59.054746)
		(end 85.471 -61.153548)
		(width 0.11938)
		(layer "B.Cu")
		(net "BNO080_I2C_SDA")
	)
	(segment
		(start 87.098124 -64.069214)
		(end 87.098124 -64.23787)
		(width 0.11938)
		(layer "B.Cu")
		(net "BNO080_I2C_SDA")
	)
	(segment
		(start 87.86749 -57.31891)
		(end 87.86749 -57.91962)
		(width 0.11938)
		(layer "B.Cu")
		(net "BNO080_I2C_SDA")
	)
	(segment
		(start 89.789 -74.676)
		(end 89.789 -76.1492)
		(width 0.11938)
		(layer "B.Cu")
		(net "BNO080_I2C_SDA")
	)
	(segment
		(start 86.039452 -61.722)
		(end 87.494618 -61.722)
		(width 0.11938)
		(layer "B.Cu")
		(net "BNO080_I2C_SDA")
	)
	(segment
		(start 88.38565 -62.781688)
		(end 87.098124 -64.069214)
		(width 0.11938)
		(layer "B.Cu")
		(net "BNO080_I2C_SDA")
	)
	(segment
		(start 90.160602 -64.55664)
		(end 89.635076 -65.082166)
		(width 0.11938)
		(layer "B.Cu")
		(net "BNO080_I2C_SDA")
	)
	(segment
		(start 87.098124 -64.23787)
		(end 87.373206 -64.512952)
		(width 0.11938)
		(layer "B.Cu")
		(net "BNO080_I2C_SDA")
	)
	(segment
		(start 89.635076 -65.082166)
		(end 89.635076 -65.250822)
		(width 0.11938)
		(layer "B.Cu")
		(net "BNO080_I2C_SDA")
	)
	(segment
		(start 89.716864 -64.112902)
		(end 89.88552 -64.112902)
		(width 0.11938)
		(layer "B.Cu")
		(net "BNO080_I2C_SDA")
	)
	(segment
		(start 87.9094 -57.277)
		(end 87.9094 -56.134)
		(width 0.11938)
		(layer "B.Cu")
		(net "BNO080_I2C_SDA")
	)
	(segment
		(start 85.471 -61.153548)
		(end 86.039452 -61.722)
		(width 0.11938)
		(layer "B.Cu")
		(net "BNO080_I2C_SDA")
	)
	(segment
		(start 87.541862 -64.512952)
		(end 88.829388 -63.225426)
		(width 0.11938)
		(layer "B.Cu")
		(net "BNO080_I2C_SDA")
	)
	(segment
		(start 88.429338 -65.400428)
		(end 89.716864 -64.112902)
		(width 0.11938)
		(layer "B.Cu")
		(net "BNO080_I2C_SDA")
	)
	(segment
		(start 88.829388 -63.225426)
		(end 88.998044 -63.225426)
		(width 0.11938)
		(layer "B.Cu")
		(net "BNO080_I2C_SDA")
	)
	(segment
		(start 89.88552 -64.112902)
		(end 90.160602 -64.387984)
		(width 0.11938)
		(layer "B.Cu")
		(net "BNO080_I2C_SDA")
	)
	(segment
		(start 87.373206 -64.512952)
		(end 87.541862 -64.512952)
		(width 0.11938)
		(layer "B.Cu")
		(net "BNO080_I2C_SDA")
	)
	(segment
		(start 91.70289 -67.654678)
		(end 91.70289 -69.471032)
		(width 0.11938)
		(layer "B.Cu")
		(net "BNO080_I2C_SDA")
	)
	(segment
		(start 90.160602 -64.387984)
		(end 90.160602 -64.55664)
		(width 0.11938)
		(layer "B.Cu")
		(net "BNO080_I2C_SDA")
	)
	(segment
		(start 91.88958 -67.467988)
		(end 91.70289 -67.654678)
		(width 0.11938)
		(layer "B.Cu")
		(net "BNO080_I2C_SDA")
	)
	(segment
		(start 87.9856 -64.95669)
		(end 87.9856 -65.125346)
		(width 0.11938)
		(layer "B.Cu")
		(net "BNO080_I2C_SDA")
	)
	(segment
		(start 89.273126 -63.669164)
		(end 87.9856 -64.95669)
		(width 0.11938)
		(layer "B.Cu")
		(net "BNO080_I2C_SDA")
	)
	(segment
		(start 89.789 -76.1492)
		(end 90.424 -76.7842)
		(width 0.11938)
		(layer "B.Cu")
		(net "BNO080_I2C_SDA")
	)
	(segment
		(start 88.998044 -63.225426)
		(end 89.273126 -63.500508)
		(width 0.11938)
		(layer "B.Cu")
		(net "BNO080_I2C_SDA")
	)
	(segment
		(start 86.486746 -58.039)
		(end 85.471 -59.054746)
		(width 0.11938)
		(layer "B.Cu")
		(net "BNO080_I2C_SDA")
	)
	(segment
		(start 90.078814 -65.525904)
		(end 90.60434 -65.000378)
		(width 0.11938)
		(layer "B.Cu")
		(net "BNO080_I2C_SDA")
	)
	(segment
		(start 87.9856 -65.125346)
		(end 88.260682 -65.400428)
		(width 0.11938)
		(layer "B.Cu")
		(net "BNO080_I2C_SDA")
	)
	(segment
		(start 89.910158 -65.525904)
		(end 90.078814 -65.525904)
		(width 0.11938)
		(layer "B.Cu")
		(net "BNO080_I2C_SDA")
	)
	(segment
		(start 88.38565 -62.613032)
		(end 88.38565 -62.781688)
		(width 0.11938)
		(layer "B.Cu")
		(net "BNO080_I2C_SDA")
	)
	(segment
		(start 90.772996 -65.000378)
		(end 91.88958 -66.116962)
		(width 0.11938)
		(layer "B.Cu")
		(net "BNO080_I2C_SDA")
	)
	(segment
		(start 90.60434 -65.000378)
		(end 90.772996 -65.000378)
		(width 0.11938)
		(layer "B.Cu")
		(net "BNO080_I2C_SDA")
	)
	(segment
		(start 87.86749 -57.91962)
		(end 87.74811 -58.039)
		(width 0.11938)
		(layer "B.Cu")
		(net "BNO080_I2C_SDA")
	)
	(segment
		(start 89.273126 -63.500508)
		(end 89.273126 -63.669164)
		(width 0.11938)
		(layer "B.Cu")
		(net "BNO080_I2C_SDA")
	)
	(segment
		(start 89.57691 -74.46391)
		(end 89.789 -74.676)
		(width 0.11938)
		(layer "B.Cu")
		(net "BNO080_I2C_SDA")
	)
	(segment
		(start 87.9094 -57.277)
		(end 87.86749 -57.31891)
		(width 0.11938)
		(layer "B.Cu")
		(net "BNO080_I2C_SDA")
	)
	(segment
		(start 87.74811 -58.039)
		(end 86.486746 -58.039)
		(width 0.11938)
		(layer "B.Cu")
		(net "BNO080_I2C_SDA")
	)
	(segment
		(start 89.57691 -71.597012)
		(end 89.57691 -74.46391)
		(width 0.11938)
		(layer "B.Cu")
		(net "BNO080_I2C_SDA")
	)
	(segment
		(start 91.88958 -66.116962)
		(end 91.88958 -67.467988)
		(width 0.11938)
		(layer "B.Cu")
		(net "BNO080_I2C_SDA")
	)
	(segment
		(start 91.70289 -69.471032)
		(end 89.57691 -71.597012)
		(width 0.11938)
		(layer "B.Cu")
		(net "BNO080_I2C_SDA")
	)
	(segment
		(start 89.635076 -65.250822)
		(end 89.910158 -65.525904)
		(width 0.11938)
		(layer "B.Cu")
		(net "BNO080_I2C_SDA")
	)
	(segment
		(start 87.494618 -61.722)
		(end 88.38565 -62.613032)
		(width 0.11938)
		(layer "B.Cu")
		(net "BNO080_I2C_SDA")
	)
	(segment
		(start 88.260682 -65.400428)
		(end 88.429338 -65.400428)
		(width 0.11938)
		(layer "B.Cu")
		(net "BNO080_I2C_SDA")
	)
	(segment
		(start 79.5274 -81.6356)
		(end 79.5274 -84.201)
		(width 0.11938)
		(layer "F.Cu")
		(net "BNO080_I2C_SCL")
	)
	(segment
		(start 81.153 -80.01)
		(end 79.5274 -81.6356)
		(width 0.11938)
		(layer "F.Cu")
		(net "BNO080_I2C_SCL")
	)
	(segment
		(start 85.979 -75.692)
		(end 85.217 -76.454)
		(width 0.11938)
		(layer "F.Cu")
		(net "BNO080_I2C_SCL")
	)
	(segment
		(start 83.185 -80.01)
		(end 81.153 -80.01)
		(width 0.11938)
		(layer "F.Cu")
		(net "BNO080_I2C_SCL")
	)
	(segment
		(start 90.678 -75.057)
		(end 90.043 -75.692)
		(width 0.11938)
		(layer "F.Cu")
		(net "BNO080_I2C_SCL")
	)
	(segment
		(start 79.20228 -84.52612)
		(end 77.2795 -84.52612)
		(width 0.11938)
		(layer "F.Cu")
		(net "BNO080_I2C_SCL")
	)
	(segment
		(start 79.5274 -84.201)
		(end 79.20228 -84.52612)
		(width 0.11938)
		(layer "F.Cu")
		(net "BNO080_I2C_SCL")
	)
	(segment
		(start 85.217 -77.978)
		(end 83.185 -80.01)
		(width 0.11938)
		(layer "F.Cu")
		(net "BNO080_I2C_SCL")
	)
	(segment
		(start 90.043 -75.692)
		(end 85.979 -75.692)
		(width 0.11938)
		(layer "F.Cu")
		(net "BNO080_I2C_SCL")
	)
	(segment
		(start 85.217 -76.454)
		(end 85.217 -77.978)
		(width 0.11938)
		(layer "F.Cu")
		(net "BNO080_I2C_SCL")
	)
	(via
		(at 90.678 -75.057)
		(size 0.508)
		(drill 0.254)
		(layers "F.Cu" "B.Cu")
		(net "BNO080_I2C_SCL")
	)
	(segment
		(start 90.678 -71.11746)
		(end 90.678 -75.057)
		(width 0.11938)
		(layer "B.Cu")
		(net "BNO080_I2C_SCL")
	)
	(segment
		(start 88.68791 -57.743344)
		(end 87.884254 -58.547)
		(width 0.11938)
		(layer "B.Cu")
		(net "BNO080_I2C_SCL")
	)
	(segment
		(start 92.14231 -69.65315)
		(end 90.678 -71.11746)
		(width 0.11938)
		(layer "B.Cu")
		(net "BNO080_I2C_SCL")
	)
	(segment
		(start 83.64601 -54.582314)
		(end 83.64601 -53.901086)
		(width 0.11938)
		(layer "B.Cu")
		(net "BNO080_I2C_SCL")
	)
	(segment
		(start 84.127086 -53.42001)
		(end 84.808314 -53.42001)
		(width 0.11938)
		(layer "B.Cu")
		(net "BNO080_I2C_SCL")
	)
	(segment
		(start 84.5566 -56.134)
		(end 84.5566 -57.277)
		(width 0.11938)
		(layer "B.Cu")
		(net "BNO080_I2C_SCL")
	)
	(segment
		(start 92.329 -67.650106)
		(end 92.14231 -67.836796)
		(width 0.11938)
		(layer "B.Cu")
		(net "BNO080_I2C_SCL")
	)
	(segment
		(start 92.14231 -67.836796)
		(end 92.14231 -69.65315)
		(width 0.11938)
		(layer "B.Cu")
		(net "BNO080_I2C_SCL")
	)
	(segment
		(start 85.979 -60.452)
		(end 86.741 -61.214)
		(width 0.11938)
		(layer "B.Cu")
		(net "BNO080_I2C_SCL")
	)
	(segment
		(start 88.68791 -53.997606)
		(end 88.68791 -57.743344)
		(width 0.11938)
		(layer "B.Cu")
		(net "BNO080_I2C_SCL")
	)
	(segment
		(start 83.64601 -53.901086)
		(end 84.127086 -53.42001)
		(width 0.11938)
		(layer "B.Cu")
		(net "BNO080_I2C_SCL")
	)
	(segment
		(start 87.608156 -61.214)
		(end 92.329 -65.934844)
		(width 0.11938)
		(layer "B.Cu")
		(net "BNO080_I2C_SCL")
	)
	(segment
		(start 85.202014 -53.02631)
		(end 87.716614 -53.02631)
		(width 0.11938)
		(layer "B.Cu")
		(net "BNO080_I2C_SCL")
	)
	(segment
		(start 84.5566 -56.134)
		(end 84.5566 -55.492904)
		(width 0.11938)
		(layer "B.Cu")
		(net "BNO080_I2C_SCL")
	)
	(segment
		(start 87.716614 -53.02631)
		(end 88.68791 -53.997606)
		(width 0.11938)
		(layer "B.Cu")
		(net "BNO080_I2C_SCL")
	)
	(segment
		(start 87.884254 -58.547)
		(end 86.614 -58.547)
		(width 0.11938)
		(layer "B.Cu")
		(net "BNO080_I2C_SCL")
	)
	(segment
		(start 84.808314 -53.42001)
		(end 85.202014 -53.02631)
		(width 0.11938)
		(layer "B.Cu")
		(net "BNO080_I2C_SCL")
	)
	(segment
		(start 92.329 -65.934844)
		(end 92.329 -67.650106)
		(width 0.11938)
		(layer "B.Cu")
		(net "BNO080_I2C_SCL")
	)
	(segment
		(start 86.741 -61.214)
		(end 87.608156 -61.214)
		(width 0.11938)
		(layer "B.Cu")
		(net "BNO080_I2C_SCL")
	)
	(segment
		(start 85.979 -59.182)
		(end 85.979 -60.452)
		(width 0.11938)
		(layer "B.Cu")
		(net "BNO080_I2C_SCL")
	)
	(segment
		(start 84.5566 -55.492904)
		(end 83.64601 -54.582314)
		(width 0.11938)
		(layer "B.Cu")
		(net "BNO080_I2C_SCL")
	)
	(segment
		(start 86.614 -58.547)
		(end 85.979 -59.182)
		(width 0.11938)
		(layer "B.Cu")
		(net "BNO080_I2C_SCL")
	)
	(segment
		(start 79.439262 -18.161)
		(end 77.2668 -15.988538)
		(width 0.11938)
		(layer "F.Cu")
		(net "BF_PCIE_PERST_N")
	)
	(segment
		(start 77.2668 -15.988538)
		(end 77.2668 -14.654276)
		(width 0.11938)
		(layer "F.Cu")
		(net "BF_PCIE_PERST_N")
	)
	(segment
		(start 77.2668 -14.654276)
		(end 76.584048 -13.971524)
		(width 0.11938)
		(layer "F.Cu")
		(net "BF_PCIE_PERST_N")
	)
	(segment
		(start 90.678 -18.161)
		(end 79.439262 -18.161)
		(width 0.11938)
		(layer "F.Cu")
		(net "BF_PCIE_PERST_N")
	)
	(segment
		(start 127 -18.415254)
		(end 125.729746 -17.145)
		(width 0.11938)
		(layer "F.Cu")
		(net "BF_PCIE_PERST_N")
	)
	(segment
		(start 119.507 -16.637)
		(end 92.202 -16.637)
		(width 0.11938)
		(layer "F.Cu")
		(net "BF_PCIE_PERST_N")
	)
	(segment
		(start 127 -24.508206)
		(end 127 -18.415254)
		(width 0.11938)
		(layer "F.Cu")
		(net "BF_PCIE_PERST_N")
	)
	(segment
		(start 75.0316 -13.9954)
		(end 75.0316 -14.590014)
		(width 0.11938)
		(layer "F.Cu")
		(net "BF_PCIE_PERST_N")
	)
	(segment
		(start 75.055476 -13.971524)
		(end 75.0316 -13.9954)
		(width 0.11938)
		(layer "F.Cu")
		(net "BF_PCIE_PERST_N")
	)
	(segment
		(start 72.3392 -14.717014)
		(end 74.9046 -14.717014)
		(width 0.11938)
		(layer "F.Cu")
		(net "BF_PCIE_PERST_N")
	)
	(segment
		(start 125.222254 -52.578)
		(end 125.1204 -52.578)
		(width 0.11938)
		(layer "F.Cu")
		(net "BF_PCIE_PERST_N")
	)
	(segment
		(start 74.9046 -14.717014)
		(end 75.0316 -14.590014)
		(width 0.11938)
		(layer "F.Cu")
		(net "BF_PCIE_PERST_N")
	)
	(segment
		(start 127.76327 -25.271476)
		(end 127 -24.508206)
		(width 0.11938)
		(layer "F.Cu")
		(net "BF_PCIE_PERST_N")
	)
	(segment
		(start 125.729746 -17.145)
		(end 120.015 -17.145)
		(width 0.11938)
		(layer "F.Cu")
		(net "BF_PCIE_PERST_N")
	)
	(segment
		(start 126.238 -53.593746)
		(end 125.222254 -52.578)
		(width 0.11938)
		(layer "F.Cu")
		(net "BF_PCIE_PERST_N")
	)
	(segment
		(start 126.365 -54.356)
		(end 126.238 -54.229)
		(width 0.11938)
		(layer "F.Cu")
		(net "BF_PCIE_PERST_N")
	)
	(segment
		(start 92.202 -16.637)
		(end 90.678 -18.161)
		(width 0.11938)
		(layer "F.Cu")
		(net "BF_PCIE_PERST_N")
	)
	(segment
		(start 126.238 -54.229)
		(end 126.238 -53.593746)
		(width 0.11938)
		(layer "F.Cu")
		(net "BF_PCIE_PERST_N")
	)
	(segment
		(start 76.584048 -13.971524)
		(end 75.055476 -13.971524)
		(width 0.11938)
		(layer "F.Cu")
		(net "BF_PCIE_PERST_N")
	)
	(segment
		(start 120.015 -17.145)
		(end 119.507 -16.637)
		(width 0.11938)
		(layer "F.Cu")
		(net "BF_PCIE_PERST_N")
	)
	(via
		(at 127.76327 -25.271476)
		(size 0.508)
		(drill 0.254)
		(layers "F.Cu" "B.Cu")
		(net "BF_PCIE_PERST_N")
	)
	(via
		(at 126.365 -54.356)
		(size 0.508)
		(drill 0.254)
		(layers "F.Cu" "B.Cu")
		(net "BF_PCIE_PERST_N")
	)
	(segment
		(start 129.921 -44.45)
		(end 129.59842 -44.12742)
		(width 0.11938)
		(layer "B.Cu")
		(net "BF_PCIE_PERST_N")
	)
	(segment
		(start 130.41884 -49.386236)
		(end 130.41884 -44.961302)
		(width 0.11938)
		(layer "B.Cu")
		(net "BF_PCIE_PERST_N")
	)
	(segment
		(start 129.59842 -30.988254)
		(end 127.76327 -29.153104)
		(width 0.11938)
		(layer "B.Cu")
		(net "BF_PCIE_PERST_N")
	)
	(segment
		(start 130.41884 -44.961302)
		(end 129.921 -44.463462)
		(width 0.11938)
		(layer "B.Cu")
		(net "BF_PCIE_PERST_N")
	)
	(segment
		(start 127.56642 -52.238656)
		(end 130.41884 -49.386236)
		(width 0.11938)
		(layer "B.Cu")
		(net "BF_PCIE_PERST_N")
	)
	(segment
		(start 127.76327 -29.153104)
		(end 127.76327 -25.271476)
		(width 0.11938)
		(layer "B.Cu")
		(net "BF_PCIE_PERST_N")
	)
	(segment
		(start 126.365 -54.356)
		(end 127.56642 -53.15458)
		(width 0.11938)
		(layer "B.Cu")
		(net "BF_PCIE_PERST_N")
	)
	(segment
		(start 129.921 -44.463462)
		(end 129.921 -44.45)
		(width 0.11938)
		(layer "B.Cu")
		(net "BF_PCIE_PERST_N")
	)
	(segment
		(start 129.59842 -44.12742)
		(end 129.59842 -30.988254)
		(width 0.11938)
		(layer "B.Cu")
		(net "BF_PCIE_PERST_N")
	)
	(segment
		(start 127.56642 -53.15458)
		(end 127.56642 -52.238656)
		(width 0.11938)
		(layer "B.Cu")
		(net "BF_PCIE_PERST_N")
	)
	(zone
		(layer "F.Cu")
		(hatch none 0.5)
		(connect_pads
			(clearance 0)
		)
		(min_thickness 0.25)
		(keepout
			(tracks allowed)
			(vias allowed)
			(pads allowed)
			(copperpour allowed)
			(footprints not_allowed)
		)
		(placement
			(enabled no)
			(sheetname "")
		)
		(fill
			(thermal_gap 0.5)
			(thermal_bridge_width 0.5)
			(island_removal_mode 0)
		)
		(polygon
			(pts
				(xy 35.66795 -91.157806) (xy 35.66795 -83.638898) (xy 20.195286 -72.404478) (xy 20.195286 -80.718406)
			)
		)
	)
	(zone
		(net "XP1R8V_FPGA")
		(layer "F.Cu")
		(hatch none 0.5)
		(connect_pads
			(clearance 0.5)
		)
		(min_thickness 0.25)
		(fill yes
			(thermal_gap 0.5)
			(thermal_bridge_width 0.5)
			(island_removal_mode 0)
		)
		(polygon
			(pts
				(xy 25.2603 -67.2719) (xy 23.9395 -67.2719) (xy 23.8252 -67.1576) (xy 23.8252 -66.0146) (xy 23.8252 -65.1002)
				(xy 23.9522 -64.9732) (xy 25.2222 -64.9732) (xy 25.4254 -65.1764) (xy 25.4254 -67.1068)
			)
		)
	)
	(zone
		(net "XP1R0V_FPGA_VCCINT")
		(layer "F.Cu")
		(hatch none 0.5)
		(connect_pads
			(clearance 0.5)
		)
		(min_thickness 0.25)
		(fill yes
			(thermal_gap 0.5)
			(thermal_bridge_width 0.5)
			(island_removal_mode 0)
		)
		(polygon
			(pts
				(xy 131.064 -44.831) (xy 129.921 -44.831) (xy 129.794 -44.704) (xy 129.794 -41.021) (xy 130.048 -40.767)
				(xy 130.048 -36.703) (xy 130.048 -31.496) (xy 130.683 -30.861) (xy 132.588 -30.861) (xy 132.588 -32.385)
				(xy 132.461 -32.512) (xy 132.461 -36.068) (xy 132.461 -41.783) (xy 131.699 -42.545) (xy 131.699 -44.831)
			)
		)
	)
	(zone
		(layer "F.Cu")
		(hatch none 0.5)
		(connect_pads
			(clearance 0)
		)
		(min_thickness 0.25)
		(keepout
			(tracks allowed)
			(vias allowed)
			(pads allowed)
			(copperpour allowed)
			(footprints allowed)
		)
		(placement
			(enabled no)
			(sheetname "")
		)
		(fill
			(thermal_gap 0.5)
			(thermal_bridge_width 0.5)
			(island_removal_mode 0)
		)
		(polygon
			(pts
				(xy 39.751 -78.613) (xy 39.751 -76.835) (xy 38.608 -76.835) (xy 38.481 -76.708) (xy 38.481 -74.295)
				(xy 43.7896 -74.295) (xy 44.5643 -75.0697) (xy 45.0977 -75.6031) (xy 45.0977 -77.8129) (xy 44.2976 -78.613)
			)
		)
	)
	(zone
		(layer "F.Cu")
		(hatch none 0.5)
		(connect_pads
			(clearance 0)
		)
		(min_thickness 0.25)
		(keepout
			(tracks allowed)
			(vias allowed)
			(pads allowed)
			(copperpour allowed)
			(footprints allowed)
		)
		(placement
			(enabled no)
			(sheetname "")
		)
		(fill
			(thermal_gap 0.5)
			(thermal_bridge_width 0.5)
			(island_removal_mode 0)
		)
		(polygon
			(pts
				(xy 138.3284 -15.7988) (xy 138.7094 -15.7988) (xy 138.7094 -16.637) (xy 138.3284 -16.637)
			)
		)
	)
	(zone
		(layer "F.Cu")
		(hatch none 0.5)
		(connect_pads
			(clearance 0)
		)
		(min_thickness 0.25)
		(keepout
			(tracks allowed)
			(vias allowed)
			(pads allowed)
			(copperpour allowed)
			(footprints allowed)
		)
		(placement
			(enabled no)
			(sheetname "")
		)
		(fill
			(thermal_gap 0.5)
			(thermal_bridge_width 0.5)
			(island_removal_mode 0)
		)
		(polygon
			(pts
				(xy 84.963 -60.579) (xy 87.122 -60.579) (xy 87.122 -61.849) (xy 87.122 -62.103) (xy 84.582 -62.103)
				(xy 84.582 -60.579)
			)
		)
	)
	(zone
		(net "XP3R3V")
		(layer "F.Cu")
		(hatch none 0.5)
		(connect_pads
			(clearance 0.5)
		)
		(min_thickness 0.25)
		(fill yes
			(thermal_gap 0.5)
			(thermal_bridge_width 0.5)
			(island_removal_mode 0)
		)
		(polygon
			(pts
				(xy 143.002 -24.765) (xy 145.161 -24.765) (xy 145.161 -26.162) (xy 144.907 -26.416) (xy 143.129 -26.416)
				(xy 141.351 -26.416) (xy 141.097 -26.162) (xy 141.097 -24.765)
			)
		)
	)
	(zone
		(net "SG")
		(layer "F.Cu")
		(hatch none 0.5)
		(connect_pads
			(clearance 0.5)
		)
		(min_thickness 0.25)
		(fill yes
			(thermal_gap 0.5)
			(thermal_bridge_width 0.5)
			(island_removal_mode 0)
		)
		(polygon
			(pts
				(xy 119.126 -66.2432) (xy 121.6152 -66.2432) (xy 121.793 -66.0654) (xy 121.793 -63.9826) (xy 121.6406 -63.8302)
				(xy 119.0498 -63.8302) (xy 118.9482 -63.9318) (xy 118.9482 -66.0654)
			)
		)
	)
	(zone
		(layer "F.Cu")
		(hatch none 0.5)
		(connect_pads
			(clearance 0)
		)
		(min_thickness 0.25)
		(keepout
			(tracks allowed)
			(vias allowed)
			(pads allowed)
			(copperpour allowed)
			(footprints allowed)
		)
		(placement
			(enabled no)
			(sheetname "")
		)
		(fill
			(thermal_gap 0.5)
			(thermal_bridge_width 0.5)
			(island_removal_mode 0)
		)
		(polygon
			(pts
				(xy 21.1328 -78.0796) (xy 31.6992 -78.0796) (xy 35.5346 -78.0796) (xy 35.687 -78.232) (xy 35.687 -91.059)
				(xy 35.179 -91.567) (xy 22.733 -91.567) (xy 21.1328 -89.9668) (xy 21.1328 -84.8614) (xy 21.1328 -83.7438)
			)
		)
	)
	(zone
		(net "SG")
		(layer "F.Cu")
		(hatch none 0.5)
		(connect_pads
			(clearance 0.5)
		)
		(min_thickness 0.25)
		(fill yes
			(thermal_gap 0.5)
			(thermal_bridge_width 0.5)
			(island_removal_mode 0)
		)
		(polygon
			(pts
				(xy 90.551 -63.881) (xy 90.551 -62.738) (xy 90.424 -62.611) (xy 89.916 -62.611) (xy 89.789 -62.738)
				(xy 89.789 -64.008) (xy 90.424 -64.008)
			)
		)
	)
	(zone
		(net "SG")
		(layer "F.Cu")
		(hatch none 0.5)
		(connect_pads
			(clearance 0.5)
		)
		(min_thickness 0.25)
		(fill yes
			(thermal_gap 0.5)
			(thermal_bridge_width 0.5)
			(island_removal_mode 0)
		)
		(polygon
			(pts
				(xy 135.7884 -56.9722) (xy 135.7884 -55.626) (xy 135.7122 -55.5498) (xy 134.366 -55.5498) (xy 134.2644 -55.6514)
				(xy 134.2644 -56.9722) (xy 134.3406 -57.0484) (xy 135.7122 -57.0484)
			)
		)
	)
	(zone
		(net "XP3R3V")
		(layer "F.Cu")
		(hatch none 0.5)
		(connect_pads
			(clearance 0.5)
		)
		(min_thickness 0.25)
		(fill yes
			(thermal_gap 0.5)
			(thermal_bridge_width 0.5)
			(island_removal_mode 0)
		)
		(polygon
			(pts
				(xy 109.982 -74.6506) (xy 111.4552 -74.6506) (xy 111.5568 -74.549) (xy 111.5568 -73.1012) (xy 111.5568 -72.5678)
				(xy 111.506 -72.517) (xy 111.506 -72.263) (xy 111.506 -71.501) (xy 111.887 -71.12) (xy 113.665 -71.12)
				(xy 113.919 -70.866) (xy 113.919 -69.215) (xy 112.395 -69.215) (xy 112.141 -69.469) (xy 109.8804 -69.469)
				(xy 109.7534 -69.596) (xy 109.7534 -71.501) (xy 109.7534 -74.422)
			)
		)
	)
	(zone
		(layer "F.Cu")
		(hatch none 0.5)
		(connect_pads
			(clearance 0)
		)
		(min_thickness 0.25)
		(keepout
			(tracks allowed)
			(vias allowed)
			(pads allowed)
			(copperpour allowed)
			(footprints allowed)
		)
		(placement
			(enabled no)
			(sheetname "")
		)
		(fill
			(thermal_gap 0.5)
			(thermal_bridge_width 0.5)
			(island_removal_mode 0)
		)
		(polygon
			(pts
				(xy 83.82 -57.404) (xy 83.82 -56.896) (xy 84.836 -56.896) (xy 84.836 -57.404)
			)
		)
	)
	(zone
		(net "SG")
		(layer "F.Cu")
		(hatch none 0.5)
		(connect_pads
			(clearance 0.5)
		)
		(min_thickness 0.25)
		(fill yes
			(thermal_gap 0.5)
			(thermal_bridge_width 0.5)
			(island_removal_mode 0)
		)
		(polygon
			(pts
				(xy 92.5068 -107.6452) (xy 92.5068 -106.0704) (xy 92.4052 -105.9688) (xy 91.2622 -105.9688) (xy 91.1352 -106.0958)
				(xy 91.1352 -107.6198) (xy 91.2622 -107.7468) (xy 92.4052 -107.7468)
			)
		)
	)
	(zone
		(layer "F.Cu")
		(hatch none 0.5)
		(connect_pads
			(clearance 0)
		)
		(min_thickness 0.25)
		(keepout
			(tracks not_allowed)
			(vias allowed)
			(pads allowed)
			(copperpour not_allowed)
			(footprints allowed)
		)
		(placement
			(enabled no)
			(sheetname "")
		)
		(fill
			(thermal_gap 0.5)
			(thermal_bridge_width 0.5)
			(island_removal_mode 0)
		)
		(polygon
			(pts
				(xy 0.999998 -13.750036) (xy 44.99991 -13.750036)
				(arc
					(start 44.99991 -10.925048)
					(mid 43.17492 -12.750038)
					(end 41.34993 -10.925048)
				)
				(arc
					(start 41.34993 -5.500116)
					(mid 41.057037 -4.793011)
					(end 40.349932 -4.500118)
				)
				(arc
					(start 34.349944 -4.500118)
					(mid 33.642839 -4.793011)
					(end 33.349946 -5.500116)
				)
				(arc
					(start 33.349946 -11.75004)
					(mid 33.057053 -12.457145)
					(end 32.349948 -12.750038)
				)
				(arc
					(start 15.999968 -12.750038)
					(mid 15.292863 -12.457145)
					(end 14.99997 -11.75004)
				)
				(arc
					(start 14.99997 -5.500116)
					(mid 14.707077 -4.793011)
					(end 13.999972 -4.500118)
				)
				(arc
					(start 0.999998 -4.500118)
					(mid 0.292893 -4.793011)
					(end 0 -5.500116)
				)
				(xy 0 -13.750036)
			)
		)
	)
	(zone
		(net "XP5R0V")
		(layer "F.Cu")
		(hatch none 0.5)
		(connect_pads
			(clearance 0.5)
		)
		(min_thickness 0.25)
		(fill yes
			(thermal_gap 0.5)
			(thermal_bridge_width 0.5)
			(island_removal_mode 0)
		)
		(polygon
			(pts
				(xy 57.912 -103.0224) (xy 51.5874 -103.0224) (xy 51.3334 -102.7684) (xy 51.3334 -98.7044) (xy 51.5874 -98.4504)
				(xy 57.7596 -98.4504) (xy 58.1152 -98.806) (xy 58.1152 -102.8192)
			)
		)
	)
	(zone
		(net "XP12R0V")
		(layer "F.Cu")
		(hatch none 0.5)
		(connect_pads
			(clearance 0.5)
		)
		(min_thickness 0.25)
		(fill yes
			(thermal_gap 0.5)
			(thermal_bridge_width 0.5)
			(island_removal_mode 0)
		)
		(polygon
			(pts
				(xy 90.6272 -106.2228) (xy 90.6272 -107.8484) (xy 90.5002 -107.9754) (xy 87.9094 -107.9754) (xy 87.7062 -107.7722)
				(xy 87.7062 -106.0958) (xy 87.7062 -105.7148) (xy 87.7062 -105.5116) (xy 88.0618 -105.156) (xy 90.2716 -105.156)
				(xy 90.6272 -105.5116) (xy 90.6272 -105.664)
			)
		)
	)
	(zone
		(layer "F.Cu")
		(hatch none 0.5)
		(connect_pads
			(clearance 0)
		)
		(min_thickness 0.25)
		(keepout
			(tracks not_allowed)
			(vias allowed)
			(pads allowed)
			(copperpour not_allowed)
			(footprints allowed)
		)
		(placement
			(enabled no)
			(sheetname "")
		)
		(fill
			(thermal_gap 0.5)
			(thermal_bridge_width 0.5)
			(island_removal_mode 0)
		)
		(polygon
			(pts
				(xy 137.150094 -110.149894) (xy 12.7 -110.149894) (xy 12.7 -89.7001) (xy 0.999998 -89.7001) (xy 0 -89.7001)
				(arc
					(start 0 -110.149894)
					(mid 0.292893 -110.856999)
					(end 0.999998 -111.149892)
				)
				(arc
					(start 166.649908 -111.149892)
					(mid 167.357013 -110.856999)
					(end 167.649906 -110.149894)
				)
				(xy 167.649906 -99.70008) (xy 157.619954 -99.70008) (xy 157.619954 -110.149894)
			)
		)
	)
	(zone
		(net "UNNAMED_515_CAPACITOR_I130_1")
		(layer "F.Cu")
		(hatch none 0.5)
		(connect_pads
			(clearance 0.5)
		)
		(min_thickness 0.25)
		(fill yes
			(thermal_gap 0.5)
			(thermal_bridge_width 0.5)
			(island_removal_mode 0)
		)
		(polygon
			(pts
				(xy 145.5674 -17.5514) (xy 143.8656 -17.5514) (xy 143.8148 -17.6022) (xy 143.8148 -19.0754) (xy 144.2466 -19.5072)
				(xy 144.2466 -21.082) (xy 144.2466 -22.479) (xy 144.2466 -24.003) (xy 144.3736 -24.13) (xy 145.2626 -24.13)
				(xy 145.4658 -23.9268) (xy 145.4658 -22.7838) (xy 145.796 -22.4536) (xy 145.796 -22.0218) (xy 145.796 -21.1074)
				(xy 145.796 -20.9804) (xy 145.796 -17.653) (xy 145.6944 -17.5514)
			)
		)
	)
	(zone
		(layer "F.Cu")
		(hatch none 0.5)
		(connect_pads
			(clearance 0)
		)
		(min_thickness 0.25)
		(keepout
			(tracks allowed)
			(vias allowed)
			(pads allowed)
			(copperpour allowed)
			(footprints allowed)
		)
		(placement
			(enabled no)
			(sheetname "")
		)
		(fill
			(thermal_gap 0.5)
			(thermal_bridge_width 0.5)
			(island_removal_mode 0)
		)
		(polygon
			(pts
				(xy 92.075 -61.468) (xy 92.075 -60.579) (xy 92.583 -60.579) (xy 92.583 -61.468)
			)
		)
	)
	(zone
		(net "VIN_XP3R3")
		(layer "F.Cu")
		(hatch none 0.5)
		(connect_pads
			(clearance 0.5)
		)
		(min_thickness 0.25)
		(fill yes
			(thermal_gap 0.5)
			(thermal_bridge_width 0.5)
			(island_removal_mode 0)
		)
		(polygon
			(pts
				(xy 85.4202 -102.6668) (xy 85.6742 -102.6668) (xy 85.8012 -102.7938) (xy 85.8012 -104.0638) (xy 85.8012 -104.3178)
				(xy 85.8012 -104.5718) (xy 86.0552 -104.8258) (xy 86.8172 -104.8258) (xy 86.9442 -104.9528) (xy 86.9442 -107.8738)
				(xy 86.8172 -108.0008) (xy 83.8962 -108.0008) (xy 83.7692 -107.8738) (xy 83.7692 -106.0958) (xy 84.1502 -105.7148)
				(xy 84.1502 -104.6988) (xy 84.2772 -104.5718) (xy 85.09 -104.5718) (xy 85.1916 -104.4702) (xy 85.1916 -102.743)
				(xy 85.2678 -102.6668)
			)
		)
	)
	(zone
		(net "XP1R8V_FPGA")
		(layer "F.Cu")
		(hatch none 0.5)
		(connect_pads
			(clearance 0.5)
		)
		(min_thickness 0.25)
		(fill yes
			(thermal_gap 0.5)
			(thermal_bridge_width 0.5)
			(island_removal_mode 0)
		)
		(polygon
			(pts
				(xy 92.202 -57.023) (xy 92.202 -54.991) (xy 90.17 -54.991) (xy 89.916 -55.245) (xy 89.916 -56.896)
				(xy 89.916 -57.404) (xy 90.17 -57.658) (xy 92.075 -57.658) (xy 92.202 -57.531)
			)
		)
	)
	(zone
		(net "SG")
		(layer "F.Cu")
		(hatch none 0.5)
		(connect_pads
			(clearance 0.5)
		)
		(min_thickness 0.25)
		(fill yes
			(thermal_gap 0.5)
			(thermal_bridge_width 0.5)
			(island_removal_mode 0)
		)
		(polygon
			(pts
				(xy 36.4363 -93.8784) (xy 36.4363 -94.3864) (xy 36.5379 -94.488) (xy 37.7317 -94.488) (xy 37.9857 -94.488)
				(xy 38.8747 -94.488) (xy 39.0017 -94.361) (xy 39.0017 -93.98) (xy 38.4937 -93.472) (xy 36.8427 -93.472)
			)
		)
	)
	(zone
		(layer "F.Cu")
		(hatch none 0.5)
		(connect_pads
			(clearance 0)
		)
		(min_thickness 0.25)
		(keepout
			(tracks allowed)
			(vias allowed)
			(pads allowed)
			(copperpour allowed)
			(footprints not_allowed)
		)
		(placement
			(enabled no)
			(sheetname "")
		)
		(fill
			(thermal_gap 0.5)
			(thermal_bridge_width 0.5)
			(island_removal_mode 0)
		)
		(polygon
			(pts
				(xy 36.46805 -91.697556) (xy 71.46798 -91.697556) (xy 71.46798 -84.22005) (xy 36.46805 -84.22005)
			)
		)
	)
	(zone
		(layer "F.Cu")
		(hatch none 0.5)
		(connect_pads
			(clearance 0)
		)
		(min_thickness 0.25)
		(keepout
			(tracks allowed)
			(vias allowed)
			(pads allowed)
			(copperpour allowed)
			(footprints allowed)
		)
		(placement
			(enabled no)
			(sheetname "")
		)
		(fill
			(thermal_gap 0.5)
			(thermal_bridge_width 0.5)
			(island_removal_mode 0)
		)
		(polygon
			(pts
				(xy 14.059408 -60.64631) (xy 14.059408 -59.35091) (xy 14.770608 -59.35091) (xy 14.770608 -60.64631)
			)
		)
	)
	(zone
		(layer "F.Cu")
		(hatch none 0.5)
		(connect_pads
			(clearance 0)
		)
		(min_thickness 0.25)
		(keepout
			(tracks allowed)
			(vias allowed)
			(pads allowed)
			(copperpour allowed)
			(footprints not_allowed)
		)
		(placement
			(enabled no)
			(sheetname "")
		)
		(fill
			(thermal_gap 0.5)
			(thermal_bridge_width 0.5)
			(island_removal_mode 0)
		)
		(polygon
			(pts
				(xy 157.619954 -22.899878) (xy 167.649906 -22.899878)
				(arc
					(start 167.649906 -13.750036)
					(mid 167.357013 -13.042931)
					(end 166.649908 -12.750038)
				)
				(arc
					(start 80.300068 -12.750038)
					(mid 79.592963 -12.457145)
					(end 79.30007 -11.75004)
				)
				(xy 79.30007 -13.750036) (xy 157.619954 -13.750036)
			)
		)
	)
	(zone
		(layer "F.Cu")
		(hatch none 0.5)
		(connect_pads
			(clearance 0)
		)
		(min_thickness 0.25)
		(keepout
			(tracks allowed)
			(vias allowed)
			(pads allowed)
			(copperpour allowed)
			(footprints allowed)
		)
		(placement
			(enabled no)
			(sheetname "")
		)
		(fill
			(thermal_gap 0.5)
			(thermal_bridge_width 0.5)
			(island_removal_mode 0)
		)
		(polygon
			(pts
				(xy 36.576 -104.013) (xy 36.576 -103.505) (xy 37.465 -103.505) (xy 37.465 -104.013)
			)
		)
	)
	(zone
		(layer "F.Cu")
		(hatch none 0.5)
		(connect_pads
			(clearance 0)
		)
		(min_thickness 0.25)
		(keepout
			(tracks allowed)
			(vias allowed)
			(pads allowed)
			(copperpour allowed)
			(footprints allowed)
		)
		(placement
			(enabled no)
			(sheetname "")
		)
		(fill
			(thermal_gap 0.5)
			(thermal_bridge_width 0.5)
			(island_removal_mode 0)
		)
		(polygon
			(pts
				(xy 133.68528 -69.3674) (xy 133.68528 -69.07784) (xy 134.48792 -69.07784) (xy 134.48792 -69.3674)
			)
		)
	)
	(zone
		(net "SG")
		(layer "F.Cu")
		(hatch none 0.5)
		(connect_pads
			(clearance 0.5)
		)
		(min_thickness 0.25)
		(fill yes
			(thermal_gap 0.5)
			(thermal_bridge_width 0.5)
			(island_removal_mode 0)
		)
		(polygon
			(pts
				(xy 139.630912 -54.5338) (xy 140.6652 -54.5338) (xy 140.843 -54.356) (xy 140.843 -53.213) (xy 139.827 -52.197)
				(xy 138.938 -52.197) (xy 138.176 -51.435) (xy 138.176 -46.609) (xy 138.049 -46.482) (xy 137.16 -46.482)
				(xy 136.906 -46.736) (xy 135.255 -46.736) (xy 135.255 -52.578) (xy 135.382 -52.705) (xy 137.541 -52.705)
				(xy 138.049 -53.213) (xy 139.192 -53.213) (xy 139.446 -53.467) (xy 139.446 -54.348888)
			)
		)
	)
	(zone
		(layer "F.Cu")
		(hatch none 0.5)
		(connect_pads
			(clearance 0)
		)
		(min_thickness 0.25)
		(keepout
			(tracks not_allowed)
			(vias allowed)
			(pads allowed)
			(copperpour not_allowed)
			(footprints allowed)
		)
		(placement
			(enabled no)
			(sheetname "")
		)
		(fill
			(thermal_gap 0.5)
			(thermal_bridge_width 0.5)
			(island_removal_mode 0)
		)
		(polygon
			(pts
				(xy 79.30007 -13.750036) (xy 157.619954 -13.750036) (xy 157.619954 -22.899878) (xy 167.649906 -22.899878)
				(arc
					(start 167.649906 -13.750036)
					(mid 167.357013 -13.042931)
					(end 166.649908 -12.750038)
				)
				(arc
					(start 80.300068 -12.750038)
					(mid 79.592963 -12.457145)
					(end 79.30007 -11.75004)
				)
			)
		)
	)
	(zone
		(layer "F.Cu")
		(hatch none 0.5)
		(connect_pads
			(clearance 0)
		)
		(min_thickness 0.25)
		(keepout
			(tracks allowed)
			(vias allowed)
			(pads allowed)
			(copperpour allowed)
			(footprints allowed)
		)
		(placement
			(enabled no)
			(sheetname "")
		)
		(fill
			(thermal_gap 0.5)
			(thermal_bridge_width 0.5)
			(island_removal_mode 0)
		)
		(polygon
			(pts
				(xy 32.639 -18.542) (xy 32.639 -17.907) (xy 34.036 -17.907) (xy 34.036 -18.542)
			)
		)
	)
	(zone
		(layer "F.Cu")
		(hatch none 0.5)
		(connect_pads
			(clearance 0)
		)
		(min_thickness 0.25)
		(keepout
			(tracks allowed)
			(vias allowed)
			(pads allowed)
			(copperpour allowed)
			(footprints allowed)
		)
		(placement
			(enabled no)
			(sheetname "")
		)
		(fill
			(thermal_gap 0.5)
			(thermal_bridge_width 0.5)
			(island_removal_mode 0)
		)
		(polygon
			(pts
				(xy 75.3872 -46.9138) (xy 76.2508 -46.9138) (xy 76.6318 -46.9138) (xy 76.835 -47.117) (xy 76.835 -47.879)
				(xy 76.454 -48.26) (xy 75.311 -48.26) (xy 74.3712 -48.26) (xy 74.1934 -48.0822) (xy 74.1934 -47.2948)
				(xy 74.2442 -47.244) (xy 75.057 -47.244) (xy 75.184 -47.117)
			)
		)
	)
	(zone
		(layer "F.Cu")
		(hatch none 0.5)
		(connect_pads
			(clearance 0)
		)
		(min_thickness 0.25)
		(keepout
			(tracks allowed)
			(vias allowed)
			(pads allowed)
			(copperpour allowed)
			(footprints allowed)
		)
		(placement
			(enabled no)
			(sheetname "")
		)
		(fill
			(thermal_gap 0.5)
			(thermal_bridge_width 0.5)
			(island_removal_mode 0)
		)
		(polygon
			(pts
				(xy 41.1226 -82.804) (xy 41.1226 -79.375) (xy 46.101 -79.375) (xy 46.101 -82.804)
			)
		)
	)
	(zone
		(layer "F.Cu")
		(hatch none 0.5)
		(connect_pads
			(clearance 0)
		)
		(min_thickness 0.25)
		(keepout
			(tracks allowed)
			(vias allowed)
			(pads allowed)
			(copperpour allowed)
			(footprints allowed)
		)
		(placement
			(enabled no)
			(sheetname "")
		)
		(fill
			(thermal_gap 0.5)
			(thermal_bridge_width 0.5)
			(island_removal_mode 0)
		)
		(polygon
			(pts
				(xy 14.0208 -31.58617) (xy 14.0208 -30.29077) (xy 14.732 -30.29077) (xy 14.732 -31.58617)
			)
		)
	)
	(zone
		(layer "F.Cu")
		(hatch none 0.5)
		(connect_pads
			(clearance 0)
		)
		(min_thickness 0.25)
		(keepout
			(tracks allowed)
			(vias allowed)
			(pads allowed)
			(copperpour allowed)
			(footprints allowed)
		)
		(placement
			(enabled no)
			(sheetname "")
		)
		(fill
			(thermal_gap 0.5)
			(thermal_bridge_width 0.5)
			(island_removal_mode 0)
		)
		(polygon
			(pts
				(xy 144.399 -59.944) (xy 144.399 -59.055) (xy 144.907 -59.055) (xy 144.907 -59.944)
			)
		)
	)
	(zone
		(layer "F.Cu")
		(hatch none 0.5)
		(connect_pads
			(clearance 0)
		)
		(min_thickness 0.25)
		(keepout
			(tracks allowed)
			(vias allowed)
			(pads allowed)
			(copperpour allowed)
			(footprints allowed)
		)
		(placement
			(enabled no)
			(sheetname "")
		)
		(fill
			(thermal_gap 0.5)
			(thermal_bridge_width 0.5)
			(island_removal_mode 0)
		)
		(polygon
			(pts
				(xy 32.004 -96.52) (xy 32.004 -96.012) (xy 33.02 -96.012) (xy 33.02 -96.52)
			)
		)
	)
	(zone
		(net "XP12R0V")
		(layer "F.Cu")
		(hatch none 0.5)
		(connect_pads
			(clearance 0.5)
		)
		(min_thickness 0.25)
		(fill yes
			(thermal_gap 0.5)
			(thermal_bridge_width 0.5)
			(island_removal_mode 0)
		)
		(polygon
			(pts
				(xy 36.617656 -94.827344) (xy 39.125144 -94.827344) (xy 39.2684 -94.9706) (xy 39.2684 -96.5454)
				(xy 39.2684 -96.774) (xy 39.243 -96.774) (xy 39.116 -96.901) (xy 36.83 -96.901) (xy 36.449 -96.52)
				(xy 36.449 -95.504) (xy 36.449 -94.996)
			)
		)
	)
	(zone
		(net "VIN_XP3R3")
		(layer "F.Cu")
		(hatch none 0.5)
		(connect_pads
			(clearance 0.5)
		)
		(min_thickness 0.25)
		(fill yes
			(thermal_gap 0.5)
			(thermal_bridge_width 0.5)
			(island_removal_mode 0)
		)
		(polygon
			(pts
				(xy 85.6996 -101.092) (xy 85.6996 -99.314) (xy 85.979 -99.0346) (xy 86.3854 -98.6282) (xy 86.4362 -98.5774)
				(xy 86.4362 -96.4438) (xy 86.3092 -96.3168) (xy 84.9122 -96.3168) (xy 84.6582 -96.5708) (xy 84.6582 -98.9838)
				(xy 85.0392 -99.3648) (xy 85.2932 -99.6188) (xy 85.3186 -99.6442) (xy 85.3186 -101.0412) (xy 85.3694 -101.092)
			)
		)
	)
	(zone
		(net "XP3R3V_GPS")
		(layer "F.Cu")
		(hatch none 0.5)
		(connect_pads
			(clearance 0.5)
		)
		(min_thickness 0.25)
		(fill yes
			(thermal_gap 0.5)
			(thermal_bridge_width 0.5)
			(island_removal_mode 0)
		)
		(polygon
			(pts
				(xy 117.983 -100.7618) (xy 122.6058 -100.7618) (xy 122.682 -100.6856) (xy 122.682 -98.806) (xy 122.5804 -98.7044)
				(xy 119.7864 -98.7044) (xy 119.3546 -98.2726) (xy 119.0752 -97.9932) (xy 118.745 -97.663) (xy 117.8306 -97.663)
				(xy 117.8306 -100.6094)
			)
		)
	)
	(zone
		(layer "F.Cu")
		(hatch none 0.5)
		(connect_pads
			(clearance 0)
		)
		(min_thickness 0.25)
		(keepout
			(tracks allowed)
			(vias allowed)
			(pads allowed)
			(copperpour allowed)
			(footprints allowed)
		)
		(placement
			(enabled no)
			(sheetname "")
		)
		(fill
			(thermal_gap 0.5)
			(thermal_bridge_width 0.5)
			(island_removal_mode 0)
		)
		(polygon
			(pts
				(xy 105.41 -86.868) (xy 105.41 -86.106) (xy 106.807 -86.106) (xy 106.807 -86.868)
			)
		)
	)
	(zone
		(layer "F.Cu")
		(hatch none 0.5)
		(connect_pads
			(clearance 0)
		)
		(min_thickness 0.25)
		(keepout
			(tracks allowed)
			(vias allowed)
			(pads allowed)
			(copperpour allowed)
			(footprints allowed)
		)
		(placement
			(enabled no)
			(sheetname "")
		)
		(fill
			(thermal_gap 0.5)
			(thermal_bridge_width 0.5)
			(island_removal_mode 0)
		)
		(polygon
			(pts
				(xy 107.442 -105.537) (xy 103.251 -105.537) (xy 103.251 -103.378) (xy 107.442 -103.378)
			)
		)
	)
	(zone
		(layer "F.Cu")
		(hatch none 0.5)
		(connect_pads
			(clearance 0)
		)
		(min_thickness 0.25)
		(keepout
			(tracks allowed)
			(vias allowed)
			(pads allowed)
			(copperpour allowed)
			(footprints allowed)
		)
		(placement
			(enabled no)
			(sheetname "")
		)
		(fill
			(thermal_gap 0.5)
			(thermal_bridge_width 0.5)
			(island_removal_mode 0)
		)
		(polygon
			(pts
				(xy 45.7962 -97.4344) (xy 45.7962 -103.9622) (xy 38.6842 -103.9622) (xy 38.6842 -97.4344)
			)
		)
	)
	(zone
		(net "XP1R0V_FPGA")
		(layer "F.Cu")
		(hatch none 0.5)
		(connect_pads
			(clearance 0.5)
		)
		(min_thickness 0.25)
		(fill yes
			(thermal_gap 0.5)
			(thermal_bridge_width 0.5)
			(island_removal_mode 0)
		)
		(polygon
			(pts
				(xy 134.747 -45.72) (xy 143.51 -45.72) (xy 144.018 -45.212) (xy 144.018 -42.164) (xy 144.018 -40.386)
				(xy 143.764 -40.132) (xy 140.843 -40.132) (xy 139.192 -41.783) (xy 136.652 -41.783) (xy 136.271 -41.783)
				(xy 135.255 -42.799) (xy 134.239 -42.799) (xy 132.969 -42.799) (xy 132.969 -45.339) (xy 133.35 -45.72)
			)
		)
	)
	(zone
		(layer "F.Cu")
		(hatch none 0.5)
		(connect_pads
			(clearance 0)
		)
		(min_thickness 0.25)
		(keepout
			(tracks allowed)
			(vias allowed)
			(pads allowed)
			(copperpour allowed)
			(footprints allowed)
		)
		(placement
			(enabled no)
			(sheetname "")
		)
		(fill
			(thermal_gap 0.5)
			(thermal_bridge_width 0.5)
			(island_removal_mode 0)
		)
		(polygon
			(pts
				(xy 140.0048 -14.6558) (xy 147.3962 -14.6558) (xy 147.3962 -20.1168) (xy 140.0048 -20.1168) (xy 140.0048 -18.8468)
				(xy 139.065 -17.907) (xy 139.065 -15.494) (xy 139.9032 -14.6558)
			)
		)
	)
	(zone
		(net "SG")
		(layer "F.Cu")
		(hatch none 0.5)
		(connect_pads
			(clearance 0.5)
		)
		(min_thickness 0.25)
		(fill yes
			(thermal_gap 0.5)
			(thermal_bridge_width 0.5)
			(island_removal_mode 0)
		)
		(polygon
			(pts
				(xy 90.17 -41.402) (xy 90.424 -41.148) (xy 92.964 -41.148) (xy 94.742 -41.148) (xy 94.742 -42.545)
				(xy 94.7293 -42.5577) (xy 94.7293 -42.7355) (xy 94.1578 -43.307) (xy 89.408 -43.307) (xy 88.773 -43.307)
				(xy 88.519 -43.053) (xy 88.519 -41.402)
			)
		)
	)
	(zone
		(net "XP5R0V_FT4232")
		(layer "F.Cu")
		(hatch none 0.5)
		(connect_pads
			(clearance 0.5)
		)
		(min_thickness 0.25)
		(fill yes
			(thermal_gap 0.5)
			(thermal_bridge_width 0.5)
			(island_removal_mode 0)
		)
		(polygon
			(pts
				(xy 39.37 -81.661) (xy 40.64 -81.661) (xy 41.021 -81.28) (xy 41.021 -79.629) (xy 40.894 -79.502)
				(xy 39.624 -79.502) (xy 39.243 -79.883) (xy 39.243 -81.534)
			)
		)
	)
	(zone
		(layer "F.Cu")
		(hatch none 0.5)
		(connect_pads
			(clearance 0)
		)
		(min_thickness 0.25)
		(keepout
			(tracks allowed)
			(vias allowed)
			(pads allowed)
			(copperpour allowed)
			(footprints allowed)
		)
		(placement
			(enabled no)
			(sheetname "")
		)
		(fill
			(thermal_gap 0.5)
			(thermal_bridge_width 0.5)
			(island_removal_mode 0)
		)
		(polygon
			(pts
				(xy 160.8582 -51.1048) (xy 160.8582 -49.6824) (xy 163.3982 -49.6824) (xy 163.3982 -51.1048)
			)
		)
	)
	(zone
		(net "XP1R2V_FPGA")
		(layer "F.Cu")
		(hatch none 0.5)
		(connect_pads
			(clearance 0.5)
		)
		(min_thickness 0.25)
		(fill yes
			(thermal_gap 0.5)
			(thermal_bridge_width 0.5)
			(island_removal_mode 0)
		)
		(polygon
			(pts
				(xy 98.171 -71.6788) (xy 97.4344 -71.6788) (xy 97.3074 -71.5518) (xy 97.3074 -71.4502) (xy 97.3074 -71.1708)
				(xy 97.2312 -71.0946) (xy 96.3422 -71.0946) (xy 96.266 -71.0184) (xy 96.266 -70.3072) (xy 96.266 -69.8246)
				(xy 96.1644 -69.723) (xy 92.583 -69.723) (xy 92.3036 -70.0024) (xy 92.3036 -71.501) (xy 92.5068 -71.7042)
				(xy 93.853 -71.7042) (xy 94.5642 -71.7042) (xy 95.5802 -71.7042) (xy 95.8596 -71.9836) (xy 95.8596 -72.6186)
				(xy 95.9866 -72.7456) (xy 96.2152 -72.7456) (xy 97.5106 -72.7456) (xy 97.7138 -72.9488) (xy 97.7138 -73.66)
				(xy 97.8408 -73.787) (xy 99.0092 -73.787) (xy 99.0092 -72.517)
			)
		)
	)
	(zone
		(layer "F.Cu")
		(hatch none 0.5)
		(connect_pads
			(clearance 0)
		)
		(min_thickness 0.25)
		(keepout
			(tracks allowed)
			(vias allowed)
			(pads allowed)
			(copperpour allowed)
			(footprints allowed)
		)
		(placement
			(enabled no)
			(sheetname "")
		)
		(fill
			(thermal_gap 0.5)
			(thermal_bridge_width 0.5)
			(island_removal_mode 0)
		)
		(polygon
			(pts
				(xy 70.231 -45.593) (xy 70.231 -45.339) (xy 71.882 -45.339) (xy 71.882 -45.593)
			)
		)
	)
	(zone
		(layer "F.Cu")
		(hatch none 0.5)
		(connect_pads
			(clearance 0)
		)
		(min_thickness 0.25)
		(keepout
			(tracks allowed)
			(vias allowed)
			(pads allowed)
			(copperpour allowed)
			(footprints allowed)
		)
		(placement
			(enabled no)
			(sheetname "")
		)
		(fill
			(thermal_gap 0.5)
			(thermal_bridge_width 0.5)
			(island_removal_mode 0)
		)
		(polygon
			(pts
				(xy 105.537 -88.773) (xy 105.537 -88.011) (xy 106.807 -88.011) (xy 106.807 -88.773)
			)
		)
	)
	(zone
		(layer "F.Cu")
		(hatch none 0.5)
		(connect_pads
			(clearance 0)
		)
		(min_thickness 0.25)
		(keepout
			(tracks allowed)
			(vias allowed)
			(pads allowed)
			(copperpour allowed)
			(footprints allowed)
		)
		(placement
			(enabled no)
			(sheetname "")
		)
		(fill
			(thermal_gap 0.5)
			(thermal_bridge_width 0.5)
			(island_removal_mode 0)
		)
		(polygon
			(pts
				(xy 85.725 -56.769) (xy 85.725 -55.372) (xy 86.487 -55.372) (xy 86.487 -56.769)
			)
		)
	)
	(zone
		(layer "F.Cu")
		(hatch none 0.5)
		(connect_pads
			(clearance 0)
		)
		(min_thickness 0.25)
		(keepout
			(tracks allowed)
			(vias allowed)
			(pads allowed)
			(copperpour allowed)
			(footprints allowed)
		)
		(placement
			(enabled no)
			(sheetname "")
		)
		(fill
			(thermal_gap 0.5)
			(thermal_bridge_width 0.5)
			(island_removal_mode 0)
		)
		(polygon
			(pts
				(xy 100.9142 -78.9178) (xy 100.9142 -78.0796) (xy 101.3206 -78.0796) (xy 101.3206 -78.9178)
			)
		)
	)
	(zone
		(net "XP3R3V")
		(layer "F.Cu")
		(hatch none 0.5)
		(connect_pads
			(clearance 0.5)
		)
		(min_thickness 0.25)
		(fill yes
			(thermal_gap 0.5)
			(thermal_bridge_width 0.5)
			(island_removal_mode 0)
		)
		(polygon
			(pts
				(xy 75.659488 -96.345502) (xy 75.659488 -90.867992) (xy 76.116434 -90.411046) (xy 85.103462 -90.411046)
				(xy 88.425528 -90.411046) (xy 89.04605 -91.031568) (xy 89.04605 -92.949776) (xy 88.9889 -93.006926)
				(xy 85.177122 -93.006926) (xy 83.396074 -93.006926) (xy 83.312 -93.091) (xy 82.146648 -93.091) (xy 81.903824 -93.333824)
				(xy 78.891892 -96.345502)
			)
		)
	)
	(zone
		(layer "F.Cu")
		(hatch none 0.5)
		(connect_pads
			(clearance 0)
		)
		(min_thickness 0.25)
		(keepout
			(tracks allowed)
			(vias allowed)
			(pads allowed)
			(copperpour allowed)
			(footprints allowed)
		)
		(placement
			(enabled no)
			(sheetname "")
		)
		(fill
			(thermal_gap 0.5)
			(thermal_bridge_width 0.5)
			(island_removal_mode 0)
		)
		(polygon
			(pts
				(xy 19.138392 -69.169026) (xy 19.138392 -67.873626) (xy 19.849592 -67.873626) (xy 19.849592 -69.169026)
			)
		)
	)
	(zone
		(net "VIN_XP1R0V")
		(layer "F.Cu")
		(hatch none 0.5)
		(connect_pads
			(clearance 0.5)
		)
		(min_thickness 0.25)
		(fill yes
			(thermal_gap 0.5)
			(thermal_bridge_width 0.5)
			(island_removal_mode 0)
		)
		(polygon
			(pts
				(xy 140.843 -54.991) (xy 140.843 -55.245) (xy 140.716 -55.372) (xy 139.446 -55.372) (xy 139.192 -55.372)
				(xy 138.938 -55.372) (xy 138.684 -55.626) (xy 138.684 -56.388) (xy 138.684 -56.8198) (xy 138.5062 -56.9976)
				(xy 136.5758 -56.9976) (xy 136.398 -56.8198) (xy 136.398 -55.5752) (xy 135.9408 -55.118) (xy 135.9408 -53.5432)
				(xy 136.144 -53.34) (xy 137.414 -53.34) (xy 137.795 -53.721) (xy 137.798048 -53.721) (xy 137.975848 -53.8988)
				(xy 138.7602 -53.8988) (xy 138.938 -54.0766) (xy 138.938 -54.5338) (xy 138.938 -54.7116) (xy 139.0904 -54.864)
				(xy 140.716 -54.864)
			)
		)
	)
	(zone
		(net "SG")
		(layer "F.Cu")
		(hatch none 0.5)
		(connect_pads
			(clearance 0.5)
		)
		(min_thickness 0.25)
		(fill yes
			(thermal_gap 0.5)
			(thermal_bridge_width 0.5)
			(island_removal_mode 0)
		)
		(polygon
			(pts
				(xy 143.5862 -16.005048) (xy 143.5862 -19.304) (xy 143.8402 -19.558) (xy 143.8402 -20.7518) (xy 143.5862 -21.0058)
				(xy 143.5862 -22.6822) (xy 143.5862 -24.0538) (xy 140.6652 -24.0538) (xy 140.3858 -23.789894) (xy 140.3858 -21.0058)
				(xy 140.5128 -20.8788) (xy 140.8938 -20.8788) (xy 141.097 -20.6756) (xy 141.097 -19.4056) (xy 141.2494 -19.2532)
				(xy 141.7828 -19.2532) (xy 142.1384 -18.8976) (xy 142.1384 -16.6116) (xy 141.9352 -16.4084) (xy 141.934184 -16.4084)
				(xy 141.9225 -16.396716) (xy 140.840206 -16.396716) (xy 140.839698 -16.397224) (xy 140.839698 -15.984474)
				(xy 140.952728 -15.871444) (xy 141.361668 -15.462504) (xy 143.435578 -15.462504) (xy 143.5862 -15.613126)
			)
		)
	)
	(zone
		(layer "F.Cu")
		(hatch none 0.5)
		(connect_pads
			(clearance 0)
		)
		(min_thickness 0.25)
		(keepout
			(tracks allowed)
			(vias allowed)
			(pads allowed)
			(copperpour allowed)
			(footprints allowed)
		)
		(placement
			(enabled no)
			(sheetname "")
		)
		(fill
			(thermal_gap 0.5)
			(thermal_bridge_width 0.5)
			(island_removal_mode 0)
		)
		(polygon
			(pts
				(xy 139.7 -59.817) (xy 139.7 -58.928) (xy 140.208 -58.928) (xy 140.208 -59.817)
			)
		)
	)
	(zone
		(layer "F.Cu")
		(hatch none 0.5)
		(connect_pads
			(clearance 0)
		)
		(min_thickness 0.25)
		(keepout
			(tracks allowed)
			(vias allowed)
			(pads allowed)
			(copperpour allowed)
			(footprints allowed)
		)
		(placement
			(enabled no)
			(sheetname "")
		)
		(fill
			(thermal_gap 0.5)
			(thermal_bridge_width 0.5)
			(island_removal_mode 0)
		)
		(polygon
			(pts
				(xy 100.457 -86.868) (xy 100.457 -86.106) (xy 101.727 -86.106) (xy 101.727 -86.868)
			)
		)
	)
	(zone
		(net "XP1R0V_SW")
		(layer "F.Cu")
		(hatch none 0.5)
		(connect_pads
			(clearance 0.5)
		)
		(min_thickness 0.25)
		(fill yes
			(thermal_gap 0.5)
			(thermal_bridge_width 0.5)
			(island_removal_mode 0)
		)
		(polygon
			(pts
				(xy 141.097 -52.705) (xy 141.097 -55.499) (xy 141.224 -55.626) (xy 141.986 -55.626) (xy 142.113 -55.499)
				(xy 142.113 -52.578) (xy 142.113 -52.197) (xy 143.3068 -51.0032) (xy 144.018 -51.0032) (xy 144.018 -49.149)
				(xy 144.018 -48.4505) (xy 143.8275 -48.4505) (xy 140.335 -48.4505) (xy 140.335 -51.435) (xy 140.589 -51.689)
				(xy 141.097 -52.197)
			)
		)
	)
	(zone
		(layer "F.Cu")
		(hatch none 0.5)
		(connect_pads
			(clearance 0)
		)
		(min_thickness 0.25)
		(keepout
			(tracks allowed)
			(vias allowed)
			(pads allowed)
			(copperpour allowed)
			(footprints allowed)
		)
		(placement
			(enabled no)
			(sheetname "")
		)
		(fill
			(thermal_gap 0.5)
			(thermal_bridge_width 0.5)
			(island_removal_mode 0)
		)
		(polygon
			(pts
				(xy 13.462 -55.3466) (xy 12.1666 -55.3466) (xy 12.1666 -54.6354) (xy 13.462 -54.6354)
			)
		)
	)
	(zone
		(layer "F.Cu")
		(hatch none 0.5)
		(connect_pads
			(clearance 0)
		)
		(min_thickness 0.25)
		(keepout
			(tracks allowed)
			(vias allowed)
			(pads allowed)
			(copperpour allowed)
			(footprints allowed)
		)
		(placement
			(enabled no)
			(sheetname "")
		)
		(fill
			(thermal_gap 0.5)
			(thermal_bridge_width 0.5)
			(island_removal_mode 0)
		)
		(polygon
			(pts
				(xy 13.97 -46.10354) (xy 13.97 -44.80814) (xy 14.6812 -44.80814) (xy 14.6812 -46.10354)
			)
		)
	)
	(zone
		(net "XP3R3V_FT4232")
		(layer "F.Cu")
		(hatch none 0.5)
		(connect_pads
			(clearance 0.5)
		)
		(min_thickness 0.25)
		(fill yes
			(thermal_gap 0.5)
			(thermal_bridge_width 0.5)
			(island_removal_mode 0)
		)
		(polygon
			(pts
				(xy 38.3032 -76.962) (xy 41.656 -76.962) (xy 41.6814 -76.9874) (xy 41.6814 -78.0796) (xy 41.2369 -78.5241)
				(xy 40.5765 -78.5241) (xy 40.2463 -78.8543) (xy 39.7637 -78.8543) (xy 38.8493 -79.7687) (xy 38.8493 -80.2513)
				(xy 38.481 -80.6196) (xy 37.7444 -80.6196) (xy 37.2872 -80.1624) (xy 36.5252 -80.1624) (xy 36.2712 -79.9084)
				(xy 36.2712 -77.6478) (xy 36.4236 -77.4954) (xy 37.7698 -77.4954)
			)
		)
	)
	(zone
		(layer "F.Cu")
		(hatch none 0.5)
		(connect_pads
			(clearance 0)
		)
		(min_thickness 0.25)
		(keepout
			(tracks allowed)
			(vias allowed)
			(pads allowed)
			(copperpour allowed)
			(footprints allowed)
		)
		(placement
			(enabled no)
			(sheetname "")
		)
		(fill
			(thermal_gap 0.5)
			(thermal_bridge_width 0.5)
			(island_removal_mode 0)
		)
		(polygon
			(pts
				(xy 99.9744 -70.6374) (xy 99.9744 -70.2564) (xy 100.7872 -70.2564) (xy 100.7872 -70.6374)
			)
		)
	)
	(zone
		(net "XP3R3V_SW")
		(layer "F.Cu")
		(hatch none 0.5)
		(connect_pads
			(clearance 0.5)
		)
		(min_thickness 0.25)
		(fill yes
			(thermal_gap 0.5)
			(thermal_bridge_width 0.5)
			(island_removal_mode 0)
		)
		(polygon
			(pts
				(xy 83.1342 -102.4128) (xy 85.852 -102.4128) (xy 85.9536 -102.3112) (xy 85.9536 -101.4984) (xy 85.852 -101.3968)
				(xy 83.0072 -101.3968) (xy 82.6262 -101.3968) (xy 82.1182 -101.3968) (xy 81.8642 -101.1428) (xy 81.8642 -101.141276)
				(xy 80.663034 -99.94011) (xy 75.86091 -99.94011) (xy 75.644248 -99.94011) (xy 75.637136 -99.947222)
				(xy 75.637136 -102.37978) (xy 75.670156 -102.4128) (xy 75.819 -102.4128) (xy 81.9658 -102.4128)
				(xy 82.4992 -102.4128)
			)
		)
	)
	(zone
		(net "XP1R8V_VIN")
		(layer "F.Cu")
		(hatch none 0.5)
		(connect_pads
			(clearance 0.5)
		)
		(min_thickness 0.25)
		(fill yes
			(thermal_gap 0.5)
			(thermal_bridge_width 0.5)
			(island_removal_mode 0)
		)
		(polygon
			(pts
				(xy 128.7272 -66.8528) (xy 128.3716 -66.4972) (xy 128.3716 -65.4812) (xy 127.9017 -65.0113) (xy 127.9017 -63.7794)
				(xy 127.7493 -63.627) (xy 124.8664 -63.627) (xy 124.6886 -63.8048) (xy 124.6886 -64.7446) (xy 124.9426 -64.9986)
				(xy 126.4666 -64.9986) (xy 126.8222 -65.3542) (xy 126.8222 -67.6656) (xy 126.9492 -67.7926) (xy 127.5588 -68.4022)
				(xy 128.7272 -68.4022)
			)
		)
	)
	(zone
		(net "XP1R8V_ICP10100")
		(layer "F.Cu")
		(hatch none 0.5)
		(connect_pads
			(clearance 0.5)
		)
		(min_thickness 0.25)
		(fill yes
			(thermal_gap 0.5)
			(thermal_bridge_width 0.5)
			(island_removal_mode 0)
		)
		(polygon
			(pts
				(xy 20.687792 -67.945) (xy 20.687792 -68.3006) (xy 21.576792 -69.1896) (xy 21.576792 -69.596) (xy 21.576792 -69.836792)
				(xy 21.6916 -69.9516) (xy 23.4188 -69.9516) (xy 23.5204 -69.85) (xy 23.5204 -69.5198) (xy 23.5204 -67.7672)
				(xy 23.3426 -67.5894) (xy 23.3426 -67.4116) (xy 23.3426 -66.5226) (xy 23.272496 -66.452496) (xy 22.383496 -66.452496)
				(xy 22.225 -66.610992) (xy 22.225 -66.929) (xy 21.336 -67.818) (xy 21.209 -67.945)
			)
		)
	)
	(zone
		(net "SG")
		(layer "F.Cu")
		(hatch none 0.5)
		(connect_pads
			(clearance 0.5)
		)
		(min_thickness 0.25)
		(fill yes
			(thermal_gap 0.5)
			(thermal_bridge_width 0.5)
			(island_removal_mode 0)
		)
		(polygon
			(pts
				(xy 116.84 -99.06) (xy 116.84 -100.965) (xy 116.713 -101.092) (xy 114.935 -101.092) (xy 114.808 -100.965)
				(xy 114.808 -98.552) (xy 115.57 -98.552) (xy 116.078 -99.06)
			)
		)
	)
	(zone
		(net "XP5R0V")
		(layer "F.Cu")
		(hatch none 0.5)
		(connect_pads
			(clearance 0.5)
		)
		(min_thickness 0.25)
		(fill yes
			(thermal_gap 0.5)
			(thermal_bridge_width 0.5)
			(island_removal_mode 0)
		)
		(polygon
			(pts
				(xy 39.4716 -83.8962) (xy 40.767 -83.8962) (xy 41.1734 -83.4898) (xy 41.1734 -82.3468) (xy 41.021 -82.1944)
				(xy 39.5732 -82.1944) (xy 39.1922 -82.5754) (xy 39.1922 -83.6168)
			)
		)
	)
	(zone
		(net "VIN_XP5R0V")
		(layer "F.Cu")
		(hatch none 0.5)
		(connect_pads
			(clearance 0.5)
		)
		(min_thickness 0.25)
		(fill yes
			(thermal_gap 0.5)
			(thermal_bridge_width 0.5)
			(island_removal_mode 0)
		)
		(polygon
			(pts
				(xy 41.6814 -98.4504) (xy 41.6814 -99.8474) (xy 41.5544 -99.9744) (xy 41.3004 -99.9744) (xy 41.1734 -99.8474)
				(xy 41.1734 -98.5774) (xy 41.1734 -98.3234) (xy 41.1734 -98.0694) (xy 40.9194 -97.8154) (xy 40.1574 -97.8154)
				(xy 40.0304 -97.6884) (xy 40.0304 -94.9198) (xy 40.1574 -94.7928) (xy 42.9768 -94.7928) (xy 43.2054 -95.0214)
				(xy 43.2054 -96.5454) (xy 42.8244 -96.9264) (xy 42.8244 -97.9424) (xy 42.6974 -98.0694) (xy 41.8084 -98.0694)
				(xy 41.6814 -98.1964)
			)
		)
	)
	(zone
		(layer "F.Cu")
		(hatch none 0.5)
		(connect_pads
			(clearance 0)
		)
		(min_thickness 0.25)
		(keepout
			(tracks allowed)
			(vias allowed)
			(pads allowed)
			(copperpour allowed)
			(footprints allowed)
		)
		(placement
			(enabled no)
			(sheetname "")
		)
		(fill
			(thermal_gap 0.5)
			(thermal_bridge_width 0.5)
			(island_removal_mode 0)
		)
		(polygon
			(pts
				(xy 105.41 -99.695) (xy 103.505 -99.695) (xy 103.505 -98.171) (xy 103.505 -97.917) (xy 105.41 -97.917)
				(xy 105.41 -98.171)
			)
		)
	)
	(zone
		(net "XP5R0V")
		(layer "F.Cu")
		(hatch none 0.5)
		(connect_pads
			(clearance 0.5)
		)
		(min_thickness 0.25)
		(fill yes
			(thermal_gap 0.5)
			(thermal_bridge_width 0.5)
			(island_removal_mode 0)
		)
		(polygon
			(pts
				(xy 129.667 -98.171) (xy 129.667 -96.901) (xy 130.175 -96.393) (xy 130.175 -95.631) (xy 130.175 -94.742)
				(xy 130.302 -94.615) (xy 132.08 -94.615) (xy 132.207 -94.742) (xy 132.207 -97.79) (xy 132.08 -97.917)
				(xy 131.826 -98.171) (xy 131.318 -98.171)
			)
		)
	)
	(zone
		(net "XP12R0V_IN")
		(layer "F.Cu")
		(hatch none 0.5)
		(connect_pads
			(clearance 0.5)
		)
		(min_thickness 0.25)
		(fill yes
			(thermal_gap 0.5)
			(thermal_bridge_width 0.5)
			(island_removal_mode 0)
		)
		(polygon
			(pts
				(xy 135.382 -99.6696) (xy 135.3566 -99.6442) (xy 135.3312 -99.6188) (xy 135.3312 -98.7044) (xy 135.1534 -98.5266)
				(xy 133.731 -98.5266) (xy 133.477 -98.7806) (xy 133.477 -101.1682) (xy 133.477 -101.4222) (xy 133.7056 -101.6508)
				(xy 135.2042 -101.6508) (xy 135.382 -101.473)
			)
		)
	)
	(zone
		(net "SG")
		(layer "F.Cu")
		(hatch none 0.5)
		(connect_pads
			(clearance 0.5)
		)
		(min_thickness 0.25)
		(fill yes
			(thermal_gap 0.5)
			(thermal_bridge_width 0.5)
			(island_removal_mode 0)
		)
		(polygon
			(pts
				(xy 46.609 -84.201) (xy 48.387 -84.201) (xy 48.768 -83.82) (xy 48.768 -80.772) (xy 48.768 -75.692)
				(xy 48.387 -75.311) (xy 47.625 -75.311) (xy 47.625 -76.327) (xy 47.244 -76.708) (xy 47.244 -77.724)
				(xy 47.371 -77.851) (xy 47.371 -79.883) (xy 46.99 -80.264) (xy 46.99 -81.661) (xy 46.355 -82.296)
				(xy 46.355 -83.947)
			)
		)
	)
	(zone
		(net "XP5R0V_SW")
		(layer "F.Cu")
		(hatch none 0.5)
		(connect_pads
			(clearance 0.5)
		)
		(min_thickness 0.25)
		(fill yes
			(thermal_gap 0.5)
			(thermal_bridge_width 0.5)
			(island_removal_mode 0)
		)
		(polygon
			(pts
				(xy 40.9194 -100.4824) (xy 40.9194 -101.1174) (xy 41.0464 -101.2444) (xy 43.9674 -101.2444) (xy 44.3484 -101.2444)
				(xy 44.8564 -101.2444) (xy 45.1104 -101.4984) (xy 45.1104 -102.7684) (xy 45.212 -102.87) (xy 48.0949 -102.87)
				(xy 48.0949 -99.1743) (xy 45.1993 -99.1743) (xy 44.069 -100.3046) (xy 41.0972 -100.3046)
			)
		)
	)
	(zone
		(net "XP1R0V_FPGA_MGTAVCC")
		(layer "F.Cu")
		(hatch none 0.5)
		(connect_pads
			(clearance 0.5)
		)
		(min_thickness 0.25)
		(fill yes
			(thermal_gap 0.5)
			(thermal_bridge_width 0.5)
			(island_removal_mode 0)
		)
		(polygon
			(pts
				(xy 93.218 -40.259) (xy 93.218 -36.703) (xy 94.7801 -36.703) (xy 95.274384 -37.197284) (xy 96.046036 -37.197284)
				(xy 96.393 -37.544248) (xy 96.393 -40.132) (xy 96.266 -40.259) (xy 95.504 -40.259)
			)
		)
	)
	(zone
		(layer "F.Cu")
		(hatch none 0.5)
		(connect_pads
			(clearance 0)
		)
		(min_thickness 0.25)
		(keepout
			(tracks allowed)
			(vias allowed)
			(pads allowed)
			(copperpour allowed)
			(footprints allowed)
		)
		(placement
			(enabled no)
			(sheetname "")
		)
		(fill
			(thermal_gap 0.5)
			(thermal_bridge_width 0.5)
			(island_removal_mode 0)
		)
		(polygon
			(pts
				(xy 97.028 -77.724) (xy 97.028 -72.136) (xy 98.171 -70.993) (xy 100.584 -70.993) (xy 101.219 -71.628)
				(xy 101.219 -72.136) (xy 101.219 -77.724)
			)
		)
	)
	(zone
		(layer "F.Cu")
		(hatch none 0.5)
		(connect_pads
			(clearance 0)
		)
		(min_thickness 0.25)
		(keepout
			(tracks allowed)
			(vias allowed)
			(pads allowed)
			(copperpour allowed)
			(footprints allowed)
		)
		(placement
			(enabled no)
			(sheetname "")
		)
		(fill
			(thermal_gap 0.5)
			(thermal_bridge_width 0.5)
			(island_removal_mode 0)
		)
		(polygon
			(pts
				(xy 13.8938 -16.9672) (xy 13.8938 -15.6718) (xy 14.605 -15.6718) (xy 14.605 -16.9672)
			)
		)
	)
	(zone
		(net "XP1R2V_VIN")
		(layer "F.Cu")
		(hatch none 0.5)
		(connect_pads
			(clearance 0.5)
		)
		(min_thickness 0.25)
		(fill yes
			(thermal_gap 0.5)
			(thermal_bridge_width 0.5)
			(island_removal_mode 0)
		)
		(polygon
			(pts
				(xy 97.4852 -75.7936) (xy 97.1042 -76.1746) (xy 95.5294 -76.1746) (xy 94.1324 -76.1746) (xy 94.0562 -76.2508)
				(xy 94.0562 -77.1906) (xy 93.8022 -77.4446) (xy 93.8022 -77.9018) (xy 93.8022 -79.1464) (xy 93.9038 -79.248)
				(xy 94.7674 -79.248) (xy 94.8182 -79.1972) (xy 94.8182 -78.994) (xy 94.8182 -78.1558) (xy 95.123 -77.851)
				(xy 95.25 -77.724) (xy 95.631 -77.724) (xy 98.298 -77.724) (xy 99.0092 -77.0128) (xy 99.0092 -75.819)
				(xy 98.9838 -75.7936)
			)
		)
	)
	(zone
		(layer "F.Cu")
		(hatch none 0.5)
		(connect_pads
			(clearance 0)
		)
		(min_thickness 0.25)
		(keepout
			(tracks allowed)
			(vias allowed)
			(pads allowed)
			(copperpour allowed)
			(footprints not_allowed)
		)
		(placement
			(enabled no)
			(sheetname "")
		)
		(fill
			(thermal_gap 0.5)
			(thermal_bridge_width 0.5)
			(island_removal_mode 0)
		)
		(polygon
			(pts
				(xy 137.150094 -110.149894) (xy 12.7 -110.149894) (xy 12.7 -89.7001) (xy 0.999998 -89.7001) (xy 0 -89.7001)
				(xy 0 -13.750036) (xy 0.999998 -13.750036) (xy 150.200106 -13.750036) (xy 150.200106 -15.100046)
				(xy 155.450032 -15.100046) (xy 155.450032 -13.750036) (xy 157.619954 -13.750036) (xy 157.619954 -22.899878)
				(xy 167.649906 -22.899878)
				(arc
					(start 167.649906 -60.325)
					(mid 167.503587 -60.678627)
					(end 167.150034 -60.825126)
				)
				(arc
					(start 166.931594 -60.825126)
					(mid 166.578131 -60.971535)
					(end 166.431722 -61.324998)
				)
				(arc
					(start 166.431722 -71.799958)
					(mid 166.578026 -72.153675)
					(end 166.931594 -72.300084)
				)
				(arc
					(start 167.150034 -72.300084)
					(mid 167.503497 -72.446493)
					(end 167.649906 -72.799956)
				)
				(xy 167.649906 -99.70008) (xy 157.619954 -99.70008) (xy 157.619954 -110.149894)
			)
		)
	)
	(zone
		(layer "F.Cu")
		(hatch none 0.5)
		(connect_pads
			(clearance 0)
		)
		(min_thickness 0.25)
		(keepout
			(tracks allowed)
			(vias allowed)
			(pads allowed)
			(copperpour allowed)
			(footprints allowed)
		)
		(placement
			(enabled no)
			(sheetname "")
		)
		(fill
			(thermal_gap 0.5)
			(thermal_bridge_width 0.5)
			(island_removal_mode 0)
		)
		(polygon
			(pts
				(xy 87.249 -61.214) (xy 87.249 -59.944) (xy 89.281 -59.944) (xy 89.281 -61.214)
			)
		)
	)
	(zone
		(layer "F.Cu")
		(hatch none 0.5)
		(connect_pads
			(clearance 0)
		)
		(min_thickness 0.25)
		(keepout
			(tracks allowed)
			(vias allowed)
			(pads allowed)
			(copperpour allowed)
			(footprints allowed)
		)
		(placement
			(enabled no)
			(sheetname "")
		)
		(fill
			(thermal_gap 0.5)
			(thermal_bridge_width 0.5)
			(island_removal_mode 0)
		)
		(polygon
			(pts
				(xy 13.5636 -68.453) (xy 12.2682 -68.453) (xy 12.2682 -67.7418) (xy 13.5636 -67.7418)
			)
		)
	)
	(zone
		(net "XP1R0V_FPGA")
		(layer "F.Cu")
		(hatch none 0.5)
		(connect_pads
			(clearance 0.5)
		)
		(min_thickness 0.25)
		(fill yes
			(thermal_gap 0.5)
			(thermal_bridge_width 0.5)
			(island_removal_mode 0)
		)
		(polygon
			(pts
				(xy 88.646 -40.259) (xy 89.789 -40.259) (xy 91.186 -40.259) (xy 91.313 -40.132) (xy 91.948 -39.497)
				(xy 91.948 -39.116) (xy 91.948 -36.576) (xy 90.551 -36.576) (xy 88.646 -38.481)
			)
		)
	)
	(zone
		(layer "F.Cu")
		(hatch none 0.5)
		(connect_pads
			(clearance 0)
		)
		(min_thickness 0.25)
		(keepout
			(tracks allowed)
			(vias allowed)
			(pads allowed)
			(copperpour allowed)
			(footprints allowed)
		)
		(placement
			(enabled no)
			(sheetname "")
		)
		(fill
			(thermal_gap 0.5)
			(thermal_bridge_width 0.5)
			(island_removal_mode 0)
		)
		(polygon
			(pts
				(xy 89.408 -100.457) (xy 89.408 -100.076) (xy 90.297 -100.076) (xy 90.297 -100.457)
			)
		)
	)
	(zone
		(net "XP3R3V_FPGA")
		(layer "F.Cu")
		(hatch none 0.5)
		(connect_pads
			(clearance 0.5)
		)
		(min_thickness 0.25)
		(fill yes
			(thermal_gap 0.5)
			(thermal_bridge_width 0.5)
			(island_removal_mode 0)
		)
		(polygon
			(pts
				(xy 114.808 -98.044) (xy 116.078 -98.044) (xy 116.459 -98.425) (xy 117.094 -98.425) (xy 117.094 -96.901)
				(xy 117.475 -96.52) (xy 117.475 -88.773) (xy 120.396 -85.852) (xy 120.396 -77.47) (xy 118.745 -75.819)
				(xy 118.491 -75.565) (xy 117.729 -75.565) (xy 117.221 -76.073) (xy 116.459 -76.835) (xy 116.459 -77.343)
				(xy 117.475 -78.359) (xy 117.475 -83.058) (xy 116.713 -83.82) (xy 114.173 -83.82) (xy 113.792 -84.201)
				(xy 113.792 -86.995) (xy 114.808 -88.011) (xy 114.808 -91.567) (xy 113.665 -92.71) (xy 113.665 -94.742)
				(xy 114.808 -95.885) (xy 114.808 -96.647)
			)
		)
	)
	(zone
		(net "SG")
		(layer "F.Cu")
		(hatch none 0.5)
		(connect_pads
			(clearance 0.5)
		)
		(min_thickness 0.25)
		(fill yes
			(thermal_gap 0.5)
			(thermal_bridge_width 0.5)
			(island_removal_mode 0)
		)
		(polygon
			(pts
				(xy 85.0392 -101.0158) (xy 85.0392 -99.8728) (xy 84.9122 -99.7458) (xy 84.6582 -99.7458) (xy 84.4042 -99.4918)
				(xy 84.4042 -98.3488) (xy 84.0232 -97.9678) (xy 84.0232 -96.4438) (xy 84.953348 -95.513652) (xy 87.212932 -95.513652)
				(xy 88.058498 -94.668086) (xy 89.017348 -94.668086) (xy 89.037922 -94.647512) (xy 89.037922 -93.778324)
				(xy 83.634326 -93.778324) (xy 83.458812 -93.60281) (xy 82.503772 -93.60281) (xy 82.3722 -93.734382)
				(xy 82.3722 -96.4438) (xy 82.3722 -98.3488) (xy 82.3722 -98.7298) (xy 82.3722 -100.8888) (xy 82.6262 -101.1428)
				(xy 82.8802 -101.1428) (xy 83.1342 -101.1428) (xy 84.9122 -101.1428)
			)
		)
	)
	(zone
		(layer "F.Cu")
		(hatch none 0.5)
		(connect_pads
			(clearance 0)
		)
		(min_thickness 0.25)
		(keepout
			(tracks allowed)
			(vias allowed)
			(pads allowed)
			(copperpour allowed)
			(footprints allowed)
		)
		(placement
			(enabled no)
			(sheetname "")
		)
		(fill
			(thermal_gap 0.5)
			(thermal_bridge_width 0.5)
			(island_removal_mode 0)
		)
		(polygon
			(pts
				(xy 103.378 -103.124) (xy 101.854 -103.124) (xy 100.838 -103.124) (xy 100.838 -101.473) (xy 101.854 -101.473)
				(xy 101.854 -99.568) (xy 103.378 -99.568)
			)
		)
	)
	(zone
		(net "XP5R0V_USB_CONN")
		(layer "F.Cu")
		(hatch none 0.5)
		(connect_pads
			(clearance 0.5)
		)
		(min_thickness 0.25)
		(fill yes
			(thermal_gap 0.5)
			(thermal_bridge_width 0.5)
			(island_removal_mode 0)
		)
		(polygon
			(pts
				(xy 157.3022 -51.021996) (xy 160.6042 -51.021996) (xy 161.6202 -52.037996) (xy 163.3474 -52.037996)
				(xy 163.4236 -52.114196) (xy 163.4236 -52.444396) (xy 163.322 -52.545996) (xy 157.3784 -52.545996)
				(xy 157.1752 -52.342796) (xy 157.1752 -51.148996)
			)
		)
	)
	(zone
		(layer "F.Cu")
		(hatch none 0.5)
		(connect_pads
			(clearance 0)
		)
		(min_thickness 0.25)
		(keepout
			(tracks allowed)
			(vias allowed)
			(pads allowed)
			(copperpour allowed)
			(footprints allowed)
		)
		(placement
			(enabled no)
			(sheetname "")
		)
		(fill
			(thermal_gap 0.5)
			(thermal_bridge_width 0.5)
			(island_removal_mode 0)
		)
		(polygon
			(pts
				(xy 150.749 -55.372) (xy 150.749 -49.911) (xy 153.162 -49.911) (xy 153.162 -55.372)
			)
		)
	)
	(zone
		(layer "F.Cu")
		(hatch none 0.5)
		(connect_pads
			(clearance 0)
		)
		(min_thickness 0.25)
		(keepout
			(tracks allowed)
			(vias allowed)
			(pads allowed)
			(copperpour allowed)
			(footprints allowed)
		)
		(placement
			(enabled no)
			(sheetname "")
		)
		(fill
			(thermal_gap 0.5)
			(thermal_bridge_width 0.5)
			(island_removal_mode 0)
		)
		(polygon
			(pts
				(xy 92.075 -59.817) (xy 92.075 -58.801) (xy 92.583 -58.801) (xy 92.583 -59.817)
			)
		)
	)
	(zone
		(layer "F.Cu")
		(hatch none 0.5)
		(connect_pads
			(clearance 0)
		)
		(min_thickness 0.25)
		(keepout
			(tracks allowed)
			(vias allowed)
			(pads allowed)
			(copperpour allowed)
			(footprints not_allowed)
		)
		(placement
			(enabled no)
			(sheetname "")
		)
		(fill
			(thermal_gap 0.5)
			(thermal_bridge_width 0.5)
			(island_removal_mode 0)
		)
		(polygon
			(pts
				(arc
					(start 25.750012 -21.699982)
					(mid 26.189314 -20.639414)
					(end 27.249882 -20.200112)
				)
				(arc
					(start 77.049884 -20.200112)
					(mid 78.110706 -20.639309)
					(end 78.550008 -21.699982)
				)
				(xy 78.550008 -46.746922) (xy 75.759818 -46.746922)
				(arc
					(start 75.759818 -41.635172)
					(mid 75.527334 -41.073906)
					(end 74.966068 -40.841422)
				)
				(arc
					(start 69.695568 -40.841422)
					(mid 69.134302 -41.073906)
					(end 68.901818 -41.635172)
				)
				(arc
					(start 68.901818 -51.858672)
					(mid 69.134302 -52.419938)
					(end 69.695568 -52.652422)
				)
				(arc
					(start 74.966068 -52.652422)
					(mid 75.527334 -52.419938)
					(end 75.759818 -51.858672)
				)
				(xy 75.759818 -48.329596) (xy 78.550008 -48.329596)
				(arc
					(start 78.550008 -71.499984)
					(mid 78.110632 -72.560732)
					(end 77.049884 -73.000108)
				)
				(arc
					(start 27.249882 -73.000108)
					(mid 26.189388 -72.560627)
					(end 25.750012 -71.499984)
				)
			)
		)
	)
	(zone
		(layer "F.Cu")
		(hatch none 0.5)
		(connect_pads
			(clearance 0)
		)
		(min_thickness 0.25)
		(keepout
			(tracks allowed)
			(vias allowed)
			(pads allowed)
			(copperpour allowed)
			(footprints allowed)
		)
		(placement
			(enabled no)
			(sheetname "")
		)
		(fill
			(thermal_gap 0.5)
			(thermal_bridge_width 0.5)
			(island_removal_mode 0)
		)
		(polygon
			(pts
				(xy 106.299 -75.4634) (xy 106.299 -70.612) (xy 113.0808 -70.612) (xy 113.0808 -75.4634)
			)
		)
	)
	(zone
		(layer "F.Cu")
		(hatch none 0.5)
		(connect_pads
			(clearance 0)
		)
		(min_thickness 0.25)
		(keepout
			(tracks allowed)
			(vias allowed)
			(pads allowed)
			(copperpour allowed)
			(footprints allowed)
		)
		(placement
			(enabled no)
			(sheetname "")
		)
		(fill
			(thermal_gap 0.5)
			(thermal_bridge_width 0.5)
			(island_removal_mode 0)
		)
		(polygon
			(pts
				(xy 43.307 -73.914) (xy 43.307 -73.406) (xy 44.323 -73.406) (xy 44.323 -73.914)
			)
		)
	)
	(zone
		(layer "F.Cu")
		(hatch none 0.5)
		(connect_pads
			(clearance 0)
		)
		(min_thickness 0.25)
		(keepout
			(tracks allowed)
			(vias allowed)
			(pads allowed)
			(copperpour allowed)
			(footprints not_allowed)
		)
		(placement
			(enabled no)
			(sheetname "")
		)
		(fill
			(thermal_gap 0.5)
			(thermal_bridge_width 0.5)
			(island_removal_mode 0)
		)
		(polygon
			(pts
				(xy 79.30007 -13.750036) (xy 44.99991 -13.750036) (xy 44.99991 -0.500126) (xy 45.500036 0) (xy 55.699914 0)
				(xy 56.20004 -0.500126)
				(arc
					(start 56.20004 -7.450074)
					(mid 57.15 -8.400034)
					(end 58.09996 -7.450074)
				)
				(xy 58.09996 -0.500126) (xy 58.600086 0) (xy 78.799944 0) (xy 79.30007 -0.500126)
			)
		)
	)
	(zone
		(layer "F.Cu")
		(hatch none 0.5)
		(connect_pads
			(clearance 0)
		)
		(min_thickness 0.25)
		(keepout
			(tracks allowed)
			(vias allowed)
			(pads allowed)
			(copperpour allowed)
			(footprints allowed)
		)
		(placement
			(enabled no)
			(sheetname "")
		)
		(fill
			(thermal_gap 0.5)
			(thermal_bridge_width 0.5)
			(island_removal_mode 0)
		)
		(polygon
			(pts
				(xy 137.287 -57.4548) (xy 137.287 -51.2064) (xy 145.1356 -51.2064) (xy 145.1356 -57.4548)
			)
		)
	)
	(zone
		(layer "F.Cu")
		(hatch none 0.5)
		(connect_pads
			(clearance 0)
		)
		(min_thickness 0.25)
		(keepout
			(tracks allowed)
			(vias allowed)
			(pads allowed)
			(copperpour allowed)
			(footprints allowed)
		)
		(placement
			(enabled no)
			(sheetname "")
		)
		(fill
			(thermal_gap 0.5)
			(thermal_bridge_width 0.5)
			(island_removal_mode 0)
		)
		(polygon
			(pts
				(xy 12.874752 -34.957004) (xy 12.874752 -32.925004) (xy 14.525752 -32.925004) (xy 14.525752 -34.957004)
			)
		)
	)
	(zone
		(layer "F.Cu")
		(hatch none 0.5)
		(connect_pads
			(clearance 0)
		)
		(min_thickness 0.25)
		(keepout
			(tracks allowed)
			(vias allowed)
			(pads allowed)
			(copperpour allowed)
			(footprints allowed)
		)
		(placement
			(enabled no)
			(sheetname "")
		)
		(fill
			(thermal_gap 0.5)
			(thermal_bridge_width 0.5)
			(island_removal_mode 0)
		)
		(polygon
			(pts
				(xy 12.7762 -20.48383) (xy 12.7762 -18.45183) (xy 14.4272 -18.45183) (xy 14.4272 -20.48383)
			)
		)
	)
	(zone
		(layer "F.Cu")
		(hatch none 0.5)
		(connect_pads
			(clearance 0)
		)
		(min_thickness 0.25)
		(keepout
			(tracks allowed)
			(vias allowed)
			(pads allowed)
			(copperpour allowed)
			(footprints not_allowed)
		)
		(placement
			(enabled no)
			(sheetname "")
		)
		(fill
			(thermal_gap 0.5)
			(thermal_bridge_width 0.5)
			(island_removal_mode 0)
		)
		(polygon
			(pts
				(xy 122.00001 -75.797156) (xy 68.49999 -75.798934) (xy 68.49999 -83.462622) (xy 72.38365 -83.462622)
				(xy 72.38365 -92.68333) (xy 62.147958 -92.68333) (xy 62.14872 -101.149912)
				(arc
					(start 65.000124 -101.149912)
					(mid 67.475083 -102.175073)
					(end 68.49999 -104.650032)
				)
				(xy 68.49999 -107.546394) (xy 122.00001 -107.549696) (xy 122.00001 -100.823522) (xy 119.73052 -100.823522)
				(xy 119.73052 -91.418156) (xy 126.946406 -91.418156) (xy 129.32156 -91.418156) (xy 129.322576 -82.14995)
				(arc
					(start 125.499876 -82.14995)
					(mid 123.025097 -81.124863)
					(end 122.00001 -78.650084)
				)
			)
		)
	)
	(zone
		(layer "F.Cu")
		(hatch none 0.5)
		(connect_pads
			(clearance 0)
		)
		(min_thickness 0.25)
		(keepout
			(tracks allowed)
			(vias allowed)
			(pads allowed)
			(copperpour allowed)
			(footprints allowed)
		)
		(placement
			(enabled no)
			(sheetname "")
		)
		(fill
			(thermal_gap 0.5)
			(thermal_bridge_width 0.5)
			(island_removal_mode 0)
		)
		(polygon
			(pts
				(xy 136.398 -101.6762) (xy 136.398 -94.05112) (xy 132.82168 -94.05112) (xy 132.82168 -93.97492)
				(xy 132.57276 -93.726) (xy 132.57276 -91.23426) (xy 132.97662 -90.8304) (xy 137.44956 -90.8304)
				(xy 138.14298 -90.13698) (xy 139.57046 -90.13698) (xy 139.64666 -90.21318) (xy 139.64666 -90.87358)
				(xy 140.06068 -91.2876) (xy 141.8209 -91.2876) (xy 141.8209 -91.4908) (xy 142.3543 -92.0242) (xy 145.288 -92.0242)
				(xy 145.288 -101.6762)
			)
		)
	)
	(zone
		(layer "F.Cu")
		(hatch none 0.5)
		(connect_pads
			(clearance 0)
		)
		(min_thickness 0.25)
		(keepout
			(tracks allowed)
			(vias allowed)
			(pads allowed)
			(copperpour allowed)
			(footprints allowed)
		)
		(placement
			(enabled no)
			(sheetname "")
		)
		(fill
			(thermal_gap 0.5)
			(thermal_bridge_width 0.5)
			(island_removal_mode 0)
		)
		(polygon
			(pts
				(xy 125.603 -70.739) (xy 125.603 -70.3326) (xy 126.5174 -70.3326) (xy 126.5174 -70.739)
			)
		)
	)
	(zone
		(net "SG")
		(layer "F.Cu")
		(hatch none 0.5)
		(connect_pads
			(clearance 0.5)
		)
		(min_thickness 0.25)
		(fill yes
			(thermal_gap 0.5)
			(thermal_bridge_width 0.5)
			(island_removal_mode 0)
		)
		(polygon
			(pts
				(xy 136.779 -90.551) (xy 137.287 -90.043) (xy 137.287 -86.1314) (xy 137.287 -81.2038) (xy 137.287 -80.772)
				(xy 137.1346 -80.6196) (xy 133.6802 -80.6196) (xy 133.5278 -80.772) (xy 133.5278 -81.0006) (xy 133.5278 -90.1446)
				(xy 133.9342 -90.551)
			)
		)
	)
	(zone
		(net "SG")
		(layer "F.Cu")
		(hatch none 0.5)
		(connect_pads
			(clearance 0.5)
		)
		(min_thickness 0.25)
		(fill yes
			(thermal_gap 0.5)
			(thermal_bridge_width 0.5)
			(island_removal_mode 0)
		)
		(polygon
			(pts
				(xy 105.4608 -75.2602) (xy 105.4608 -72.0598) (xy 105.4608 -70.4596) (xy 105.3338 -70.3326) (xy 104.013 -70.3326)
				(xy 103.6066 -70.739) (xy 103.6066 -75.057) (xy 103.9622 -75.4126) (xy 105.3084 -75.4126)
			)
		)
	)
	(zone
		(net "SG")
		(layer "F.Cu")
		(hatch none 0.5)
		(connect_pads
			(clearance 0.5)
		)
		(min_thickness 0.25)
		(fill yes
			(thermal_gap 0.5)
			(thermal_bridge_width 0.5)
			(island_removal_mode 0)
		)
		(polygon
			(pts
				(xy 41.9608 -77.47) (xy 43.434 -77.47) (xy 43.434 -74.3712) (xy 43.2054 -74.1426) (xy 43.2054 -73.533)
				(xy 36.322 -73.533) (xy 35.687 -74.168) (xy 35.687 -76.3524) (xy 36.2204 -76.8858) (xy 37.719 -76.8858)
				(xy 38.0746 -76.5302) (xy 38.0746 -74.422) (xy 38.2016 -74.295) (xy 40.386 -74.295) (xy 40.64 -74.549)
				(xy 40.64 -75.692) (xy 41.9354 -75.692) (xy 41.9608 -75.7174)
			)
		)
	)
	(zone
		(net "SG")
		(layer "F.Cu")
		(hatch none 0.5)
		(connect_pads
			(clearance 0.5)
		)
		(min_thickness 0.25)
		(fill yes
			(thermal_gap 0.5)
			(thermal_bridge_width 0.5)
			(island_removal_mode 0)
		)
		(polygon
			(pts
				(xy 97.028 -75.5396) (xy 100.6602 -75.5396) (xy 101.1174 -75.5396) (xy 101.219 -75.438) (xy 101.219 -72.6948)
				(xy 101.1428 -72.6186) (xy 100.3046 -72.6186) (xy 100.203 -72.7202) (xy 100.203 -73.9648) (xy 100.076 -74.0918)
				(xy 97.5614 -74.0918) (xy 97.3328 -74.0918) (xy 97.155 -73.914) (xy 97.155 -73.279) (xy 96.9772 -73.1012)
				(xy 95.9866 -73.1012) (xy 95.6056 -73.1012) (xy 95.504 -72.9996) (xy 95.504 -72.4662) (xy 95.4278 -72.39)
				(xy 91.7702 -72.39) (xy 91.567 -72.5932) (xy 91.567 -72.898) (xy 91.567 -75.565) (xy 91.7448 -75.7428)
				(xy 93.7514 -75.7428) (xy 94.0308 -75.4634) (xy 95.8088 -75.4634) (xy 95.885 -75.5396)
			)
		)
	)
	(zone
		(net "XP3R3V_FPGA")
		(layer "F.Cu")
		(hatch none 0.5)
		(connect_pads
			(clearance 0.5)
		)
		(min_thickness 0.25)
		(fill yes
			(thermal_gap 0.5)
			(thermal_bridge_width 0.5)
			(island_removal_mode 0)
		)
		(polygon
			(pts
				(xy 118.9736 -62.5094) (xy 118.9736 -60.9854) (xy 118.999 -60.96) (xy 119.2657 -60.6933) (xy 119.507 -60.452)
				(xy 121.539 -60.452) (xy 121.8692 -60.7822) (xy 121.8692 -62.4586) (xy 121.7422 -62.5856) (xy 119.0498 -62.5856)
			)
		)
	)
	(zone
		(layer "F.Cu")
		(hatch none 0.5)
		(connect_pads
			(clearance 0)
		)
		(min_thickness 0.25)
		(keepout
			(tracks allowed)
			(vias allowed)
			(pads allowed)
			(copperpour allowed)
			(footprints allowed)
		)
		(placement
			(enabled no)
			(sheetname "")
		)
		(fill
			(thermal_gap 0.5)
			(thermal_bridge_width 0.5)
			(island_removal_mode 0)
		)
		(polygon
			(pts
				(xy 12.7 -63.754) (xy 12.7 -62.4078) (xy 14.351 -62.4078) (xy 14.351 -63.754)
			)
		)
	)
	(zone
		(net "SG")
		(layer "F.Cu")
		(hatch none 0.5)
		(connect_pads
			(clearance 0.5)
		)
		(min_thickness 0.25)
		(fill yes
			(thermal_gap 0.5)
			(thermal_bridge_width 0.5)
			(island_removal_mode 0)
		)
		(polygon
			(pts
				(xy 25.2222 -67.7926) (xy 24.1046 -67.7926) (xy 24.0284 -67.8688) (xy 23.7998 -68.0974) (xy 23.7998 -69.6722)
				(xy 23.9522 -69.8246) (xy 25.2222 -69.8246) (xy 25.3492 -69.6976) (xy 25.3492 -69.3674) (xy 25.3492 -67.9196)
			)
		)
	)
	(zone
		(net "XP1R8V_FPGA_VCCAUX")
		(layer "F.Cu")
		(hatch none 0.5)
		(connect_pads
			(clearance 0.5)
		)
		(min_thickness 0.25)
		(fill yes
			(thermal_gap 0.5)
			(thermal_bridge_width 0.5)
			(island_removal_mode 0)
		)
		(polygon
			(pts
				(xy 93.472 -54.991) (xy 93.472 -57.023) (xy 93.472 -57.785) (xy 93.599 -57.912) (xy 95.885 -57.912)
				(xy 96.393 -57.404) (xy 96.393 -56.769) (xy 96.393 -55.245) (xy 96.139 -54.991)
			)
		)
	)
	(zone
		(net "SG")
		(layer "F.Cu")
		(hatch none 0.5)
		(connect_pads
			(clearance 0.5)
		)
		(min_thickness 0.25)
		(fill yes
			(thermal_gap 0.5)
			(thermal_bridge_width 0.5)
			(island_removal_mode 0)
		)
		(polygon
			(pts
				(xy 111.252 -68.834) (xy 111.633 -68.834) (xy 112.141 -68.326) (xy 113.792 -68.326) (xy 113.792 -66.802)
				(xy 113.538 -66.548) (xy 111.633 -66.548) (xy 111.252 -66.929)
			)
		)
	)
	(zone
		(net "SG")
		(layer "F.Cu")
		(hatch none 0.5)
		(connect_pads
			(clearance 0.5)
		)
		(min_thickness 0.25)
		(fill yes
			(thermal_gap 0.5)
			(thermal_bridge_width 0.5)
			(island_removal_mode 0)
		)
		(polygon
			(pts
				(xy 43.0784 -106.3244) (xy 58.9026 -106.3244) (xy 59.436 -105.791) (xy 59.436 -97.5614) (xy 56.7436 -94.869)
				(xy 43.9674 -94.869) (xy 43.8404 -94.996) (xy 43.8404 -96.6724) (xy 43.3324 -97.1804) (xy 43.3324 -98.3234)
				(xy 43.0784 -98.5774) (xy 42.0624 -98.5774) (xy 41.9354 -98.7044) (xy 41.9354 -99.8474) (xy 42.0624 -99.9744)
				(xy 43.3324 -99.9744) (xy 45.5168 -97.79) (xy 56.0578 -97.79) (xy 56.1594 -97.6884) (xy 57.785 -97.6884)
				(xy 58.6232 -98.5266) (xy 58.6232 -103.378) (xy 58.3438 -103.6574) (xy 54.2544 -103.6574) (xy 54.1528 -103.759)
				(xy 44.958 -103.759) (xy 44.6024 -103.4034) (xy 44.6024 -101.7524) (xy 44.3484 -101.4984) (xy 42.0624 -101.4984)
				(xy 41.9354 -101.6254) (xy 41.9354 -102.7684) (xy 42.5704 -103.4034) (xy 42.5704 -104.2924) (xy 42.9514 -104.6734)
				(xy 42.9514 -106.1974)
			)
		)
	)
	(zone
		(net "XP3R3V")
		(layer "F.Cu")
		(hatch none 0.5)
		(connect_pads
			(clearance 0.5)
		)
		(min_thickness 0.25)
		(fill yes
			(thermal_gap 0.5)
			(thermal_bridge_width 0.5)
			(island_removal_mode 0)
		)
		(polygon
			(pts
				(xy 127.7112 -61.2902) (xy 127.7112 -62.5094) (xy 127.7112 -62.9158) (xy 127.6096 -63.0174) (xy 124.8918 -63.0174)
				(xy 124.8156 -62.9412) (xy 124.8156 -62.5094) (xy 124.8156 -61.0108) (xy 124.968 -60.8584) (xy 127.5588 -60.8584)
				(xy 127.7112 -61.0108)
			)
		)
	)
	(zone
		(net "SG")
		(layer "F.Cu")
		(hatch none 0.5)
		(connect_pads
			(clearance 0.5)
		)
		(min_thickness 0.25)
		(fill yes
			(thermal_gap 0.5)
			(thermal_bridge_width 0.5)
			(island_removal_mode 0)
		)
		(polygon
			(pts
				(xy 135.0518 -97.7138) (xy 135.0518 -96.52) (xy 135.0518 -96.4184) (xy 135.7122 -95.758) (xy 136.1694 -95.758)
				(xy 136.271 -95.6564) (xy 136.271 -94.5642) (xy 136.144 -94.4372) (xy 132.8928 -94.4372) (xy 132.6388 -94.6912)
				(xy 132.6388 -94.8944) (xy 132.6388 -97.6376) (xy 132.9182 -97.917) (xy 134.8486 -97.917)
			)
		)
	)
	(zone
		(layer "F.Cu")
		(hatch none 0.5)
		(connect_pads
			(clearance 0)
		)
		(min_thickness 0.25)
		(keepout
			(tracks allowed)
			(vias allowed)
			(pads allowed)
			(copperpour allowed)
			(footprints allowed)
		)
		(placement
			(enabled no)
			(sheetname "")
		)
		(fill
			(thermal_gap 0.5)
			(thermal_bridge_width 0.5)
			(island_removal_mode 0)
		)
		(polygon
			(pts
				(xy 81.788 -105.6386) (xy 81.788 -98.3488) (xy 88.646 -98.3488) (xy 88.646 -105.6386)
			)
		)
	)
	(zone
		(layer "F.Cu")
		(hatch none 0.5)
		(connect_pads
			(clearance 0)
		)
		(min_thickness 0.25)
		(keepout
			(tracks allowed)
			(vias allowed)
			(pads allowed)
			(copperpour allowed)
			(footprints allowed)
		)
		(placement
			(enabled no)
			(sheetname "")
		)
		(fill
			(thermal_gap 0.5)
			(thermal_bridge_width 0.5)
			(island_removal_mode 0)
		)
		(polygon
			(pts
				(xy 19.685 -57.785) (xy 19.685 -56.9468) (xy 20.6248 -56.9468) (xy 20.6248 -57.785)
			)
		)
	)
	(zone
		(layer "F.Cu")
		(hatch none 0.5)
		(connect_pads
			(clearance 0)
		)
		(min_thickness 0.25)
		(keepout
			(tracks allowed)
			(vias allowed)
			(pads allowed)
			(copperpour allowed)
			(footprints allowed)
		)
		(placement
			(enabled no)
			(sheetname "")
		)
		(fill
			(thermal_gap 0.5)
			(thermal_bridge_width 0.5)
			(island_removal_mode 0)
		)
		(polygon
			(pts
				(xy 100.33 -89.027) (xy 100.33 -88.011) (xy 101.981 -88.011) (xy 101.981 -89.027)
			)
		)
	)
	(zone
		(net "XP2R5V_FPGA")
		(layer "F.Cu")
		(hatch none 0.5)
		(connect_pads
			(clearance 0.5)
		)
		(min_thickness 0.25)
		(fill yes
			(thermal_gap 0.5)
			(thermal_bridge_width 0.5)
			(island_removal_mode 0)
		)
		(polygon
			(pts
				(xy 141.859 -17.5514) (xy 140.589 -17.5514) (xy 140.3096 -17.5514) (xy 137.795 -20.066) (xy 137.795 -20.1168)
				(xy 137.795 -20.447) (xy 137.795 -22.352) (xy 138.049 -22.606) (xy 139.7762 -22.606) (xy 139.7762 -22.0472)
				(xy 139.7762 -21.0312) (xy 140.0556 -20.7518) (xy 140.3096 -20.4978) (xy 140.6652 -20.4978) (xy 140.8176 -20.3454)
				(xy 140.8176 -19.1008) (xy 141.0208 -18.8976) (xy 141.8082 -18.8976) (xy 141.9098 -18.796) (xy 141.9098 -17.6022)
			)
		)
	)
	(zone
		(net "XP12R0V_EXT")
		(layer "F.Cu")
		(hatch none 0.5)
		(connect_pads
			(clearance 0.5)
		)
		(min_thickness 0.25)
		(fill yes
			(thermal_gap 0.5)
			(thermal_bridge_width 0.5)
			(island_removal_mode 0)
		)
		(polygon
			(pts
				(xy 24.257 -98.0694) (xy 21.2852 -98.0694) (xy 21.1582 -98.0694) (xy 20.9042 -98.0694) (xy 20.7772 -97.9424)
				(xy 20.7772 -92.3544) (xy 20.9042 -92.2274) (xy 24.257 -92.2274) (xy 24.6888 -92.6592) (xy 24.6888 -97.6376)
			)
		)
	)
	(zone
		(layer "F.Cu")
		(hatch none 0.5)
		(connect_pads
			(clearance 0)
		)
		(min_thickness 0.25)
		(keepout
			(tracks allowed)
			(vias allowed)
			(pads allowed)
			(copperpour allowed)
			(footprints allowed)
		)
		(placement
			(enabled no)
			(sheetname "")
		)
		(fill
			(thermal_gap 0.5)
			(thermal_bridge_width 0.5)
			(island_removal_mode 0)
		)
		(polygon
			(pts
				(xy 70.3072 -49.0728) (xy 70.3072 -47.371) (xy 71.628 -47.371) (xy 71.628 -49.0728)
			)
		)
	)
	(zone
		(layer "F.Cu")
		(hatch none 0.5)
		(connect_pads
			(clearance 0)
		)
		(min_thickness 0.25)
		(keepout
			(tracks allowed)
			(vias allowed)
			(pads allowed)
			(copperpour allowed)
			(footprints allowed)
		)
		(placement
			(enabled no)
			(sheetname "")
		)
		(fill
			(thermal_gap 0.5)
			(thermal_bridge_width 0.5)
			(island_removal_mode 0)
		)
		(polygon
			(pts
				(xy 19.5834 -62.4332) (xy 19.5834 -60.8076) (xy 20.7772 -60.8076) (xy 20.7772 -62.4332)
			)
		)
	)
	(zone
		(layer "F.Cu")
		(hatch none 0.5)
		(connect_pads
			(clearance 0)
		)
		(min_thickness 0.25)
		(keepout
			(tracks allowed)
			(vias allowed)
			(pads allowed)
			(copperpour allowed)
			(footprints allowed)
		)
		(placement
			(enabled no)
			(sheetname "")
		)
		(fill
			(thermal_gap 0.5)
			(thermal_bridge_width 0.5)
			(island_removal_mode 0)
		)
		(polygon
			(pts
				(xy 153.289 -26.035) (xy 153.289 -25.4) (xy 155.067 -25.4) (xy 155.067 -26.035)
			)
		)
	)
	(zone
		(layer "F.Cu")
		(hatch none 0.5)
		(connect_pads
			(clearance 0)
		)
		(min_thickness 0.25)
		(keepout
			(tracks allowed)
			(vias allowed)
			(pads allowed)
			(copperpour allowed)
			(footprints allowed)
		)
		(placement
			(enabled no)
			(sheetname "")
		)
		(fill
			(thermal_gap 0.5)
			(thermal_bridge_width 0.5)
			(island_removal_mode 0)
		)
		(polygon
			(pts
				(xy 87.249 -59.182) (xy 87.249 -58.928) (xy 88.011 -58.928) (xy 88.011 -59.182)
			)
		)
	)
	(zone
		(net "UNNAMED_525_CAPACITOR_I16_1")
		(layer "F.Cu")
		(hatch none 0.5)
		(connect_pads
			(clearance 0.5)
		)
		(min_thickness 0.25)
		(fill yes
			(thermal_gap 0.5)
			(thermal_bridge_width 0.5)
			(island_removal_mode 0)
		)
		(polygon
			(pts
				(xy 43.688 -78.105) (xy 43.688 -79.502) (xy 44.196 -80.01) (xy 46.482 -80.01) (xy 46.863 -79.629)
				(xy 46.863 -78.232) (xy 46.609 -77.978) (xy 46.609 -76.581) (xy 47.117 -76.073) (xy 47.117 -75.438)
				(xy 46.99 -75.311) (xy 46.228 -75.311) (xy 45.847 -75.692) (xy 45.847 -76.073) (xy 45.085 -76.835)
				(xy 43.815 -76.835) (xy 43.688 -76.962)
			)
		)
	)
	(zone
		(net "XP3R3V")
		(layer "F.Cu")
		(hatch none 0.5)
		(connect_pads
			(clearance 0.5)
		)
		(min_thickness 0.25)
		(fill yes
			(thermal_gap 0.5)
			(thermal_bridge_width 0.5)
			(island_removal_mode 0)
		)
		(polygon
			(pts
				(xy 91.9734 -76.3016) (xy 93.1926 -76.3016) (xy 93.3196 -76.4286) (xy 93.3196 -79.0956) (xy 93.1418 -79.2734)
				(xy 91.6178 -79.2734) (xy 91.5162 -79.1718) (xy 91.5162 -76.4794) (xy 91.694 -76.3016)
			)
		)
	)
	(zone
		(net "XP12R0V")
		(layer "F.Cu")
		(hatch none 0.5)
		(connect_pads
			(clearance 0.5)
		)
		(min_thickness 0.25)
		(fill yes
			(thermal_gap 0.5)
			(thermal_bridge_width 0.5)
			(island_removal_mode 0)
		)
		(polygon
			(pts
				(xy 136.271 -57.6326) (xy 136.2964 -57.658) (xy 137.7188 -57.658) (xy 137.9474 -57.8866) (xy 137.9474 -59.4106)
				(xy 137.9474 -59.7916) (xy 137.668 -60.071) (xy 135.4836 -60.071) (xy 134.9883 -59.5757) (xy 134.7216 -59.309)
				(xy 134.7216 -59.2074) (xy 134.7216 -57.7596) (xy 134.8486 -57.6326)
			)
		)
	)
	(zone
		(net "XP12R0V_IN")
		(layer "F.Cu")
		(hatch none 0.5)
		(connect_pads
			(clearance 0.5)
		)
		(min_thickness 0.25)
		(fill yes
			(thermal_gap 0.5)
			(thermal_bridge_width 0.5)
			(island_removal_mode 0)
		)
		(polygon
			(pts
				(xy 140.462 -96.6978) (xy 141.224 -96.6978) (xy 141.3002 -96.6216) (xy 141.3002 -91.5162) (xy 141.4272 -91.3892)
				(xy 142.2908 -91.3892) (xy 142.4686 -91.2114) (xy 142.4686 -89.3572) (xy 142.4686 -88.6206) (xy 142.7226 -88.3666)
				(xy 142.748 -88.3666) (xy 143.51 -87.6046) (xy 143.51 -81.4324) (xy 143.002 -80.9244) (xy 140.208 -80.9244)
				(xy 139.954 -81.1784) (xy 139.954 -88.265) (xy 139.954 -89.535) (xy 140.081 -89.662) (xy 140.081 -91.059)
				(xy 139.954 -91.186) (xy 139.954 -96.52) (xy 140.1318 -96.6978)
			)
		)
	)
	(zone
		(layer "F.Cu")
		(hatch none 0.5)
		(connect_pads
			(clearance 0)
		)
		(min_thickness 0.25)
		(keepout
			(tracks allowed)
			(vias allowed)
			(pads allowed)
			(copperpour allowed)
			(footprints allowed)
		)
		(placement
			(enabled no)
			(sheetname "")
		)
		(fill
			(thermal_gap 0.5)
			(thermal_bridge_width 0.5)
			(island_removal_mode 0)
		)
		(polygon
			(pts
				(xy 109.093 -103.251) (xy 106.934 -103.251) (xy 106.934 -99.695) (xy 109.093 -99.695)
			)
		)
	)
	(zone
		(layer "F.Cu")
		(hatch none 0.5)
		(connect_pads
			(clearance 0)
		)
		(min_thickness 0.25)
		(keepout
			(tracks allowed)
			(vias allowed)
			(pads allowed)
			(copperpour allowed)
			(footprints allowed)
		)
		(placement
			(enabled no)
			(sheetname "")
		)
		(fill
			(thermal_gap 0.5)
			(thermal_bridge_width 0.5)
			(island_removal_mode 0)
		)
		(polygon
			(pts
				(xy 55.3974 -79.0956) (xy 54.2798 -79.0956) (xy 54.2798 -77.343) (xy 55.3974 -77.343)
			)
		)
	)
	(zone
		(layer "F.Cu")
		(hatch none 0.5)
		(connect_pads
			(clearance 0)
		)
		(min_thickness 0.25)
		(keepout
			(tracks allowed)
			(vias allowed)
			(pads allowed)
			(copperpour allowed)
			(footprints allowed)
		)
		(placement
			(enabled no)
			(sheetname "")
		)
		(fill
			(thermal_gap 0.5)
			(thermal_bridge_width 0.5)
			(island_removal_mode 0)
		)
		(polygon
			(pts
				(xy 12.827 -49.36617) (xy 12.827 -47.33417) (xy 14.478 -47.33417) (xy 14.478 -49.36617)
			)
		)
	)
	(zone
		(layer "F.Cu")
		(hatch none 0.5)
		(connect_pads
			(clearance 0)
		)
		(min_thickness 0.25)
		(keepout
			(tracks allowed)
			(vias allowed)
			(pads allowed)
			(copperpour allowed)
			(footprints allowed)
		)
		(placement
			(enabled no)
			(sheetname "")
		)
		(fill
			(thermal_gap 0.5)
			(thermal_bridge_width 0.5)
			(island_removal_mode 0)
		)
		(polygon
			(pts
				(xy 89.408 -104.902) (xy 89.408 -104.394) (xy 90.297 -104.394) (xy 90.297 -104.902)
			)
		)
	)
	(zone
		(net "XP3R3V_FPGA")
		(layer "F.Cu")
		(hatch none 0.5)
		(connect_pads
			(clearance 0.5)
		)
		(min_thickness 0.25)
		(fill yes
			(thermal_gap 0.5)
			(thermal_bridge_width 0.5)
			(island_removal_mode 0)
		)
		(polygon
			(pts
				(xy 88.3412 -64.6938) (xy 88.1888 -64.8462) (xy 88.1888 -66.1924) (xy 88.2015 -66.2051) (xy 88.2015 -66.5099)
				(xy 88.3412 -66.6496) (xy 90.17 -66.6496) (xy 90.3986 -66.421) (xy 90.424 -66.421) (xy 90.424 -64.6557)
				(xy 89.2937 -64.6557) (xy 88.3793 -64.6557)
			)
		)
	)
	(zone
		(layer "F.Cu")
		(hatch none 0.5)
		(connect_pads
			(clearance 0)
		)
		(min_thickness 0.25)
		(keepout
			(tracks allowed)
			(vias allowed)
			(pads allowed)
			(copperpour allowed)
			(footprints allowed)
		)
		(placement
			(enabled no)
			(sheetname "")
		)
		(fill
			(thermal_gap 0.5)
			(thermal_bridge_width 0.5)
			(island_removal_mode 0)
		)
		(polygon
			(pts
				(xy 13.2842 -40.2082) (xy 11.9888 -40.2082) (xy 11.9888 -39.497) (xy 13.2842 -39.497)
			)
		)
	)
	(zone
		(net "SG")
		(layer "F.Cu")
		(hatch none 0.5)
		(connect_pads
			(clearance 0.5)
		)
		(min_thickness 0.25)
		(fill yes
			(thermal_gap 0.5)
			(thermal_bridge_width 0.5)
			(island_removal_mode 0)
		)
		(polygon
			(pts
				(xy 142.621 -54.61) (xy 143.637 -54.61) (xy 143.6624 -54.61) (xy 143.8656 -54.4068) (xy 144.3736 -53.8988)
				(xy 145.084038 -53.8988) (xy 145.48739 -53.495448) (xy 145.9992 -53.495448) (xy 146.976592 -53.495448)
				(xy 146.976592 -51.830478) (xy 146.708114 -51.562) (xy 145.796 -51.562) (xy 143.383 -51.562) (xy 142.621 -52.324)
			)
		)
	)
	(zone
		(layer "F.Cu")
		(hatch none 0.5)
		(connect_pads
			(clearance 0)
		)
		(min_thickness 0.25)
		(keepout
			(tracks allowed)
			(vias allowed)
			(pads allowed)
			(copperpour allowed)
			(footprints allowed)
		)
		(placement
			(enabled no)
			(sheetname "")
		)
		(fill
			(thermal_gap 0.5)
			(thermal_bridge_width 0.5)
			(island_removal_mode 0)
		)
		(polygon
			(pts
				(xy 12.3952 -25.019) (xy 13.6906 -25.019) (xy 13.6906 -25.7302) (xy 12.3952 -25.7302)
			)
		)
	)
	(zone
		(layer "F.Cu")
		(hatch none 0.5)
		(connect_pads
			(clearance 0)
		)
		(min_thickness 0.25)
		(keepout
			(tracks allowed)
			(vias allowed)
			(pads allowed)
			(copperpour allowed)
			(footprints allowed)
		)
		(placement
			(enabled no)
			(sheetname "")
		)
		(fill
			(thermal_gap 0.5)
			(thermal_bridge_width 0.5)
			(island_removal_mode 0)
		)
		(polygon
			(pts
				(xy 30.607 -96.52) (xy 30.607 -96.012) (xy 31.623 -96.012) (xy 31.623 -96.52)
			)
		)
	)
	(zone
		(layer "F.Cu")
		(hatch none 0.5)
		(connect_pads
			(clearance 0)
		)
		(min_thickness 0.25)
		(keepout
			(tracks allowed)
			(vias allowed)
			(pads allowed)
			(copperpour allowed)
			(footprints allowed)
		)
		(placement
			(enabled no)
			(sheetname "")
		)
		(fill
			(thermal_gap 0.5)
			(thermal_bridge_width 0.5)
			(island_removal_mode 0)
		)
		(polygon
			(pts
				(xy 126.619 -71.0438) (xy 126.619 -66.2432) (xy 133.0452 -66.2432) (xy 133.0452 -71.0438)
			)
		)
	)
	(zone
		(net "SG")
		(layer "F.Cu")
		(hatch none 0.5)
		(connect_pads
			(clearance 0.5)
		)
		(min_thickness 0.25)
		(fill yes
			(thermal_gap 0.5)
			(thermal_bridge_width 0.5)
			(island_removal_mode 0)
		)
		(polygon
			(pts
				(xy 46.482 -73.025) (xy 26.924 -73.025) (xy 25.908 -72.009) (xy 25.908 -21.336) (xy 26.924 -20.32)
				(xy 44.196 -20.32) (xy 45.974 -22.098) (xy 57.15 -22.098) (xy 58.928 -20.32) (xy 77.47 -20.32) (xy 78.359 -21.209)
				(xy 78.359 -39.37) (xy 77.47 -40.259) (xy 68.707 -40.259) (xy 68.072 -40.894) (xy 68.072 -41.402)
				(xy 68.072 -52.578) (xy 68.961 -53.467) (xy 70.231 -54.737) (xy 77.978 -54.737) (xy 78.486 -55.245)
				(xy 78.486 -71.755) (xy 77.343 -72.898) (xy 52.578 -72.898) (xy 51.816 -73.66) (xy 51.816 -78.994)
				(xy 52.197 -79.375) (xy 55.88 -79.375) (xy 56.134 -79.629) (xy 56.134 -81.026) (xy 56.134 -81.661)
				(xy 56.007 -81.788) (xy 51.435 -81.788) (xy 50.927 -81.788) (xy 50.419 -81.28) (xy 49.657 -80.518)
				(xy 49.403 -80.264) (xy 49.403 -74.422) (xy 49.149 -74.168) (xy 48.006 -73.025)
			)
		)
	)
	(zone
		(net "VIN_XP1R0V")
		(layer "F.Cu")
		(hatch none 0.5)
		(connect_pads
			(clearance 0.5)
		)
		(min_thickness 0.25)
		(fill yes
			(thermal_gap 0.5)
			(thermal_bridge_width 0.5)
			(island_removal_mode 0)
		)
		(polygon
			(pts
				(xy 142.367 -54.991) (xy 142.367 -55.245) (xy 142.494 -55.372) (xy 143.51 -55.372) (xy 144.145 -55.372)
				(xy 144.272 -55.499) (xy 144.272 -55.8038) (xy 144.653 -56.1848) (xy 146.304 -56.1848) (xy 146.4564 -56.0324)
				(xy 146.4564 -54.6354) (xy 146.05 -54.229) (xy 144.4498 -54.229) (xy 144.3482 -54.3306) (xy 144.3482 -54.4576)
				(xy 144.145 -54.6608) (xy 143.9418 -54.864) (xy 143.891 -54.864) (xy 142.494 -54.864)
			)
		)
	)
	(zone
		(layer "F.Cu")
		(hatch none 0.5)
		(connect_pads
			(clearance 0)
		)
		(min_thickness 0.25)
		(keepout
			(tracks allowed)
			(vias allowed)
			(pads allowed)
			(copperpour allowed)
			(footprints allowed)
		)
		(placement
			(enabled no)
			(sheetname "")
		)
		(fill
			(thermal_gap 0.5)
			(thermal_bridge_width 0.5)
			(island_removal_mode 0)
		)
		(polygon
			(pts
				(xy 158.369 -27.686) (xy 158.369 -27.051) (xy 160.02 -27.051) (xy 160.02 -27.686)
			)
		)
	)
	(zone
		(layer "F.Cu")
		(hatch none 0.5)
		(connect_pads
			(clearance 0)
		)
		(min_thickness 0.25)
		(keepout
			(tracks allowed)
			(vias allowed)
			(pads allowed)
			(copperpour allowed)
			(footprints allowed)
		)
		(placement
			(enabled no)
			(sheetname "")
		)
		(fill
			(thermal_gap 0.5)
			(thermal_bridge_width 0.5)
			(island_removal_mode 0)
		)
		(polygon
			(pts
				(xy 36.576 -102.616) (xy 36.576 -102.108) (xy 37.592 -102.108) (xy 37.592 -102.616)
			)
		)
	)
	(zone
		(net "XP12R0V")
		(layer "F.Cu")
		(hatch none 0.5)
		(connect_pads
			(clearance 0.5)
		)
		(min_thickness 0.25)
		(fill yes
			(thermal_gap 0.5)
			(thermal_bridge_width 0.5)
			(island_removal_mode 0)
		)
		(polygon
			(pts
				(xy 138.0998 -96.5708) (xy 139.7508 -96.5708) (xy 139.8016 -96.52) (xy 139.8016 -91.52636) (xy 139.5476 -91.27236)
				(xy 139.5476 -90.9574) (xy 139.5476 -90.1954) (xy 138.5062 -90.1954) (xy 137.8204 -90.8812) (xy 137.6426 -91.059)
				(xy 132.842 -91.059) (xy 132.715 -91.186) (xy 132.715 -93.7514) (xy 132.8674 -93.7514) (xy 134.239 -93.7514)
				(xy 136.1948 -93.7514) (xy 136.398 -93.9546) (xy 137.795 -95.3516) (xy 137.795 -96.266)
			)
		)
	)
	(zone
		(net "VDD_BNO085")
		(layer "F.Cu")
		(hatch none 0.5)
		(connect_pads
			(clearance 0.5)
		)
		(min_thickness 0.25)
		(fill yes
			(thermal_gap 0.5)
			(thermal_bridge_width 0.5)
			(island_removal_mode 0)
		)
		(polygon
			(pts
				(xy 86.6902 -62.1538) (xy 87.122 -62.1538) (xy 87.8332 -62.1538) (xy 88.265 -61.722) (xy 88.265 -60.833)
				(xy 88.519 -60.579) (xy 88.773 -60.579) (xy 89.027 -60.833) (xy 89.027 -63.881) (xy 85.725 -63.881)
				(xy 85.725 -62.484) (xy 86.0298 -62.1792) (xy 86.0552 -62.1538)
			)
		)
	)
	(zone
		(layer "F.Cu")
		(hatch none 0.5)
		(connect_pads
			(clearance 0)
		)
		(min_thickness 0.25)
		(keepout
			(tracks allowed)
			(vias allowed)
			(pads allowed)
			(copperpour allowed)
			(footprints allowed)
		)
		(placement
			(enabled no)
			(sheetname "")
		)
		(fill
			(thermal_gap 0.5)
			(thermal_bridge_width 0.5)
			(island_removal_mode 0)
		)
		(polygon
			(pts
				(xy 21.906992 -67.4116) (xy 21.906992 -69.0626) (xy 21.906992 -69.279008) (xy 21.59 -69.596) (xy 20.574 -69.596)
				(xy 20.066 -69.088) (xy 20.066 -68.707) (xy 20.103592 -68.669408) (xy 20.103592 -67.4116)
			)
		)
	)
	(zone
		(layer "F.Cu")
		(hatch none 0.5)
		(connect_pads
			(clearance 0)
		)
		(min_thickness 0.25)
		(keepout
			(tracks allowed)
			(vias allowed)
			(pads allowed)
			(copperpour allowed)
			(footprints not_allowed)
		)
		(placement
			(enabled no)
			(sheetname "")
		)
		(fill
			(thermal_gap 0.5)
			(thermal_bridge_width 0.5)
			(island_removal_mode 0)
		)
		(polygon
			(pts
				(xy 0.999998 -89.7001) (xy 12.7 -89.7001) (xy 12.7 -110.149894) (xy 137.150094 -110.149894) (xy 157.619954 -110.149894)
				(xy 157.619954 -99.70008) (xy 167.649906 -99.70008)
				(arc
					(start 167.649906 -110.149894)
					(mid 167.357013 -110.856999)
					(end 166.649908 -111.149892)
				)
				(arc
					(start 0.999998 -111.149892)
					(mid 0.292893 -110.856999)
					(end 0 -110.149894)
				)
				(xy 0 -89.7001)
			)
		)
	)
	(zone
		(layer "F.Cu")
		(hatch none 0.5)
		(connect_pads
			(clearance 0)
		)
		(min_thickness 0.25)
		(keepout
			(tracks allowed)
			(vias allowed)
			(pads allowed)
			(copperpour allowed)
			(footprints allowed)
		)
		(placement
			(enabled no)
			(sheetname "")
		)
		(fill
			(thermal_gap 0.5)
			(thermal_bridge_width 0.5)
			(island_removal_mode 0)
		)
		(polygon
			(pts
				(xy 69.0753 -47.1932) (xy 69.0753 -46.7868) (xy 70.8787 -46.7868) (xy 70.8787 -47.1932)
			)
		)
	)
	(zone
		(layer "F.Cu")
		(hatch none 0.5)
		(connect_pads
			(clearance 0)
		)
		(min_thickness 0.25)
		(keepout
			(tracks allowed)
			(vias allowed)
			(pads allowed)
			(copperpour allowed)
			(footprints not_allowed)
		)
		(placement
			(enabled no)
			(sheetname "")
		)
		(fill
			(thermal_gap 0.5)
			(thermal_bridge_width 0.5)
			(island_removal_mode 0)
		)
		(polygon
			(pts
				(xy 1.500124 -80.249268) (xy 19.500088 -80.249268) (xy 19.500088 -71.89978) (xy 1.500124 -71.89978)
			)
		)
	)
	(zone
		(net "XP12R0V_A_AVIN")
		(layer "F.Cu")
		(hatch none 0.5)
		(connect_pads
			(clearance 0.5)
		)
		(min_thickness 0.25)
		(fill yes
			(thermal_gap 0.5)
			(thermal_bridge_width 0.5)
			(island_removal_mode 0)
		)
		(polygon
			(pts
				(xy 139.7762 -97.4344) (xy 139.7762 -96.8248) (xy 139.7254 -96.774) (xy 137.7442 -96.774) (xy 137.2362 -96.266)
				(xy 135.9154 -96.266) (xy 135.7376 -96.4438) (xy 135.7376 -98.3742) (xy 135.9662 -98.6028) (xy 135.9662 -99.4664)
				(xy 136.0932 -99.5934) (xy 137.287 -99.5934) (xy 137.541 -99.5934) (xy 137.6934 -99.441) (xy 137.6934 -98.2218)
				(xy 138.43 -97.4852) (xy 139.7254 -97.4852)
			)
		)
	)
	(zone
		(net "SG")
		(layer "F.Cu")
		(hatch none 0.5)
		(connect_pads
			(clearance 0.5)
		)
		(min_thickness 0.25)
		(fill yes
			(thermal_gap 0.5)
			(thermal_bridge_width 0.5)
			(island_removal_mode 0)
		)
		(polygon
			(pts
				(xy 83.5152 -102.7938) (xy 83.6422 -102.6668) (xy 84.8868 -102.6668) (xy 84.9884 -102.7684) (xy 84.9884 -103.9114)
				(xy 84.836 -104.0638) (xy 84.2772 -104.0638) (xy 83.8962 -104.0638) (xy 83.6422 -104.3178) (xy 83.6422 -105.4608)
				(xy 83.1342 -105.9688) (xy 83.1342 -106.2228) (xy 83.1342 -107.7468) (xy 83.0072 -107.8738) (xy 82.1182 -107.8738)
				(xy 81.4832 -107.8738) (xy 81.3562 -107.7468) (xy 81.3562 -104.9528) (xy 82.2452 -104.0638)
			)
		)
	)
	(zone
		(net "SG")
		(layer "F.Cu")
		(hatch none 0.5)
		(connect_pads
			(clearance 0.5)
		)
		(min_thickness 0.25)
		(fill yes
			(thermal_gap 0.5)
			(thermal_bridge_width 0.5)
			(island_removal_mode 0)
		)
		(polygon
			(pts
				(xy 128.905 -97.917) (xy 127.635 -97.917) (xy 127.635 -95.377) (xy 127.889 -95.123) (xy 129.159 -95.123)
				(xy 129.413 -95.377) (xy 129.413 -96.266) (xy 128.905 -96.774)
			)
		)
	)
	(zone
		(layer "F.Cu")
		(hatch none 0.5)
		(connect_pads
			(clearance 0)
		)
		(min_thickness 0.25)
		(keepout
			(tracks allowed)
			(vias allowed)
			(pads allowed)
			(copperpour allowed)
			(footprints allowed)
		)
		(placement
			(enabled no)
			(sheetname "")
		)
		(fill
			(thermal_gap 0.5)
			(thermal_bridge_width 0.5)
			(island_removal_mode 0)
		)
		(polygon
			(pts
				(xy 88.4936 -50.5714) (xy 88.4936 -46.8376) (xy 91.948 -46.8376) (xy 91.948 -50.5714)
			)
		)
	)
	(zone
		(net "SG")
		(layer "F.Cu")
		(hatch none 0.5)
		(connect_pads
			(clearance 0.5)
		)
		(min_thickness 0.25)
		(fill yes
			(thermal_gap 0.5)
			(thermal_bridge_width 0.5)
			(island_removal_mode 0)
		)
		(polygon
			(pts
				(xy 133.985 -41.783) (xy 133.985 -35.941) (xy 133.985 -32.512) (xy 133.477 -32.004) (xy 133.477 -30.861)
				(xy 135.763 -30.861) (xy 136.652 -31.75) (xy 136.652 -36.195) (xy 136.652 -37.592) (xy 137.668 -38.608)
				(xy 145.288 -38.608) (xy 146.685 -40.005) (xy 146.685 -50.038) (xy 146.939 -50.292) (xy 146.939 -52.197)
				(xy 144.145 -52.197) (xy 144.145 -51.562) (xy 144.907 -50.8) (xy 144.907 -40.005) (xy 144.526 -39.624)
				(xy 140.462 -39.624) (xy 138.811 -41.275) (xy 138.557 -41.275) (xy 136.017 -41.275) (xy 135.509 -41.783)
			)
		)
	)
	(zone
		(layer "F.Cu")
		(hatch none 0.5)
		(connect_pads
			(clearance 0)
		)
		(min_thickness 0.25)
		(keepout
			(tracks allowed)
			(vias allowed)
			(pads allowed)
			(copperpour allowed)
			(footprints allowed)
		)
		(placement
			(enabled no)
			(sheetname "")
		)
		(fill
			(thermal_gap 0.5)
			(thermal_bridge_width 0.5)
			(island_removal_mode 0)
		)
		(polygon
			(pts
				(xy 36.703 -99.314) (xy 36.703 -98.806) (xy 37.719 -98.806) (xy 37.719 -99.314)
			)
		)
	)
	(zone
		(layer "F.Cu")
		(hatch none 0.5)
		(connect_pads
			(clearance 0)
		)
		(min_thickness 0.25)
		(keepout
			(tracks allowed)
			(vias allowed)
			(pads allowed)
			(copperpour allowed)
			(footprints allowed)
		)
		(placement
			(enabled no)
			(sheetname "")
		)
		(fill
			(thermal_gap 0.5)
			(thermal_bridge_width 0.5)
			(island_removal_mode 0)
		)
		(polygon
			(pts
				(xy 143.01216 -60.01258) (xy 143.01216 -58.99658) (xy 143.52016 -58.99658) (xy 143.52016 -60.01258)
			)
		)
	)
	(zone
		(net "UNNAMED_525_CAPACITOR_I7_1")
		(layer "F.Cu")
		(hatch none 0.5)
		(connect_pads
			(clearance 0.5)
		)
		(min_thickness 0.25)
		(fill yes
			(thermal_gap 0.5)
			(thermal_bridge_width 0.5)
			(island_removal_mode 0)
		)
		(polygon
			(pts
				(xy 42.418 -84.201) (xy 45.339 -84.201) (xy 45.847 -83.693) (xy 45.847 -82.169) (xy 46.482 -81.534)
				(xy 46.482 -80.645) (xy 46.355 -80.518) (xy 43.815 -80.518) (xy 43.307 -80.01) (xy 42.545 -80.01)
				(xy 42.164 -80.391) (xy 42.164 -83.947)
			)
		)
	)
	(zone
		(net "XP5R0V_VCC_ANT")
		(layer "F.Cu")
		(hatch none 0.5)
		(connect_pads
			(clearance 0.5)
		)
		(min_thickness 0.25)
		(fill yes
			(thermal_gap 0.5)
			(thermal_bridge_width 0.5)
			(island_removal_mode 0)
		)
		(polygon
			(pts
				(xy 123.825 -98.806) (xy 130.302 -98.806) (xy 130.429 -98.933) (xy 130.429 -100.203) (xy 130.175 -100.457)
				(xy 124.079 -100.457) (xy 123.825 -100.203)
			)
		)
	)
	(zone
		(layer "F.Cu")
		(hatch none 0.5)
		(connect_pads
			(clearance 0)
		)
		(min_thickness 0.25)
		(keepout
			(tracks allowed)
			(vias allowed)
			(pads allowed)
			(copperpour allowed)
			(footprints allowed)
		)
		(placement
			(enabled no)
			(sheetname "")
		)
		(fill
			(thermal_gap 0.5)
			(thermal_bridge_width 0.5)
			(island_removal_mode 0)
		)
		(polygon
			(pts
				(xy 83.693 -59.182) (xy 83.693 -58.801) (xy 84.836 -58.801) (xy 84.836 -59.182)
			)
		)
	)
	(zone
		(net "XP12R0V_IN")
		(layer "F.Cu")
		(hatch none 0.5)
		(connect_pads
			(clearance 0.5)
		)
		(min_thickness 0.25)
		(fill yes
			(thermal_gap 0.5)
			(thermal_bridge_width 0.5)
			(island_removal_mode 0)
		)
		(polygon
			(pts
				(xy 26.2382 -99.2124) (xy 26.2382 -104.8004) (xy 26.2382 -105.1814) (xy 25.8572 -105.5624) (xy 25.4762 -105.5624)
				(xy 24.1046 -105.5624) (xy 15.621 -105.5624) (xy 14.0462 -105.5624) (xy 13.6652 -105.1814) (xy 13.6652 -98.9584)
				(xy 13.6652 -98.8314) (xy 13.7922 -98.7044) (xy 25.9842 -98.7044) (xy 26.2382 -98.9584)
			)
		)
	)
	(zone
		(net "XP12R0V_PCIE")
		(layer "F.Cu")
		(hatch none 0.5)
		(connect_pads
			(clearance 0.5)
		)
		(min_thickness 0.25)
		(fill yes
			(thermal_gap 0.5)
			(thermal_bridge_width 0.5)
			(island_removal_mode 0)
		)
		(polygon
			(pts
				(xy 13.843 -98.0694) (xy 17.7292 -98.0694) (xy 18.2372 -98.0694) (xy 18.7452 -98.0694) (xy 19.0246 -98.0694)
				(xy 19.2024 -97.8916) (xy 19.2024 -92.4052) (xy 19.0246 -92.2274) (xy 18.7452 -92.2274) (xy 14.3256 -92.2274)
				(xy 13.843 -92.71)
			)
		)
	)
	(zone
		(net "XP3R3V_FPGA")
		(layer "F.Cu")
		(hatch none 0.5)
		(connect_pads
			(clearance 0.5)
		)
		(min_thickness 0.25)
		(fill yes
			(thermal_gap 0.5)
			(thermal_bridge_width 0.5)
			(island_removal_mode 0)
		)
		(polygon
			(pts
				(xy 109.0422 -71.4502) (xy 109.347 -71.4502) (xy 109.4486 -71.5518) (xy 109.4486 -74.9554) (xy 109.4486 -75.3364)
				(xy 109.1692 -75.6158) (xy 106.2482 -75.6158) (xy 106.1339 -75.5015) (xy 106.1339 -74.8665) (xy 106.1339 -71.5137)
				(xy 105.918 -71.2978) (xy 105.918 -70.2818) (xy 106.172 -70.0278) (xy 108.2548 -70.0278) (xy 108.3818 -70.1548)
				(xy 108.3818 -71.2724) (xy 108.5596 -71.4502)
			)
		)
	)
	(zone
		(net "XP1R8V_FPGA")
		(layer "F.Cu")
		(hatch none 0.5)
		(connect_pads
			(clearance 0.5)
		)
		(min_thickness 0.25)
		(fill yes
			(thermal_gap 0.5)
			(thermal_bridge_width 0.5)
			(island_removal_mode 0)
		)
		(polygon
			(pts
				(xy 130.7592 -68.453) (xy 132.207 -68.453) (xy 132.7658 -68.453) (xy 132.8674 -68.3514) (xy 132.8674 -66.8274)
				(xy 132.9944 -66.7004) (xy 133.096 -66.7004) (xy 133.3754 -66.7004) (xy 133.4516 -66.6242) (xy 133.4516 -65.7352)
				(xy 133.7564 -65.4304) (xy 133.7564 -65.3796) (xy 134.366 -64.77) (xy 134.366 -62.865) (xy 133.731 -62.23)
				(xy 132.715 -62.23) (xy 132.2578 -62.6872) (xy 132.2578 -63.3222) (xy 132.2578 -64.7192) (xy 131.8006 -65.1764)
				(xy 131.8006 -65.3796) (xy 131.8006 -65.6082) (xy 131.8006 -66.9036) (xy 131.5974 -67.1068) (xy 130.81 -67.1068)
				(xy 130.7084 -67.2084) (xy 130.7084 -68.4022)
			)
		)
	)
	(zone
		(net "SG")
		(layer "F.Cu")
		(hatch none 0.5)
		(connect_pads
			(clearance 0.5)
		)
		(min_thickness 0.25)
		(fill yes
			(thermal_gap 0.5)
			(thermal_bridge_width 0.5)
			(island_removal_mode 0)
		)
		(polygon
			(pts
				(xy 157.4292 -49.243996) (xy 166.4716 -49.243996) (xy 166.878 -49.650396) (xy 166.878 -57.295796)
				(xy 166.2938 -57.879996) (xy 162.5854 -57.879996) (xy 162.2044 -57.879996) (xy 161.8996 -57.575196)
				(xy 161.8996 -57.194196) (xy 161.8996 -55.924196) (xy 162.2552 -55.568596) (xy 163.7792 -55.568596)
				(xy 164.2618 -55.568596) (xy 164.4904 -55.339996) (xy 164.4904 -51.834796) (xy 164.1856 -51.529996)
				(xy 163.8554 -51.529996) (xy 162.1282 -51.529996) (xy 161.3154 -50.717196) (xy 161.3154 -50.691796)
				(xy 161.0868 -50.463196) (xy 157.4546 -50.463196) (xy 157.2768 -50.285396) (xy 157.2768 -49.396396)
			)
		)
	)
	(zone
		(net "VIN_XP5R0V")
		(layer "F.Cu")
		(hatch none 0.5)
		(connect_pads
			(clearance 0.5)
		)
		(min_thickness 0.25)
		(fill yes
			(thermal_gap 0.5)
			(thermal_bridge_width 0.5)
			(island_removal_mode 0)
		)
		(polygon
			(pts
				(xy 41.5544 -101.4984) (xy 41.3004 -101.4984) (xy 41.1734 -101.6254) (xy 41.1734 -102.6414) (xy 41.1734 -102.8192)
				(xy 40.5384 -103.4542) (xy 40.5384 -103.759) (xy 40.5384 -106.1974) (xy 40.6654 -106.3244) (xy 42.0624 -106.3244)
				(xy 42.3164 -106.0704) (xy 42.3164 -103.5304) (xy 42.0624 -103.2764) (xy 41.6814 -102.8954) (xy 41.6814 -101.6254)
			)
		)
	)
	(zone
		(layer "F.Cu")
		(hatch none 0.5)
		(connect_pads
			(clearance 0)
		)
		(min_thickness 0.25)
		(keepout
			(tracks allowed)
			(vias allowed)
			(pads allowed)
			(copperpour allowed)
			(footprints allowed)
		)
		(placement
			(enabled no)
			(sheetname "")
		)
		(fill
			(thermal_gap 0.5)
			(thermal_bridge_width 0.5)
			(island_removal_mode 0)
		)
		(polygon
			(pts
				(xy 53.9496 -84.455) (xy 52.9082 -84.455) (xy 52.9082 -82.6008) (xy 53.9496 -82.6008)
			)
		)
	)
	(zone
		(net "SG")
		(layer "F.Cu")
		(hatch none 0.5)
		(connect_pads
			(clearance 0.5)
		)
		(min_thickness 0.25)
		(fill yes
			(thermal_gap 0.5)
			(thermal_bridge_width 0.5)
			(island_removal_mode 0)
		)
		(polygon
			(pts
				(xy 128.9177 -66.3321) (xy 129.0066 -66.421) (xy 129.0066 -70.0532) (xy 129.017776 -70.064376) (xy 129.017776 -70.378828)
				(xy 129.105406 -70.466458) (xy 131.597654 -70.466458) (xy 131.770882 -70.29323) (xy 131.770882 -69.961506)
				(xy 131.770882 -69.596) (xy 130.5814 -69.596) (xy 130.4544 -69.469) (xy 130.4544 -66.9544) (xy 130.4671 -66.9417)
				(xy 130.4671 -66.5353) (xy 130.6322 -66.3702) (xy 131.2164 -66.3702) (xy 131.445 -66.1416) (xy 131.445 -65.3796)
				(xy 131.445 -64.9986) (xy 131.445 -64.81318) (xy 131.5974 -64.66078) (xy 131.5974 -60.9854) (xy 131.4196 -60.8076)
				(xy 128.3208 -60.8076) (xy 128.1684 -60.96) (xy 128.1684 -62.8904) (xy 128.524 -63.246) (xy 128.524 -65.024)
				(xy 128.9177 -65.4177)
			)
		)
	)
	(zone
		(layer "F.Cu")
		(hatch none 0.5)
		(connect_pads
			(clearance 0)
		)
		(min_thickness 0.25)
		(keepout
			(tracks allowed)
			(vias allowed)
			(pads allowed)
			(copperpour allowed)
			(footprints allowed)
		)
		(placement
			(enabled no)
			(sheetname "")
		)
		(fill
			(thermal_gap 0.5)
			(thermal_bridge_width 0.5)
			(island_removal_mode 0)
		)
		(polygon
			(pts
				(xy 89.408 -99.06) (xy 89.408 -98.679) (xy 90.297 -98.679) (xy 90.297 -99.06)
			)
		)
	)
	(zone
		(layers "F.Cu" "B.Cu" "In1.Cu" "In2.Cu" "In3.Cu" "In4.Cu" "In5.Cu" "In6.Cu"
			"In7.Cu" "In8.Cu"
		)
		(hatch none 0.5)
		(connect_pads
			(clearance 0)
		)
		(min_thickness 0.25)
		(keepout
			(tracks not_allowed)
			(vias allowed)
			(pads allowed)
			(copperpour not_allowed)
			(footprints allowed)
		)
		(placement
			(enabled no)
			(sheetname "")
		)
		(fill
			(thermal_gap 0.5)
			(thermal_bridge_width 0.5)
			(island_removal_mode 0)
		)
		(polygon
			(pts
				(xy 110.680754 -29.235146) (xy 112.458754 -29.235146) (xy 112.458754 -29.997146) (xy 110.680754 -29.997146)
			)
		)
	)
	(zone
		(layers "F.Cu" "B.Cu" "In1.Cu" "In2.Cu" "In3.Cu" "In4.Cu" "In5.Cu" "In6.Cu"
			"In7.Cu" "In8.Cu"
		)
		(hatch none 0.5)
		(connect_pads
			(clearance 0)
		)
		(min_thickness 0.25)
		(keepout
			(tracks not_allowed)
			(vias allowed)
			(pads allowed)
			(copperpour not_allowed)
			(footprints allowed)
		)
		(placement
			(enabled no)
			(sheetname "")
		)
		(fill
			(thermal_gap 0.5)
			(thermal_bridge_width 0.5)
			(island_removal_mode 0)
		)
		(polygon
			(pts
				(xy 91.7194 -23.0124) (xy 93.2434 -23.0124) (xy 93.2434 -23.7236) (xy 91.7194 -23.7236)
			)
		)
	)
	(zone
		(layers "F.Cu" "B.Cu" "In1.Cu" "In2.Cu" "In3.Cu" "In4.Cu" "In5.Cu" "In6.Cu"
			"In7.Cu" "In8.Cu"
		)
		(name "Package Keepin")
		(hatch none 0.5)
		(connect_pads
			(clearance 0)
		)
		(min_thickness 0.25)
		(keepout
			(tracks allowed)
			(vias allowed)
			(pads allowed)
			(copperpour allowed)
			(footprints allowed)
		)
		(placement
			(enabled no)
			(sheetname "")
		)
		(fill
			(thermal_gap 0.5)
			(thermal_bridge_width 0.5)
			(island_removal_mode 0)
		)
		(polygon
			(pts
				(arc
					(start 164.399722 -61.324998)
					(mid 164.725179 -60.083181)
					(end 165.617906 -59.160664)
				)
				(xy 165.617906 -14.782038)
				(arc
					(start 80.300068 -14.782038)
					(mid 78.156122 -13.893986)
					(end 77.26807 -11.75004)
				)
				(xy 77.26807 -2.032) (xy 60.13196 -2.032)
				(arc
					(start 60.13196 -7.450074)
					(mid 57.15 -10.432034)
					(end 54.16804 -7.450074)
				)
				(xy 54.16804 -2.032) (xy 47.03191 -2.032)
				(arc
					(start 47.03191 -10.925048)
					(mid 43.17492 -14.782038)
					(end 39.31793 -10.925048)
				)
				(xy 39.31793 -6.532118) (xy 35.381946 -6.532118)
				(arc
					(start 35.381946 -11.75004)
					(mid 34.493894 -13.893986)
					(end 32.349948 -14.782038)
				)
				(arc
					(start 15.999968 -14.782038)
					(mid 13.856022 -13.893986)
					(end 12.96797 -11.75004)
				)
				(xy 12.96797 -6.532118) (xy 2.032 -6.532118) (xy 2.032 -109.117892) (xy 165.617906 -109.117892)
				(arc
					(start 165.617906 -73.964546)
					(mid 164.725191 -73.042135)
					(end 164.399722 -71.800466)
				)
			)
		)
	)
	(zone
		(layers "F.Cu" "B.Cu" "In1.Cu" "In2.Cu" "In3.Cu" "In4.Cu" "In5.Cu" "In6.Cu"
			"In7.Cu" "In8.Cu"
		)
		(hatch none 0.5)
		(connect_pads
			(clearance 0)
		)
		(min_thickness 0.25)
		(keepout
			(tracks not_allowed)
			(vias allowed)
			(pads allowed)
			(copperpour not_allowed)
			(footprints allowed)
		)
		(placement
			(enabled no)
			(sheetname "")
		)
		(fill
			(thermal_gap 0.5)
			(thermal_bridge_width 0.5)
			(island_removal_mode 0)
		)
		(polygon
			(pts
				(arc
					(start 98.347022 -35.99307)
					(mid 98.016822 -36.32327)
					(end 98.347022 -36.65347)
				)
				(arc
					(start 99.34702 -36.65347)
					(mid 99.67722 -36.32327)
					(end 99.34702 -35.99307)
				)
			)
		)
	)
	(zone
		(layers "F.Cu" "B.Cu" "In1.Cu" "In2.Cu" "In3.Cu" "In4.Cu" "In5.Cu" "In6.Cu"
			"In7.Cu" "In8.Cu"
		)
		(hatch none 0.5)
		(connect_pads
			(clearance 0)
		)
		(min_thickness 0.25)
		(keepout
			(tracks not_allowed)
			(vias allowed)
			(pads allowed)
			(copperpour not_allowed)
			(footprints allowed)
		)
		(placement
			(enabled no)
			(sheetname "")
		)
		(fill
			(thermal_gap 0.5)
			(thermal_bridge_width 0.5)
			(island_removal_mode 0)
		)
		(polygon
			(pts
				(xy 101.5365 -29.108146) (xy 103.3145 -29.108146) (xy 103.3145 -29.870146) (xy 101.5365 -29.870146)
			)
		)
	)
	(zone
		(layers "F.Cu" "B.Cu" "In1.Cu" "In2.Cu" "In3.Cu" "In4.Cu" "In5.Cu" "In6.Cu"
			"In7.Cu" "In8.Cu"
		)
		(hatch none 0.5)
		(connect_pads
			(clearance 0)
		)
		(min_thickness 0.25)
		(keepout
			(tracks not_allowed)
			(vias allowed)
			(pads allowed)
			(copperpour not_allowed)
			(footprints allowed)
		)
		(placement
			(enabled no)
			(sheetname "")
		)
		(fill
			(thermal_gap 0.5)
			(thermal_bridge_width 0.5)
			(island_removal_mode 0)
		)
		(polygon
			(pts
				(arc
					(start 98.347022 -37.993066)
					(mid 98.016822 -38.323266)
					(end 98.347022 -38.653466)
				)
				(arc
					(start 99.34702 -38.653466)
					(mid 99.67722 -38.323266)
					(end 99.34702 -37.993066)
				)
			)
		)
	)
	(zone
		(layers "F.Cu" "B.Cu" "In1.Cu" "In2.Cu" "In3.Cu" "In4.Cu" "In5.Cu" "In6.Cu"
			"In7.Cu" "In8.Cu"
		)
		(hatch none 0.5)
		(connect_pads
			(clearance 0)
		)
		(min_thickness 0.25)
		(keepout
			(tracks not_allowed)
			(vias allowed)
			(pads allowed)
			(copperpour not_allowed)
			(footprints allowed)
		)
		(placement
			(enabled no)
			(sheetname "")
		)
		(fill
			(thermal_gap 0.5)
			(thermal_bridge_width 0.5)
			(island_removal_mode 0)
		)
		(polygon
			(pts
				(xy 157.114494 -56.660796) (xy 157.825694 -56.660796) (xy 157.825694 -58.184796) (xy 157.114494 -58.184796)
			)
		)
	)
	(zone
		(layers "F.Cu" "B.Cu" "In1.Cu" "In2.Cu" "In3.Cu" "In4.Cu" "In5.Cu" "In6.Cu"
			"In7.Cu" "In8.Cu"
		)
		(hatch none 0.5)
		(connect_pads
			(clearance 0)
		)
		(min_thickness 0.25)
		(keepout
			(tracks not_allowed)
			(vias allowed)
			(pads allowed)
			(copperpour not_allowed)
			(footprints allowed)
		)
		(placement
			(enabled no)
			(sheetname "")
		)
		(fill
			(thermal_gap 0.5)
			(thermal_bridge_width 0.5)
			(island_removal_mode 0)
		)
		(polygon
			(pts
				(xy 67.387978 -19.0246) (xy 68.911978 -19.0246) (xy 68.911978 -19.7358) (xy 67.387978 -19.7358)
			)
		)
	)
	(zone
		(layers "F.Cu" "B.Cu" "In1.Cu" "In2.Cu" "In3.Cu" "In4.Cu" "In5.Cu" "In6.Cu"
			"In7.Cu" "In8.Cu"
		)
		(hatch none 0.5)
		(connect_pads
			(clearance 0)
		)
		(min_thickness 0.25)
		(keepout
			(tracks not_allowed)
			(vias allowed)
			(pads allowed)
			(copperpour not_allowed)
			(footprints allowed)
		)
		(placement
			(enabled no)
			(sheetname "")
		)
		(fill
			(thermal_gap 0.5)
			(thermal_bridge_width 0.5)
			(island_removal_mode 0)
		)
		(polygon
			(pts
				(arc
					(start 98.347022 -41.993058)
					(mid 98.016822 -42.323258)
					(end 98.347022 -42.653458)
				)
				(arc
					(start 99.34702 -42.653458)
					(mid 99.67722 -42.323258)
					(end 99.34702 -41.993058)
				)
			)
		)
	)
	(zone
		(layers "F.Cu" "B.Cu" "In1.Cu" "In2.Cu" "In3.Cu" "In4.Cu" "In5.Cu" "In6.Cu"
			"In7.Cu" "In8.Cu"
		)
		(hatch none 0.5)
		(connect_pads
			(clearance 0)
		)
		(min_thickness 0.25)
		(keepout
			(tracks not_allowed)
			(vias allowed)
			(pads allowed)
			(copperpour not_allowed)
			(footprints allowed)
		)
		(placement
			(enabled no)
			(sheetname "")
		)
		(fill
			(thermal_gap 0.5)
			(thermal_bridge_width 0.5)
			(island_removal_mode 0)
		)
		(polygon
			(pts
				(xy 19.0246 -90.4494) (xy 19.0246 -91.1606) (xy 17.5006 -91.1606) (xy 17.5006 -90.4494)
			)
		)
	)
	(zone
		(layers "F.Cu" "B.Cu" "In1.Cu" "In2.Cu" "In3.Cu" "In4.Cu" "In5.Cu" "In6.Cu"
			"In7.Cu" "In8.Cu"
		)
		(hatch none 0.5)
		(connect_pads
			(clearance 0)
		)
		(min_thickness 0.25)
		(keepout
			(tracks not_allowed)
			(vias allowed)
			(pads allowed)
			(copperpour not_allowed)
			(footprints allowed)
		)
		(placement
			(enabled no)
			(sheetname "")
		)
		(fill
			(thermal_gap 0.5)
			(thermal_bridge_width 0.5)
			(island_removal_mode 0)
		)
		(polygon
			(pts
				(arc
					(start 157.226 -53.1876)
					(mid 147.066 -53.1876)
					(end 157.226 -53.1876)
				)
			)
		)
	)
	(zone
		(layers "F.Cu" "B.Cu" "In1.Cu" "In2.Cu" "In3.Cu" "In4.Cu" "In5.Cu" "In6.Cu"
			"In7.Cu" "In8.Cu"
		)
		(hatch none 0.5)
		(connect_pads
			(clearance 0)
		)
		(min_thickness 0.25)
		(keepout
			(tracks not_allowed)
			(vias allowed)
			(pads allowed)
			(copperpour not_allowed)
			(footprints allowed)
		)
		(placement
			(enabled no)
			(sheetname "")
		)
		(fill
			(thermal_gap 0.5)
			(thermal_bridge_width 0.5)
			(island_removal_mode 0)
		)
		(polygon
			(pts
				(xy 71.23557 -19.0246) (xy 72.75957 -19.0246) (xy 72.75957 -19.7358) (xy 71.23557 -19.7358)
			)
		)
	)
	(zone
		(layers "F.Cu" "B.Cu" "In1.Cu" "In2.Cu" "In3.Cu" "In4.Cu" "In5.Cu" "In6.Cu"
			"In7.Cu" "In8.Cu"
		)
		(hatch none 0.5)
		(connect_pads
			(clearance 0)
		)
		(min_thickness 0.25)
		(keepout
			(tracks not_allowed)
			(vias allowed)
			(pads allowed)
			(copperpour not_allowed)
			(footprints allowed)
		)
		(placement
			(enabled no)
			(sheetname "")
		)
		(fill
			(thermal_gap 0.5)
			(thermal_bridge_width 0.5)
			(island_removal_mode 0)
		)
		(polygon
			(pts
				(xy 71.882 -46.3296) (xy 72.644 -46.3296) (xy 72.644 -48.1076) (xy 71.882 -48.1076)
			)
		)
	)
	(zone
		(layers "F.Cu" "B.Cu" "In1.Cu" "In2.Cu" "In3.Cu" "In4.Cu" "In5.Cu" "In6.Cu"
			"In7.Cu" "In8.Cu"
		)
		(hatch none 0.5)
		(connect_pads
			(clearance 0)
		)
		(min_thickness 0.25)
		(keepout
			(tracks not_allowed)
			(vias allowed)
			(pads allowed)
			(copperpour not_allowed)
			(footprints allowed)
		)
		(placement
			(enabled no)
			(sheetname "")
		)
		(fill
			(thermal_gap 0.5)
			(thermal_bridge_width 0.5)
			(island_removal_mode 0)
		)
		(polygon
			(pts
				(xy 92.380054 -47.487586) (xy 93.091254 -47.487586) (xy 93.091254 -49.011586) (xy 92.380054 -49.011586)
			)
		)
	)
	(zone
		(layers "F.Cu" "B.Cu" "In1.Cu" "In2.Cu" "In3.Cu" "In4.Cu" "In5.Cu" "In6.Cu"
			"In7.Cu" "In8.Cu"
		)
		(hatch none 0.5)
		(connect_pads
			(clearance 0)
		)
		(min_thickness 0.25)
		(keepout
			(tracks not_allowed)
			(vias allowed)
			(pads allowed)
			(copperpour not_allowed)
			(footprints allowed)
		)
		(placement
			(enabled no)
			(sheetname "")
		)
		(fill
			(thermal_gap 0.5)
			(thermal_bridge_width 0.5)
			(island_removal_mode 0)
		)
		(polygon
			(pts
				(xy 114.866674 -30.649418) (xy 116.644674 -30.649418) (xy 116.644674 -31.411418) (xy 114.866674 -31.411418)
			)
		)
	)
	(zone
		(layers "F.Cu" "B.Cu" "In1.Cu" "In2.Cu" "In3.Cu" "In4.Cu" "In5.Cu" "In6.Cu"
			"In7.Cu" "In8.Cu"
		)
		(hatch none 0.5)
		(connect_pads
			(clearance 0)
		)
		(min_thickness 0.25)
		(keepout
			(tracks not_allowed)
			(vias allowed)
			(pads allowed)
			(copperpour not_allowed)
			(footprints allowed)
		)
		(placement
			(enabled no)
			(sheetname "")
		)
		(fill
			(thermal_gap 0.5)
			(thermal_bridge_width 0.5)
			(island_removal_mode 0)
		)
		(polygon
			(pts
				(xy 88.78951 -26.214578) (xy 90.56751 -26.214578) (xy 90.56751 -26.976578) (xy 88.78951 -26.976578)
			)
		)
	)
	(zone
		(layers "F.Cu" "B.Cu" "In1.Cu" "In2.Cu" "In3.Cu" "In4.Cu" "In5.Cu" "In6.Cu"
			"In7.Cu" "In8.Cu"
		)
		(hatch none 0.5)
		(connect_pads
			(clearance 0)
		)
		(min_thickness 0.25)
		(keepout
			(tracks not_allowed)
			(vias allowed)
			(pads allowed)
			(copperpour not_allowed)
			(footprints allowed)
		)
		(placement
			(enabled no)
			(sheetname "")
		)
		(fill
			(thermal_gap 0.5)
			(thermal_bridge_width 0.5)
			(island_removal_mode 0)
		)
		(polygon
			(pts
				(xy 74.78649 -8.6106) (xy 75.49769 -8.6106) (xy 75.49769 -10.1346) (xy 74.78649 -10.1346)
			)
		)
	)
	(zone
		(layers "F.Cu" "B.Cu" "In1.Cu" "In2.Cu" "In3.Cu" "In4.Cu" "In5.Cu" "In6.Cu"
			"In7.Cu" "In8.Cu"
		)
		(hatch none 0.5)
		(connect_pads
			(clearance 0)
		)
		(min_thickness 0.25)
		(keepout
			(tracks not_allowed)
			(vias allowed)
			(pads allowed)
			(copperpour not_allowed)
			(footprints allowed)
		)
		(placement
			(enabled no)
			(sheetname "")
		)
		(fill
			(thermal_gap 0.5)
			(thermal_bridge_width 0.5)
			(island_removal_mode 0)
		)
		(polygon
			(pts
				(xy 79.375 -22.72792) (xy 78.87208 -22.225) (xy 79.949802 -21.147278) (xy 80.452722 -21.650198)
			)
		)
	)
	(zone
		(layers "F.Cu" "B.Cu" "In1.Cu" "In2.Cu" "In3.Cu" "In4.Cu" "In5.Cu" "In6.Cu"
			"In7.Cu" "In8.Cu"
		)
		(hatch none 0.5)
		(connect_pads
			(clearance 0)
		)
		(min_thickness 0.25)
		(keepout
			(tracks not_allowed)
			(vias allowed)
			(pads allowed)
			(copperpour not_allowed)
			(footprints allowed)
		)
		(placement
			(enabled no)
			(sheetname "")
		)
		(fill
			(thermal_gap 0.5)
			(thermal_bridge_width 0.5)
			(island_removal_mode 0)
		)
		(polygon
			(pts
				(xy 28.4226 -96.7994) (xy 28.4226 -97.5106) (xy 26.8986 -97.5106) (xy 26.8986 -96.7994)
			)
		)
	)
	(zone
		(layers "F.Cu" "B.Cu" "In1.Cu" "In2.Cu" "In3.Cu" "In4.Cu" "In5.Cu" "In6.Cu"
			"In7.Cu" "In8.Cu"
		)
		(hatch none 0.5)
		(connect_pads
			(clearance 0)
		)
		(min_thickness 0.25)
		(keepout
			(tracks not_allowed)
			(vias allowed)
			(pads allowed)
			(copperpour not_allowed)
			(footprints allowed)
		)
		(placement
			(enabled no)
			(sheetname "")
		)
		(fill
			(thermal_gap 0.5)
			(thermal_bridge_width 0.5)
			(island_removal_mode 0)
		)
		(polygon
			(pts
				(xy 86.3346 -27.178) (xy 88.1126 -27.178) (xy 88.1126 -27.94) (xy 86.3346 -27.94)
			)
		)
	)
	(zone
		(layers "F.Cu" "B.Cu" "In1.Cu" "In2.Cu" "In3.Cu" "In4.Cu" "In5.Cu" "In6.Cu"
			"In7.Cu" "In8.Cu"
		)
		(hatch none 0.5)
		(connect_pads
			(clearance 0)
		)
		(min_thickness 0.25)
		(keepout
			(tracks not_allowed)
			(vias allowed)
			(pads allowed)
			(copperpour not_allowed)
			(footprints allowed)
		)
		(placement
			(enabled no)
			(sheetname "")
		)
		(fill
			(thermal_gap 0.5)
			(thermal_bridge_width 0.5)
			(island_removal_mode 0)
		)
		(polygon
			(pts
				(arc
					(start 119.34698 -36.993068)
					(mid 119.01678 -37.323268)
					(end 119.34698 -37.653468)
				)
				(arc
					(start 120.346978 -37.653468)
					(mid 120.677178 -37.323268)
					(end 120.346978 -36.993068)
				)
			)
		)
	)
	(zone
		(layers "F.Cu" "B.Cu" "In1.Cu" "In2.Cu" "In3.Cu" "In4.Cu" "In5.Cu" "In6.Cu"
			"In7.Cu" "In8.Cu"
		)
		(hatch none 0.5)
		(connect_pads
			(clearance 0)
		)
		(min_thickness 0.25)
		(keepout
			(tracks not_allowed)
			(vias allowed)
			(pads allowed)
			(copperpour not_allowed)
			(footprints allowed)
		)
		(placement
			(enabled no)
			(sheetname "")
		)
		(fill
			(thermal_gap 0.5)
			(thermal_bridge_width 0.5)
			(island_removal_mode 0)
		)
		(polygon
			(pts
				(arc
					(start 102.347268 -37.993066)
					(mid 102.017068 -38.323266)
					(end 102.347268 -38.653466)
				)
				(arc
					(start 103.347266 -38.653466)
					(mid 103.677466 -38.323266)
					(end 103.347266 -37.993066)
				)
			)
		)
	)
	(zone
		(layers "F.Cu" "B.Cu" "In1.Cu" "In2.Cu" "In3.Cu" "In4.Cu" "In5.Cu" "In6.Cu"
			"In7.Cu" "In8.Cu"
		)
		(hatch none 0.5)
		(connect_pads
			(clearance 0)
		)
		(min_thickness 0.25)
		(keepout
			(tracks not_allowed)
			(vias allowed)
			(pads allowed)
			(copperpour not_allowed)
			(footprints allowed)
		)
		(placement
			(enabled no)
			(sheetname "")
		)
		(fill
			(thermal_gap 0.5)
			(thermal_bridge_width 0.5)
			(island_removal_mode 0)
		)
		(polygon
			(pts
				(arc
					(start 113.346992 -35.99307)
					(mid 113.016792 -36.32327)
					(end 113.346992 -36.65347)
				)
				(arc
					(start 114.34699 -36.65347)
					(mid 114.67719 -36.32327)
					(end 114.34699 -35.99307)
				)
			)
		)
	)
	(zone
		(layers "F.Cu" "B.Cu" "In1.Cu" "In2.Cu" "In3.Cu" "In4.Cu" "In5.Cu" "In6.Cu"
			"In7.Cu" "In8.Cu"
		)
		(hatch none 0.5)
		(connect_pads
			(clearance 0)
		)
		(min_thickness 0.25)
		(keepout
			(tracks not_allowed)
			(vias allowed)
			(pads allowed)
			(copperpour not_allowed)
			(footprints allowed)
		)
		(placement
			(enabled no)
			(sheetname "")
		)
		(fill
			(thermal_gap 0.5)
			(thermal_bridge_width 0.5)
			(island_removal_mode 0)
		)
		(polygon
			(pts
				(arc
					(start 98.347022 -39.993062)
					(mid 98.016822 -40.323262)
					(end 98.347022 -40.653462)
				)
				(arc
					(start 99.34702 -40.653462)
					(mid 99.67722 -40.323262)
					(end 99.34702 -39.993062)
				)
			)
		)
	)
	(zone
		(layers "F.Cu" "B.Cu" "In1.Cu" "In2.Cu" "In3.Cu" "In4.Cu" "In5.Cu" "In6.Cu"
			"In7.Cu" "In8.Cu"
		)
		(hatch none 0.5)
		(connect_pads
			(clearance 0)
		)
		(min_thickness 0.25)
		(keepout
			(tracks not_allowed)
			(vias allowed)
			(pads allowed)
			(copperpour not_allowed)
			(footprints allowed)
		)
		(placement
			(enabled no)
			(sheetname "")
		)
		(fill
			(thermal_gap 0.5)
			(thermal_bridge_width 0.5)
			(island_removal_mode 0)
		)
		(polygon
			(pts
				(xy 70.688454 -50.0888) (xy 72.466454 -50.0888) (xy 72.466454 -50.8508) (xy 70.688454 -50.8508)
			)
		)
	)
	(zone
		(layers "F.Cu" "B.Cu" "In1.Cu" "In2.Cu" "In3.Cu" "In4.Cu" "In5.Cu" "In6.Cu"
			"In7.Cu" "In8.Cu"
		)
		(hatch none 0.5)
		(connect_pads
			(clearance 0)
		)
		(min_thickness 0.25)
		(keepout
			(tracks not_allowed)
			(vias allowed)
			(pads allowed)
			(copperpour not_allowed)
			(footprints allowed)
		)
		(placement
			(enabled no)
			(sheetname "")
		)
		(fill
			(thermal_gap 0.5)
			(thermal_bridge_width 0.5)
			(island_removal_mode 0)
		)
		(polygon
			(pts
				(arc
					(start 100.347018 -42.993056)
					(mid 100.016818 -43.323256)
					(end 100.347018 -43.653456)
				)
				(arc
					(start 101.347016 -43.653456)
					(mid 101.677216 -43.323256)
					(end 101.347016 -42.993056)
				)
			)
		)
	)
	(zone
		(layers "F.Cu" "B.Cu" "In1.Cu" "In2.Cu" "In3.Cu" "In4.Cu" "In5.Cu" "In6.Cu"
			"In7.Cu" "In8.Cu"
		)
		(hatch none 0.5)
		(connect_pads
			(clearance 0)
		)
		(min_thickness 0.25)
		(keepout
			(tracks not_allowed)
			(vias allowed)
			(pads allowed)
			(copperpour not_allowed)
			(footprints allowed)
		)
		(placement
			(enabled no)
			(sheetname "")
		)
		(fill
			(thermal_gap 0.5)
			(thermal_bridge_width 0.5)
			(island_removal_mode 0)
		)
		(polygon
			(pts
				(arc
					(start 161.925 -26.543)
					(mid 151.765 -26.543)
					(end 161.925 -26.543)
				)
			)
		)
	)
	(zone
		(layers "F.Cu" "B.Cu" "In1.Cu" "In2.Cu" "In3.Cu" "In4.Cu" "In5.Cu" "In6.Cu"
			"In7.Cu" "In8.Cu"
		)
		(hatch none 0.5)
		(connect_pads
			(clearance 0)
		)
		(min_thickness 0.25)
		(keepout
			(tracks not_allowed)
			(vias allowed)
			(pads allowed)
			(copperpour not_allowed)
			(footprints allowed)
		)
		(placement
			(enabled no)
			(sheetname "")
		)
		(fill
			(thermal_gap 0.5)
			(thermal_bridge_width 0.5)
			(island_removal_mode 0)
		)
		(polygon
			(pts
				(arc
					(start 102.347268 -41.993058)
					(mid 102.017068 -42.323258)
					(end 102.347268 -42.653458)
				)
				(arc
					(start 103.347266 -42.653458)
					(mid 103.677466 -42.323258)
					(end 103.347266 -41.993058)
				)
			)
		)
	)
	(zone
		(layers "F.Cu" "B.Cu" "In1.Cu" "In2.Cu" "In3.Cu" "In4.Cu" "In5.Cu" "In6.Cu"
			"In7.Cu" "In8.Cu"
		)
		(hatch none 0.5)
		(connect_pads
			(clearance 0)
		)
		(min_thickness 0.25)
		(keepout
			(tracks not_allowed)
			(vias allowed)
			(pads allowed)
			(copperpour not_allowed)
			(footprints allowed)
		)
		(placement
			(enabled no)
			(sheetname "")
		)
		(fill
			(thermal_gap 0.5)
			(thermal_bridge_width 0.5)
			(island_removal_mode 0)
		)
		(polygon
			(pts
				(arc
					(start 100.347018 -38.993064)
					(mid 100.016818 -39.323264)
					(end 100.347018 -39.653464)
				)
				(arc
					(start 101.347016 -39.653464)
					(mid 101.677216 -39.323264)
					(end 101.347016 -38.993064)
				)
			)
		)
	)
	(zone
		(layers "F.Cu" "B.Cu" "In1.Cu" "In2.Cu" "In3.Cu" "In4.Cu" "In5.Cu" "In6.Cu"
			"In7.Cu" "In8.Cu"
		)
		(hatch none 0.5)
		(connect_pads
			(clearance 0)
		)
		(min_thickness 0.25)
		(keepout
			(tracks not_allowed)
			(vias allowed)
			(pads allowed)
			(copperpour not_allowed)
			(footprints allowed)
		)
		(placement
			(enabled no)
			(sheetname "")
		)
		(fill
			(thermal_gap 0.5)
			(thermal_bridge_width 0.5)
			(island_removal_mode 0)
		)
		(polygon
			(pts
				(xy 87.350854 -47.878746) (xy 88.062054 -47.878746) (xy 88.062054 -49.402746) (xy 87.350854 -49.402746)
			)
		)
	)
	(zone
		(layers "F.Cu" "B.Cu" "In1.Cu" "In2.Cu" "In3.Cu" "In4.Cu" "In5.Cu" "In6.Cu"
			"In7.Cu" "In8.Cu"
		)
		(hatch none 0.5)
		(connect_pads
			(clearance 0)
		)
		(min_thickness 0.25)
		(keepout
			(tracks not_allowed)
			(vias allowed)
			(pads allowed)
			(copperpour not_allowed)
			(footprints allowed)
		)
		(placement
			(enabled no)
			(sheetname "")
		)
		(fill
			(thermal_gap 0.5)
			(thermal_bridge_width 0.5)
			(island_removal_mode 0)
		)
		(polygon
			(pts
				(xy 74.78649 -11.049) (xy 75.49769 -11.049) (xy 75.49769 -12.573) (xy 74.78649 -12.573)
			)
		)
	)
	(zone
		(layers "F.Cu" "B.Cu" "In1.Cu" "In2.Cu" "In3.Cu" "In4.Cu" "In5.Cu" "In6.Cu"
			"In7.Cu" "In8.Cu"
		)
		(hatch none 0.5)
		(connect_pads
			(clearance 0)
		)
		(min_thickness 0.25)
		(keepout
			(tracks not_allowed)
			(vias allowed)
			(pads allowed)
			(copperpour not_allowed)
			(footprints allowed)
		)
		(placement
			(enabled no)
			(sheetname "")
		)
		(fill
			(thermal_gap 0.5)
			(thermal_bridge_width 0.5)
			(island_removal_mode 0)
		)
		(polygon
			(pts
				(xy 85.344 -29.0322) (xy 86.106 -29.0322) (xy 86.106 -30.8102) (xy 85.344 -30.8102)
			)
		)
	)
	(zone
		(layers "F.Cu" "B.Cu" "In1.Cu" "In2.Cu" "In3.Cu" "In4.Cu" "In5.Cu" "In6.Cu"
			"In7.Cu" "In8.Cu"
		)
		(hatch none 0.5)
		(connect_pads
			(clearance 0)
		)
		(min_thickness 0.25)
		(keepout
			(tracks not_allowed)
			(vias allowed)
			(pads allowed)
			(copperpour not_allowed)
			(footprints allowed)
		)
		(placement
			(enabled no)
			(sheetname "")
		)
		(fill
			(thermal_gap 0.5)
			(thermal_bridge_width 0.5)
			(island_removal_mode 0)
		)
		(polygon
			(pts
				(arc
					(start 117.346984 -32.992822)
					(mid 117.016784 -33.323022)
					(end 117.346984 -33.653222)
				)
				(arc
					(start 118.346982 -33.653222)
					(mid 118.677182 -33.323022)
					(end 118.346982 -32.992822)
				)
			)
		)
	)
	(zone
		(layers "F.Cu" "B.Cu" "In1.Cu" "In2.Cu" "In3.Cu" "In4.Cu" "In5.Cu" "In6.Cu"
			"In7.Cu" "In8.Cu"
		)
		(hatch none 0.5)
		(connect_pads
			(clearance 0)
		)
		(min_thickness 0.25)
		(keepout
			(tracks not_allowed)
			(vias allowed)
			(pads allowed)
			(copperpour not_allowed)
			(footprints allowed)
		)
		(placement
			(enabled no)
			(sheetname "")
		)
		(fill
			(thermal_gap 0.5)
			(thermal_bridge_width 0.5)
			(island_removal_mode 0)
		)
		(polygon
			(pts
				(xy 66.786506 -8.6106) (xy 67.497706 -8.6106) (xy 67.497706 -10.1346) (xy 66.786506 -10.1346)
			)
		)
	)
	(zone
		(layers "F.Cu" "B.Cu" "In1.Cu" "In2.Cu" "In3.Cu" "In4.Cu" "In5.Cu" "In6.Cu"
			"In7.Cu" "In8.Cu"
		)
		(hatch none 0.5)
		(connect_pads
			(clearance 0)
		)
		(min_thickness 0.25)
		(keepout
			(tracks not_allowed)
			(vias allowed)
			(pads allowed)
			(copperpour not_allowed)
			(footprints allowed)
		)
		(placement
			(enabled no)
			(sheetname "")
		)
		(fill
			(thermal_gap 0.5)
			(thermal_bridge_width 0.5)
			(island_removal_mode 0)
		)
		(polygon
			(pts
				(xy 81.61274 -47.980346) (xy 83.13674 -47.980346) (xy 83.13674 -48.691546) (xy 81.61274 -48.691546)
			)
		)
	)
	(zone
		(layers "F.Cu" "B.Cu" "In1.Cu" "In2.Cu" "In3.Cu" "In4.Cu" "In5.Cu" "In6.Cu"
			"In7.Cu" "In8.Cu"
		)
		(hatch none 0.5)
		(connect_pads
			(clearance 0)
		)
		(min_thickness 0.25)
		(keepout
			(tracks not_allowed)
			(vias allowed)
			(pads allowed)
			(copperpour not_allowed)
			(footprints allowed)
		)
		(placement
			(enabled no)
			(sheetname "")
		)
		(fill
			(thermal_gap 0.5)
			(thermal_bridge_width 0.5)
			(island_removal_mode 0)
		)
		(polygon
			(pts
				(arc
					(start 112.346994 -46.992794)
					(mid 112.016794 -47.322994)
					(end 112.346994 -47.653194)
				)
				(arc
					(start 113.346992 -47.653194)
					(mid 113.677192 -47.322994)
					(end 113.346992 -46.992794)
				)
			)
		)
	)
	(zone
		(layers "F.Cu" "B.Cu" "In1.Cu" "In2.Cu" "In3.Cu" "In4.Cu" "In5.Cu" "In6.Cu"
			"In7.Cu" "In8.Cu"
		)
		(hatch none 0.5)
		(connect_pads
			(clearance 0)
		)
		(min_thickness 0.25)
		(keepout
			(tracks not_allowed)
			(vias allowed)
			(pads allowed)
			(copperpour not_allowed)
			(footprints allowed)
		)
		(placement
			(enabled no)
			(sheetname "")
		)
		(fill
			(thermal_gap 0.5)
			(thermal_bridge_width 0.5)
			(island_removal_mode 0)
		)
		(polygon
			(pts
				(xy 60.708032 -17.272) (xy 61.470032 -17.272) (xy 61.470032 -19.05) (xy 60.708032 -19.05)
			)
		)
	)
	(zone
		(layers "F.Cu" "B.Cu" "In1.Cu" "In2.Cu" "In3.Cu" "In4.Cu" "In5.Cu" "In6.Cu"
			"In7.Cu" "In8.Cu"
		)
		(hatch none 0.5)
		(connect_pads
			(clearance 0)
		)
		(min_thickness 0.25)
		(keepout
			(tracks not_allowed)
			(vias allowed)
			(pads allowed)
			(copperpour not_allowed)
			(footprints allowed)
		)
		(placement
			(enabled no)
			(sheetname "")
		)
		(fill
			(thermal_gap 0.5)
			(thermal_bridge_width 0.5)
			(island_removal_mode 0)
		)
		(polygon
			(pts
				(xy 70.786498 -8.6106) (xy 71.497698 -8.6106) (xy 71.497698 -10.1346) (xy 70.786498 -10.1346)
			)
		)
	)
	(zone
		(layers "F.Cu" "B.Cu" "In1.Cu" "In2.Cu" "In3.Cu" "In4.Cu" "In5.Cu" "In6.Cu"
			"In7.Cu" "In8.Cu"
		)
		(hatch none 0.5)
		(connect_pads
			(clearance 0)
		)
		(min_thickness 0.25)
		(keepout
			(tracks not_allowed)
			(vias allowed)
			(pads allowed)
			(copperpour not_allowed)
			(footprints allowed)
		)
		(placement
			(enabled no)
			(sheetname "")
		)
		(fill
			(thermal_gap 0.5)
			(thermal_bridge_width 0.5)
			(island_removal_mode 0)
		)
		(polygon
			(pts
				(xy 62.387988 -19.0246) (xy 63.911988 -19.0246) (xy 63.911988 -19.7358) (xy 62.387988 -19.7358)
			)
		)
	)
	(zone
		(layers "F.Cu" "B.Cu" "In1.Cu" "In2.Cu" "In3.Cu" "In4.Cu" "In5.Cu" "In6.Cu"
			"In7.Cu" "In8.Cu"
		)
		(hatch none 0.5)
		(connect_pads
			(clearance 0)
		)
		(min_thickness 0.25)
		(keepout
			(tracks not_allowed)
			(vias allowed)
			(pads allowed)
			(copperpour not_allowed)
			(footprints allowed)
		)
		(placement
			(enabled no)
			(sheetname "")
		)
		(fill
			(thermal_gap 0.5)
			(thermal_bridge_width 0.5)
			(island_removal_mode 0)
		)
		(polygon
			(pts
				(arc
					(start 100.347018 -36.993068)
					(mid 100.016818 -37.323268)
					(end 100.347018 -37.653468)
				)
				(arc
					(start 101.347016 -37.653468)
					(mid 101.677216 -37.323268)
					(end 101.347016 -36.993068)
				)
			)
		)
	)
	(zone
		(layers "F.Cu" "B.Cu" "In1.Cu" "In2.Cu" "In3.Cu" "In4.Cu" "In5.Cu" "In6.Cu"
			"In7.Cu" "In8.Cu"
		)
		(hatch none 0.5)
		(connect_pads
			(clearance 0)
		)
		(min_thickness 0.25)
		(keepout
			(tracks not_allowed)
			(vias allowed)
			(pads allowed)
			(copperpour not_allowed)
			(footprints allowed)
		)
		(placement
			(enabled no)
			(sheetname "")
		)
		(fill
			(thermal_gap 0.5)
			(thermal_bridge_width 0.5)
			(island_removal_mode 0)
		)
		(polygon
			(pts
				(arc
					(start 100.347018 -40.99306)
					(mid 100.016818 -41.32326)
					(end 100.347018 -41.65346)
				)
				(arc
					(start 101.347016 -41.65346)
					(mid 101.677216 -41.32326)
					(end 101.347016 -40.99306)
				)
			)
		)
	)
	(zone
		(layers "F.Cu" "B.Cu" "In1.Cu" "In2.Cu" "In3.Cu" "In4.Cu" "In5.Cu" "In6.Cu"
			"In7.Cu" "In8.Cu"
		)
		(hatch none 0.5)
		(connect_pads
			(clearance 0)
		)
		(min_thickness 0.25)
		(keepout
			(tracks not_allowed)
			(vias allowed)
			(pads allowed)
			(copperpour not_allowed)
			(footprints allowed)
		)
		(placement
			(enabled no)
			(sheetname "")
		)
		(fill
			(thermal_gap 0.5)
			(thermal_bridge_width 0.5)
			(island_removal_mode 0)
		)
		(polygon
			(pts
				(arc
					(start 120.016778 -35.323018)
					(mid 120.346978 -35.653218)
					(end 120.677178 -35.323018)
				)
				(arc
					(start 120.677178 -34.32302)
					(mid 120.346978 -33.99282)
					(end 120.016778 -34.32302)
				)
			)
		)
	)
	(zone
		(layers "F.Cu" "B.Cu" "In1.Cu" "In2.Cu" "In3.Cu" "In4.Cu" "In5.Cu" "In6.Cu"
			"In7.Cu" "In8.Cu"
		)
		(name "Route Keepin")
		(hatch none 0.5)
		(connect_pads
			(clearance 0)
		)
		(min_thickness 0.25)
		(keepout
			(tracks allowed)
			(vias allowed)
			(pads allowed)
			(copperpour allowed)
			(footprints allowed)
		)
		(placement
			(enabled no)
			(sheetname "")
		)
		(fill
			(thermal_gap 0.5)
			(thermal_bridge_width 0.5)
			(island_removal_mode 0)
		)
		(polygon
			(pts
				(arc
					(start 165.669722 -61.324998)
					(mid 166.024001 -60.448302)
					(end 166.887906 -60.063888)
				)
				(arc
					(start 166.887906 -13.750036)
					(mid 166.818198 -13.581746)
					(end 166.649908 -13.512038)
				)
				(arc
					(start 80.300068 -13.512038)
					(mid 79.054147 -12.995961)
					(end 78.53807 -11.75004)
				)
				(xy 78.53807 -0.815848) (xy 78.484222 -0.762) (xy 58.915808 -0.762) (xy 58.86196 -0.815848)
				(arc
					(start 58.86196 -7.450074)
					(mid 57.15 -9.162034)
					(end 55.43804 -7.450074)
				)
				(xy 55.43804 -0.815848) (xy 55.384192 -0.762) (xy 45.815758 -0.762) (xy 45.76191 -0.815848)
				(arc
					(start 45.76191 -10.925048)
					(mid 43.17492 -13.512038)
					(end 40.58793 -10.925048)
				)
				(arc
					(start 40.58793 -5.500116)
					(mid 40.518222 -5.331826)
					(end 40.349932 -5.262118)
				)
				(arc
					(start 34.349944 -5.262118)
					(mid 34.181654 -5.331826)
					(end 34.111946 -5.500116)
				)
				(arc
					(start 34.111946 -11.75004)
					(mid 33.595869 -12.995961)
					(end 32.349948 -13.512038)
				)
				(arc
					(start 15.999968 -13.512038)
					(mid 14.754047 -12.995961)
					(end 14.23797 -11.75004)
				)
				(arc
					(start 14.23797 -5.500116)
					(mid 14.168262 -5.331826)
					(end 13.999972 -5.262118)
				)
				(arc
					(start 0.999998 -5.262118)
					(mid 0.831708 -5.331826)
					(end 0.762 -5.500116)
				)
				(arc
					(start 0.762 -110.149894)
					(mid 0.831708 -110.318184)
					(end 0.999998 -110.387892)
				)
				(arc
					(start 166.649908 -110.387892)
					(mid 166.818198 -110.318184)
					(end 166.887906 -110.149894)
				)
				(arc
					(start 166.887906 -73.061322)
					(mid 166.023914 -72.676921)
					(end 165.669722 -71.800212)
				)
			)
		)
	)
	(zone
		(layer "B.Cu")
		(hatch none 0.5)
		(connect_pads
			(clearance 0)
		)
		(min_thickness 0.25)
		(keepout
			(tracks allowed)
			(vias allowed)
			(pads allowed)
			(copperpour allowed)
			(footprints allowed)
		)
		(placement
			(enabled no)
			(sheetname "")
		)
		(fill
			(thermal_gap 0.5)
			(thermal_bridge_width 0.5)
			(island_removal_mode 0)
		)
		(polygon
			(pts
				(xy 8.636 -77.089) (xy 8.636 -76.2) (xy 10.033 -76.2) (xy 10.033 -77.089)
			)
		)
	)
	(zone
		(net "SG")
		(layer "B.Cu")
		(hatch none 0.5)
		(connect_pads
			(clearance 0.5)
		)
		(min_thickness 0.25)
		(fill yes
			(thermal_gap 0.5)
			(thermal_bridge_width 0.5)
			(island_removal_mode 0)
		)
		(polygon
			(pts
				(xy 90.2843 -33.8963) (xy 90.3224 -33.8582) (xy 90.805 -33.3756) (xy 90.805 -33.147) (xy 90.805 -32.3088)
				(xy 90.5764 -32.0802) (xy 87.5284 -32.0802) (xy 87.249 -32.3596) (xy 87.249 -33.147) (xy 87.249 -33.782)
				(xy 87.3633 -33.8963)
			)
		)
	)
	(zone
		(layer "B.Cu")
		(hatch none 0.5)
		(connect_pads
			(clearance 0)
		)
		(min_thickness 0.25)
		(keepout
			(tracks not_allowed)
			(vias allowed)
			(pads allowed)
			(copperpour not_allowed)
			(footprints allowed)
		)
		(placement
			(enabled no)
			(sheetname "")
		)
		(fill
			(thermal_gap 0.5)
			(thermal_bridge_width 0.5)
			(island_removal_mode 0)
		)
		(polygon
			(pts
				(xy 157.619954 -22.899878) (xy 157.619954 -13.750036) (xy 79.30007 -13.750036)
				(arc
					(start 79.30007 -11.75004)
					(mid 79.592963 -12.457145)
					(end 80.300068 -12.750038)
				)
				(arc
					(start 166.649908 -12.750038)
					(mid 167.357013 -13.042931)
					(end 167.649906 -13.750036)
				)
				(xy 167.649906 -22.899878)
			)
		)
	)
	(zone
		(layer "B.Cu")
		(hatch none 0.5)
		(connect_pads
			(clearance 0)
		)
		(min_thickness 0.25)
		(keepout
			(tracks allowed)
			(vias allowed)
			(pads allowed)
			(copperpour allowed)
			(footprints allowed)
		)
		(placement
			(enabled no)
			(sheetname "")
		)
		(fill
			(thermal_gap 0.5)
			(thermal_bridge_width 0.5)
			(island_removal_mode 0)
		)
		(polygon
			(pts
				(xy 114.4524 -59.4614) (xy 114.4524 -58.801) (xy 116.0272 -58.801) (xy 116.0272 -59.4614)
			)
		)
	)
	(zone
		(net "SG")
		(layer "B.Cu")
		(hatch none 0.5)
		(connect_pads
			(clearance 0.5)
		)
		(min_thickness 0.25)
		(fill yes
			(thermal_gap 0.5)
			(thermal_bridge_width 0.5)
			(island_removal_mode 0)
		)
		(polygon
			(pts
				(xy 72.263 -73.279) (xy 74.168 -73.279) (xy 74.422 -73.533) (xy 79.629 -73.533) (xy 79.629 -75.311)
				(xy 79.375 -75.565) (xy 73.533 -75.565) (xy 72.263 -74.295)
			)
		)
	)
	(zone
		(net "XP5R0V_VCC_ANT")
		(layer "B.Cu")
		(hatch none 0.5)
		(connect_pads
			(clearance 0.5)
		)
		(min_thickness 0.25)
		(fill yes
			(thermal_gap 0.5)
			(thermal_bridge_width 0.5)
			(island_removal_mode 0)
		)
		(polygon
			(pts
				(xy 127.635 -98.679) (xy 129.413 -98.679) (xy 129.413 -100.584) (xy 129.286 -100.711) (xy 127.762 -100.711)
				(xy 127.508 -100.457) (xy 127.508 -98.806)
			)
		)
	)
	(zone
		(net "XP3R3V_VPLL")
		(layer "B.Cu")
		(hatch none 0.5)
		(connect_pads
			(clearance 0.5)
		)
		(min_thickness 0.25)
		(fill yes
			(thermal_gap 0.5)
			(thermal_bridge_width 0.5)
			(island_removal_mode 0)
		)
		(polygon
			(pts
				(xy 27.305 -90.932) (xy 28.956 -90.932) (xy 29.083 -90.805) (xy 29.083 -89.281) (xy 28.575 -88.773)
				(xy 27.305 -88.773) (xy 27.178 -88.9) (xy 27.178 -90.805)
			)
		)
	)
	(zone
		(net "XP3R3V_GPS")
		(layer "B.Cu")
		(hatch none 0.5)
		(connect_pads
			(clearance 0.5)
		)
		(min_thickness 0.25)
		(fill yes
			(thermal_gap 0.5)
			(thermal_bridge_width 0.5)
			(island_removal_mode 0)
		)
		(polygon
			(pts
				(xy 117.983 -98.679) (xy 117.983 -100.838) (xy 118.11 -100.965) (xy 120.015 -100.965) (xy 120.269 -100.711)
				(xy 120.269 -98.806) (xy 120.142 -98.679)
			)
		)
	)
	(zone
		(net "SG")
		(layer "B.Cu")
		(hatch none 0.5)
		(connect_pads
			(clearance 0.5)
		)
		(min_thickness 0.25)
		(fill yes
			(thermal_gap 0.5)
			(thermal_bridge_width 0.5)
			(island_removal_mode 0)
		)
		(polygon
			(pts
				(xy 136.525 -46.736) (xy 138.176 -46.736) (xy 138.303 -46.863) (xy 138.303 -48.641) (xy 138.176 -48.768)
				(xy 136.652 -48.768) (xy 136.525 -48.641)
			)
		)
	)
	(zone
		(layer "B.Cu")
		(hatch none 0.5)
		(connect_pads
			(clearance 0)
		)
		(min_thickness 0.25)
		(keepout
			(tracks allowed)
			(vias allowed)
			(pads allowed)
			(copperpour allowed)
			(footprints not_allowed)
		)
		(placement
			(enabled no)
			(sheetname "")
		)
		(fill
			(thermal_gap 0.5)
			(thermal_bridge_width 0.5)
			(island_removal_mode 0)
		)
		(polygon
			(pts
				(xy 157.619954 -110.149894) (xy 157.619954 -99.70008) (xy 167.649906 -99.70008)
				(arc
					(start 167.649906 -110.149894)
					(mid 167.357013 -110.856999)
					(end 166.649908 -111.149892)
				)
				(arc
					(start 0.999998 -111.149892)
					(mid 0.292893 -110.856999)
					(end 0 -110.149894)
				)
				(xy 0 -89.7001) (xy 0.999998 -89.7001) (xy 12.7 -89.7001) (xy 12.7 -110.149894)
			)
		)
	)
	(zone
		(layer "B.Cu")
		(hatch none 0.5)
		(connect_pads
			(clearance 0)
		)
		(min_thickness 0.25)
		(keepout
			(tracks allowed)
			(vias allowed)
			(pads allowed)
			(copperpour allowed)
			(footprints not_allowed)
		)
		(placement
			(enabled no)
			(sheetname "")
		)
		(fill
			(thermal_gap 0.5)
			(thermal_bridge_width 0.5)
			(island_removal_mode 0)
		)
		(polygon
			(pts
				(arc
					(start 34.101024 -68.082922)
					(mid 37.101018 -71.082916)
					(end 40.101012 -68.082922)
				)
				(arc
					(start 40.101012 -68.082922)
					(mid 37.101018 -65.082928)
					(end 34.101024 -68.082922)
				)
			)
		)
	)
	(zone
		(net "SG")
		(layer "B.Cu")
		(hatch none 0.5)
		(connect_pads
			(clearance 0.5)
		)
		(min_thickness 0.25)
		(fill yes
			(thermal_gap 0.5)
			(thermal_bridge_width 0.5)
			(island_removal_mode 0)
		)
		(polygon
			(pts
				(xy 127.635 -98.171) (xy 129.413 -98.171) (xy 129.54 -98.044) (xy 129.54 -94.996) (xy 129.413 -94.869)
				(xy 128.016 -94.869) (xy 127.635 -95.25)
			)
		)
	)
	(zone
		(layer "B.Cu")
		(hatch none 0.5)
		(connect_pads
			(clearance 0)
		)
		(min_thickness 0.25)
		(keepout
			(tracks allowed)
			(vias allowed)
			(pads allowed)
			(copperpour allowed)
			(footprints not_allowed)
		)
		(placement
			(enabled no)
			(sheetname "")
		)
		(fill
			(thermal_gap 0.5)
			(thermal_bridge_width 0.5)
			(island_removal_mode 0)
		)
		(polygon
			(pts
				(xy 79.30007 -13.750036) (xy 44.99991 -13.750036) (xy 44.99991 -10.925048) (xy 44.99991 -0.500126)
				(xy 45.500036 0) (xy 55.699914 0) (xy 56.20004 -0.500126)
				(arc
					(start 56.20004 -7.450074)
					(mid 57.15 -8.400034)
					(end 58.09996 -7.450074)
				)
				(xy 58.09996 -0.500126) (xy 58.600086 0) (xy 78.799944 0) (xy 79.30007 -0.500126)
			)
		)
	)
	(zone
		(net "XP12R0V")
		(layer "B.Cu")
		(hatch none 0.5)
		(connect_pads
			(clearance 0.5)
		)
		(min_thickness 0.25)
		(fill yes
			(thermal_gap 0.5)
			(thermal_bridge_width 0.5)
			(island_removal_mode 0)
		)
		(polygon
			(pts
				(xy 136.652 -91.1606) (xy 137.9982 -91.1606) (xy 138.2522 -91.1606) (xy 138.4554 -91.3638) (xy 138.4554 -94.6404)
				(xy 138.4554 -94.8436) (xy 138.0871 -95.2119) (xy 133.5405 -95.2119) (xy 133.4262 -95.0976) (xy 133.4262 -94.8182)
				(xy 133.4262 -92.8878) (xy 133.731 -92.583) (xy 136.017 -92.583) (xy 136.525 -92.075) (xy 136.525 -91.2876)
			)
		)
	)
	(zone
		(net "XP5R0V")
		(layer "B.Cu")
		(hatch none 0.5)
		(connect_pads
			(clearance 0.5)
		)
		(min_thickness 0.25)
		(fill yes
			(thermal_gap 0.5)
			(thermal_bridge_width 0.5)
			(island_removal_mode 0)
		)
		(polygon
			(pts
				(xy 54.0766 -101.4476) (xy 57.404 -101.4476) (xy 58.1914 -100.6602) (xy 58.1914 -98.5774) (xy 57.404 -97.79)
				(xy 55.372 -97.79) (xy 54.8894 -97.3074) (xy 54.8894 -97.155) (xy 54.8894 -96.2406) (xy 55.5244 -95.6056)
				(xy 55.7276 -95.4024) (xy 58.9534 -95.4024) (xy 61.4172 -92.9386) (xy 65.6844 -92.9386) (xy 66.548 -92.075)
				(xy 66.548 -87.503) (xy 66.294 -87.249) (xy 61.2394 -87.249) (xy 57.2389 -91.2495) (xy 52.5907 -91.2495)
				(xy 51.3334 -92.5068) (xy 51.3334 -100.1268) (xy 52.6542 -101.4476)
			)
		)
	)
	(zone
		(net "XP3R3V_PCIE")
		(layer "B.Cu")
		(hatch none 0.5)
		(connect_pads
			(clearance 0.5)
		)
		(min_thickness 0.25)
		(fill yes
			(thermal_gap 0.5)
			(thermal_bridge_width 0.5)
			(island_removal_mode 0)
		)
		(polygon
			(pts
				(xy 54.483 -15.875) (xy 58.039 -15.875) (xy 58.039 -14.351) (xy 58.039 -13.589) (xy 54.864 -10.414)
				(xy 54.864 -7.493) (xy 54.61 -7.239) (xy 52.832 -7.239) (xy 52.705 -7.366) (xy 52.705 -10.668) (xy 54.102 -12.065)
				(xy 54.483 -12.446)
			)
		)
	)
	(zone
		(layer "B.Cu")
		(hatch none 0.5)
		(connect_pads
			(clearance 0)
		)
		(min_thickness 0.25)
		(keepout
			(tracks allowed)
			(vias allowed)
			(pads allowed)
			(copperpour allowed)
			(footprints allowed)
		)
		(placement
			(enabled no)
			(sheetname "")
		)
		(fill
			(thermal_gap 0.5)
			(thermal_bridge_width 0.5)
			(island_removal_mode 0)
		)
		(polygon
			(pts
				(xy 13.335 -75.565) (xy 13.335 -74.803) (xy 14.732 -74.803) (xy 14.732 -75.565)
			)
		)
	)
	(zone
		(net "XP1R2V_FPGA")
		(layer "B.Cu")
		(hatch none 0.5)
		(connect_pads
			(clearance 0.5)
		)
		(min_thickness 0.25)
		(fill yes
			(thermal_gap 0.5)
			(thermal_bridge_width 0.5)
			(island_removal_mode 0)
		)
		(polygon
			(pts
				(xy 91.948 -35.433) (xy 91.948 -36.322) (xy 91.694 -36.576) (xy 91.44 -36.83) (xy 88.138 -36.83)
				(xy 87.249 -36.83) (xy 87.122 -36.703) (xy 87.122 -35.0012) (xy 87.2236 -34.8996) (xy 87.3252 -34.798)
				(xy 90.043 -34.798) (xy 90.424 -34.417) (xy 91.948 -34.417)
			)
		)
	)
	(zone
		(layer "B.Cu")
		(hatch none 0.5)
		(connect_pads
			(clearance 0)
		)
		(min_thickness 0.25)
		(keepout
			(tracks not_allowed)
			(vias allowed)
			(pads allowed)
			(copperpour not_allowed)
			(footprints allowed)
		)
		(placement
			(enabled no)
			(sheetname "")
		)
		(fill
			(thermal_gap 0.5)
			(thermal_bridge_width 0.5)
			(island_removal_mode 0)
		)
		(polygon
			(pts
				(xy 157.619954 -99.70008) (xy 167.649906 -99.70008)
				(arc
					(start 167.649906 -110.149894)
					(mid 167.357013 -110.856999)
					(end 166.649908 -111.149892)
				)
				(arc
					(start 0.999998 -111.149892)
					(mid 0.292893 -110.856999)
					(end 0 -110.149894)
				)
				(xy 0 -89.7001) (xy 0.999998 -89.7001) (xy 12.7 -89.7001) (xy 12.7 -110.149894) (xy 137.150094 -110.149894)
				(xy 157.619954 -110.149894)
			)
		)
	)
	(zone
		(net "XP5R0V")
		(layer "B.Cu")
		(hatch none 0.5)
		(connect_pads
			(clearance 0.5)
		)
		(min_thickness 0.25)
		(fill yes
			(thermal_gap 0.5)
			(thermal_bridge_width 0.5)
			(island_removal_mode 0)
		)
		(polygon
			(pts
				(xy 80.264 -73.66) (xy 81.661 -73.66) (xy 81.788 -73.533) (xy 82.677 -73.533) (xy 82.677 -75.184)
				(xy 82.423 -75.438) (xy 80.518 -75.438) (xy 80.264 -75.184)
			)
		)
	)
	(zone
		(net "XP3R3V")
		(layer "B.Cu")
		(hatch none 0.5)
		(connect_pads
			(clearance 0.5)
		)
		(min_thickness 0.25)
		(fill yes
			(thermal_gap 0.5)
			(thermal_bridge_width 0.5)
			(island_removal_mode 0)
		)
		(polygon
			(pts
				(xy 91.4908 -76.1746) (xy 93.7514 -76.1746) (xy 93.9038 -76.327) (xy 93.9038 -79.1718) (xy 93.8022 -79.2734)
				(xy 91.6178 -79.2734) (xy 91.3892 -79.0448) (xy 91.3892 -76.2762)
			)
		)
	)
	(zone
		(net "SG")
		(layer "B.Cu")
		(hatch none 0.5)
		(connect_pads
			(clearance 0.5)
		)
		(min_thickness 0.25)
		(fill yes
			(thermal_gap 0.5)
			(thermal_bridge_width 0.5)
			(island_removal_mode 0)
		)
		(polygon
			(pts
				(xy 77.343 -50.419) (xy 77.47 -50.292) (xy 77.47 -48.768) (xy 78.613 -48.768) (xy 79.248 -48.768)
				(xy 79.375 -48.895) (xy 79.375 -52.07) (xy 79.121 -52.324) (xy 78.74 -52.324) (xy 77.343 -52.324)
				(xy 76.962 -52.324) (xy 76.962 -50.8)
			)
		)
	)
	(zone
		(layer "B.Cu")
		(hatch none 0.5)
		(connect_pads
			(clearance 0)
		)
		(min_thickness 0.25)
		(keepout
			(tracks allowed)
			(vias allowed)
			(pads allowed)
			(copperpour allowed)
			(footprints not_allowed)
		)
		(placement
			(enabled no)
			(sheetname "")
		)
		(fill
			(thermal_gap 0.5)
			(thermal_bridge_width 0.5)
			(island_removal_mode 0)
		)
		(polygon
			(pts
				(arc
					(start 33.466024 -26.934922)
					(mid 36.466018 -29.934916)
					(end 39.466012 -26.934922)
				)
				(arc
					(start 39.466012 -26.934922)
					(mid 36.466018 -23.934928)
					(end 33.466024 -26.934922)
				)
			)
		)
	)
	(zone
		(layer "B.Cu")
		(hatch none 0.5)
		(connect_pads
			(clearance 0)
		)
		(min_thickness 0.25)
		(keepout
			(tracks allowed)
			(vias allowed)
			(pads allowed)
			(copperpour allowed)
			(footprints not_allowed)
		)
		(placement
			(enabled no)
			(sheetname "")
		)
		(fill
			(thermal_gap 0.5)
			(thermal_bridge_width 0.5)
			(island_removal_mode 0)
		)
		(polygon
			(pts
				(arc
					(start 65.216024 -28.484322)
					(mid 68.216018 -31.484316)
					(end 71.216012 -28.484322)
				)
				(arc
					(start 71.216012 -28.484322)
					(mid 68.216018 -25.484328)
					(end 65.216024 -28.484322)
				)
			)
		)
	)
	(zone
		(net "SG")
		(layer "B.Cu")
		(hatch none 0.5)
		(connect_pads
			(clearance 0.5)
		)
		(min_thickness 0.25)
		(fill yes
			(thermal_gap 0.5)
			(thermal_bridge_width 0.5)
			(island_removal_mode 0)
		)
		(polygon
			(pts
				(xy 129.413 -63.8302) (xy 132.2578 -63.8302) (xy 132.4102 -63.6778) (xy 132.4102 -60.9854) (xy 132.207 -60.7822)
				(xy 129.0828 -60.7822) (xy 128.7526 -60.7822) (xy 128.524 -61.0108) (xy 128.524 -63.5508) (xy 128.8034 -63.8302)
			)
		)
	)
	(zone
		(net "SG")
		(layer "B.Cu")
		(hatch none 0.5)
		(connect_pads
			(clearance 0.5)
		)
		(min_thickness 0.25)
		(fill yes
			(thermal_gap 0.5)
			(thermal_bridge_width 0.5)
			(island_removal_mode 0)
		)
		(polygon
			(pts
				(xy 92.964 -57.277) (xy 92.964 -55.88) (xy 92.583 -55.499) (xy 92.583 -54.61) (xy 92.456 -54.483)
				(xy 92.329 -54.356) (xy 92.329 -53.721) (xy 92.456 -53.594) (xy 93.091 -53.594) (xy 94.615 -53.594)
				(xy 94.742 -53.721) (xy 94.742 -56.896) (xy 94.361 -57.277)
			)
		)
	)
	(zone
		(net "SG")
		(layer "B.Cu")
		(hatch none 0.5)
		(connect_pads
			(clearance 0.5)
		)
		(min_thickness 0.25)
		(fill yes
			(thermal_gap 0.5)
			(thermal_bridge_width 0.5)
			(island_removal_mode 0)
		)
		(polygon
			(pts
				(xy 143.5608 -22.7076) (xy 143.5608 -22.5298) (xy 143.5608 -22.3012) (xy 143.5608 -20.9296) (xy 143.5862 -20.9042)
				(xy 143.5862 -17.8562) (xy 143.129 -17.399) (xy 142.3162 -17.399) (xy 142.0622 -17.653) (xy 142.0622 -18.4404)
				(xy 142.0622 -19.685) (xy 141.8082 -19.939) (xy 140.6652 -19.939) (xy 140.462 -20.1422) (xy 140.462 -20.8534)
				(xy 140.462 -22.225) (xy 140.462 -22.7584) (xy 140.7922 -23.0886) (xy 143.1798 -23.0886)
			)
		)
	)
	(zone
		(layer "B.Cu")
		(hatch none 0.5)
		(connect_pads
			(clearance 0)
		)
		(min_thickness 0.25)
		(keepout
			(tracks not_allowed)
			(vias allowed)
			(pads allowed)
			(copperpour not_allowed)
			(footprints allowed)
		)
		(placement
			(enabled no)
			(sheetname "")
		)
		(fill
			(thermal_gap 0.5)
			(thermal_bridge_width 0.5)
			(island_removal_mode 0)
		)
		(polygon
			(pts
				(arc
					(start 65.216024 -28.484322)
					(mid 68.216018 -31.484316)
					(end 71.216012 -28.484322)
				)
				(arc
					(start 71.216012 -28.484322)
					(mid 68.216018 -25.484328)
					(end 65.216024 -28.484322)
				)
			)
		)
	)
	(zone
		(net "SG")
		(layer "B.Cu")
		(hatch none 0.5)
		(connect_pads
			(clearance 0.5)
		)
		(min_thickness 0.25)
		(fill yes
			(thermal_gap 0.5)
			(thermal_bridge_width 0.5)
			(island_removal_mode 0)
		)
		(polygon
			(pts
				(xy 117.475 -98.679) (xy 117.475 -100.965) (xy 117.348 -101.092) (xy 115.062 -101.092) (xy 114.681 -100.711)
				(xy 114.681 -98.806) (xy 114.808 -98.679)
			)
		)
	)
	(zone
		(layer "B.Cu")
		(hatch none 0.5)
		(connect_pads
			(clearance 0)
		)
		(min_thickness 0.25)
		(keepout
			(tracks allowed)
			(vias allowed)
			(pads allowed)
			(copperpour allowed)
			(footprints not_allowed)
		)
		(placement
			(enabled no)
			(sheetname "")
		)
		(fill
			(thermal_gap 0.5)
			(thermal_bridge_width 0.5)
			(island_removal_mode 0)
		)
		(polygon
			(pts
				(xy 0 -13.750036)
				(arc
					(start 0 -5.500116)
					(mid 0.292893 -4.793011)
					(end 0.999998 -4.500118)
				)
				(arc
					(start 13.999972 -4.500118)
					(mid 14.707077 -4.793011)
					(end 14.99997 -5.500116)
				)
				(arc
					(start 14.99997 -11.75004)
					(mid 15.292863 -12.457145)
					(end 15.999968 -12.750038)
				)
				(arc
					(start 32.349948 -12.750038)
					(mid 33.057053 -12.457145)
					(end 33.349946 -11.75004)
				)
				(arc
					(start 33.349946 -5.500116)
					(mid 33.642839 -4.793011)
					(end 34.349944 -4.500118)
				)
				(arc
					(start 40.349932 -4.500118)
					(mid 41.057037 -4.793011)
					(end 41.34993 -5.500116)
				)
				(arc
					(start 41.34993 -10.925048)
					(mid 43.17492 -12.750038)
					(end 44.99991 -10.925048)
				)
				(xy 44.99991 -13.750036) (xy 1.035812 -13.750036)
			)
		)
	)
	(zone
		(net "VIN_XP1R0V")
		(layer "B.Cu")
		(hatch none 0.5)
		(connect_pads
			(clearance 0.5)
		)
		(min_thickness 0.25)
		(fill yes
			(thermal_gap 0.5)
			(thermal_bridge_width 0.5)
			(island_removal_mode 0)
		)
		(polygon
			(pts
				(xy 144.653 -54.1274) (xy 146.177 -54.1274) (xy 146.5326 -54.483) (xy 146.5326 -56.134) (xy 146.3548 -56.3118)
				(xy 144.8816 -56.3118) (xy 144.653 -56.0832) (xy 144.4752 -55.9054) (xy 144.4752 -54.3052)
			)
		)
	)
	(zone
		(net "XP12R0V_IN")
		(layer "B.Cu")
		(hatch none 0.5)
		(connect_pads
			(clearance 0.5)
		)
		(min_thickness 0.25)
		(fill yes
			(thermal_gap 0.5)
			(thermal_bridge_width 0.5)
			(island_removal_mode 0)
		)
		(polygon
			(pts
				(xy 139.8524 -86.5886) (xy 139.8524 -80.5942) (xy 140.1445 -80.3021) (xy 143.1036 -80.3021) (xy 143.5608 -80.7593)
				(xy 143.5608 -87.9094) (xy 143.002 -88.4682) (xy 140.1318 -88.4682) (xy 139.8524 -88.1888)
			)
		)
	)
	(zone
		(layer "B.Cu")
		(hatch none 0.5)
		(connect_pads
			(clearance 0)
		)
		(min_thickness 0.25)
		(keepout
			(tracks not_allowed)
			(vias allowed)
			(pads allowed)
			(copperpour not_allowed)
			(footprints allowed)
		)
		(placement
			(enabled no)
			(sheetname "")
		)
		(fill
			(thermal_gap 0.5)
			(thermal_bridge_width 0.5)
			(island_removal_mode 0)
		)
		(polygon
			(pts
				(arc
					(start 65.216024 -65.009522)
					(mid 68.216018 -68.009516)
					(end 71.216012 -65.009522)
				)
				(arc
					(start 71.216012 -65.009522)
					(mid 68.216018 -62.009528)
					(end 65.216024 -65.009522)
				)
			)
		)
	)
	(zone
		(layer "B.Cu")
		(hatch none 0.5)
		(connect_pads
			(clearance 0)
		)
		(min_thickness 0.25)
		(keepout
			(tracks not_allowed)
			(vias allowed)
			(pads allowed)
			(copperpour not_allowed)
			(footprints allowed)
		)
		(placement
			(enabled no)
			(sheetname "")
		)
		(fill
			(thermal_gap 0.5)
			(thermal_bridge_width 0.5)
			(island_removal_mode 0)
		)
		(polygon
			(pts
				(arc
					(start 34.101024 -68.082922)
					(mid 37.101018 -71.082916)
					(end 40.101012 -68.082922)
				)
				(arc
					(start 40.101012 -68.082922)
					(mid 37.101018 -65.082928)
					(end 34.101024 -68.082922)
				)
			)
		)
	)
	(zone
		(layer "B.Cu")
		(hatch none 0.5)
		(connect_pads
			(clearance 0)
		)
		(min_thickness 0.25)
		(keepout
			(tracks allowed)
			(vias allowed)
			(pads allowed)
			(copperpour allowed)
			(footprints not_allowed)
		)
		(placement
			(enabled no)
			(sheetname "")
		)
		(fill
			(thermal_gap 0.5)
			(thermal_bridge_width 0.5)
			(island_removal_mode 0)
		)
		(polygon
			(pts
				(arc
					(start 65.216024 -65.009522)
					(mid 68.216018 -68.009516)
					(end 71.216012 -65.009522)
				)
				(arc
					(start 71.216012 -65.009522)
					(mid 68.216018 -62.009528)
					(end 65.216024 -65.009522)
				)
			)
		)
	)
	(zone
		(layer "B.Cu")
		(hatch none 0.5)
		(connect_pads
			(clearance 0)
		)
		(min_thickness 0.25)
		(keepout
			(tracks allowed)
			(vias allowed)
			(pads allowed)
			(copperpour allowed)
			(footprints not_allowed)
		)
		(placement
			(enabled no)
			(sheetname "")
		)
		(fill
			(thermal_gap 0.5)
			(thermal_bridge_width 0.5)
			(island_removal_mode 0)
		)
		(polygon
			(pts
				(xy 157.619954 -22.899878) (xy 157.619954 -13.750036) (xy 79.30007 -13.750036)
				(arc
					(start 79.30007 -11.75004)
					(mid 79.592963 -12.457145)
					(end 80.300068 -12.750038)
				)
				(arc
					(start 166.649908 -12.750038)
					(mid 167.357013 -13.042931)
					(end 167.649906 -13.750036)
				)
				(xy 167.649906 -22.899878)
			)
		)
	)
	(zone
		(net "SG")
		(layer "B.Cu")
		(hatch none 0.5)
		(connect_pads
			(clearance 0.5)
		)
		(min_thickness 0.25)
		(fill yes
			(thermal_gap 0.5)
			(thermal_bridge_width 0.5)
			(island_removal_mode 0)
		)
		(polygon
			(pts
				(xy 104.267 -70.4596) (xy 103.632 -70.4596) (xy 103.3526 -70.739) (xy 103.3526 -74.7268) (xy 104.0384 -75.4126)
				(xy 105.3338 -75.4126) (xy 105.5116 -75.2348) (xy 105.5116 -70.993) (xy 105.5116 -70.6374) (xy 105.3338 -70.4596)
				(xy 104.9782 -70.4596)
			)
		)
	)
	(zone
		(net "SG")
		(layer "B.Cu")
		(hatch none 0.5)
		(connect_pads
			(clearance 0.5)
		)
		(min_thickness 0.25)
		(fill yes
			(thermal_gap 0.5)
			(thermal_bridge_width 0.5)
			(island_removal_mode 0)
		)
		(polygon
			(pts
				(xy 132.6896 -81.6356) (xy 132.6388 -81.6864) (xy 132.6388 -90.3478) (xy 132.842 -90.551) (xy 136.7536 -90.551)
				(xy 136.8806 -90.424) (xy 139.319 -87.9856) (xy 139.319 -80.899) (xy 139.065 -80.645) (xy 133.223 -80.645)
				(xy 132.6896 -81.1784)
			)
		)
	)
	(zone
		(net "SG")
		(layer "B.Cu")
		(hatch none 0.5)
		(connect_pads
			(clearance 0.5)
		)
		(min_thickness 0.25)
		(fill yes
			(thermal_gap 0.5)
			(thermal_bridge_width 0.5)
			(island_removal_mode 0)
		)
		(polygon
			(pts
				(xy 91.6432 -75.4634) (xy 94.4118 -75.4634) (xy 94.5134 -75.3618) (xy 94.5134 -72.517) (xy 94.2848 -72.2884)
				(xy 91.5416 -72.2884) (xy 91.4146 -72.4154) (xy 91.4146 -75.2348)
			)
		)
	)
	(zone
		(net "XP1R0V_FPGA")
		(layer "B.Cu")
		(hatch none 0.5)
		(connect_pads
			(clearance 0.5)
		)
		(min_thickness 0.25)
		(fill yes
			(thermal_gap 0.5)
			(thermal_bridge_width 0.5)
			(island_removal_mode 0)
		)
		(polygon
			(pts
				(xy 136.652 -41.656) (xy 138.176 -41.656) (xy 138.303 -41.783) (xy 138.303 -45.72) (xy 138.176 -45.847)
				(xy 136.652 -45.847) (xy 136.398 -45.847) (xy 136.271 -45.72) (xy 136.271 -41.783) (xy 136.398 -41.656)
			)
		)
	)
	(zone
		(net "XP5R0V_MAC_USB")
		(layer "B.Cu")
		(hatch none 0.5)
		(connect_pads
			(clearance 0.5)
		)
		(min_thickness 0.25)
		(fill yes
			(thermal_gap 0.5)
			(thermal_bridge_width 0.5)
			(island_removal_mode 0)
		)
		(polygon
			(pts
				(xy 69.088 -56.261) (xy 69.596 -56.261) (xy 70.485 -55.372) (xy 72.771 -55.372) (xy 75.311 -52.832)
				(xy 75.819 -52.324) (xy 76.2 -52.324) (xy 76.327 -52.197) (xy 76.327 -50.292) (xy 76.708 -49.911)
				(xy 76.708 -47.498) (xy 76.708 -47.244) (xy 76.581 -47.117) (xy 74.93 -47.117) (xy 73.279 -48.768)
				(xy 73.279 -49.149) (xy 73.279 -50.673) (xy 72.771 -51.181) (xy 71.247 -51.181) (xy 69.088 -53.34)
			)
		)
	)
	(zone
		(net "XP3R3V_FT4232")
		(layer "B.Cu")
		(hatch none 0.5)
		(connect_pads
			(clearance 0.5)
		)
		(min_thickness 0.25)
		(fill yes
			(thermal_gap 0.5)
			(thermal_bridge_width 0.5)
			(island_removal_mode 0)
		)
		(polygon
			(pts
				(xy 27.051 -88.265) (xy 28.321 -88.265) (xy 28.575 -88.519) (xy 29.337 -88.519) (xy 29.591 -88.265)
				(xy 29.591 -87.376) (xy 29.337 -87.122) (xy 27.178 -87.122) (xy 26.924 -87.376) (xy 26.924 -88.138)
			)
		)
	)
	(zone
		(net "SG")
		(layer "B.Cu")
		(hatch none 0.5)
		(connect_pads
			(clearance 0.5)
		)
		(min_thickness 0.25)
		(fill yes
			(thermal_gap 0.5)
			(thermal_bridge_width 0.5)
			(island_removal_mode 0)
		)
		(polygon
			(pts
				(xy 94.488 -33.909) (xy 94.234 -33.909) (xy 94.107 -33.782) (xy 94.107 -32.512) (xy 94.234 -32.385)
				(xy 94.742 -32.385) (xy 96.266 -32.385) (xy 96.774 -32.893) (xy 96.774 -33.147) (xy 96.774 -33.655)
				(xy 96.52 -33.909)
			)
		)
	)
	(zone
		(net "XP5R0V_MAC")
		(layer "B.Cu")
		(hatch none 0.5)
		(connect_pads
			(clearance 0.5)
		)
		(min_thickness 0.25)
		(fill yes
			(thermal_gap 0.5)
			(thermal_bridge_width 0.5)
			(island_removal_mode 0)
		)
		(polygon
			(pts
				(xy 81.534 -72.644) (xy 72.009 -72.644) (xy 71.374 -72.009) (xy 71.374 -68.199) (xy 71.628 -67.945)
				(xy 71.628 -63.627) (xy 71.628 -63.373) (xy 71.374 -63.119) (xy 68.961 -60.706) (xy 68.961 -59.944)
				(xy 68.961 -58.039) (xy 69.469 -58.039) (xy 70.231 -58.801) (xy 71.374 -58.801) (xy 71.755 -59.182)
				(xy 76.073 -59.182) (xy 76.454 -59.563) (xy 76.708 -59.73445) (xy 76.708 -60.198) (xy 76.708 -68.453)
				(xy 78.486 -70.231) (xy 79.375 -71.12) (xy 81.28 -71.12) (xy 81.534 -71.374)
			)
		)
	)
	(zone
		(net "SG")
		(layer "B.Cu")
		(hatch none 0.5)
		(connect_pads
			(clearance 0.5)
		)
		(min_thickness 0.25)
		(fill yes
			(thermal_gap 0.5)
			(thermal_bridge_width 0.5)
			(island_removal_mode 0)
		)
		(polygon
			(pts
				(xy 143.3576 -53.3146) (xy 143.1036 -53.0606) (xy 143.1036 -51.816) (xy 143.3322 -51.5874) (xy 146.05 -51.5874)
				(xy 146.2659 -51.8033) (xy 146.2659 -53.0225) (xy 145.9738 -53.3146)
			)
		)
	)
	(zone
		(layer "B.Cu")
		(hatch none 0.5)
		(connect_pads
			(clearance 0)
		)
		(min_thickness 0.25)
		(keepout
			(tracks not_allowed)
			(vias allowed)
			(pads allowed)
			(copperpour not_allowed)
			(footprints allowed)
		)
		(placement
			(enabled no)
			(sheetname "")
		)
		(fill
			(thermal_gap 0.5)
			(thermal_bridge_width 0.5)
			(island_removal_mode 0)
		)
		(polygon
			(pts
				(arc
					(start 33.466024 -26.934922)
					(mid 36.466018 -29.934916)
					(end 39.466012 -26.934922)
				)
				(arc
					(start 39.466012 -26.934922)
					(mid 36.466018 -23.934928)
					(end 33.466024 -26.934922)
				)
			)
		)
	)
	(zone
		(net "SG")
		(layer "B.Cu")
		(hatch none 0.5)
		(connect_pads
			(clearance 0.5)
		)
		(min_thickness 0.25)
		(fill yes
			(thermal_gap 0.5)
			(thermal_bridge_width 0.5)
			(island_removal_mode 0)
		)
		(polygon
			(pts
				(xy 136.652 -41.021) (xy 138.43 -41.021) (xy 138.557 -40.894) (xy 138.557 -40.132) (xy 138.43 -40.005)
				(xy 136.779 -40.005) (xy 136.652 -40.132)
			)
		)
	)
	(zone
		(net "XP3R3V")
		(layer "B.Cu")
		(hatch none 0.5)
		(connect_pads
			(clearance 0.5)
		)
		(min_thickness 0.25)
		(fill yes
			(thermal_gap 0.5)
			(thermal_bridge_width 0.5)
			(island_removal_mode 0)
		)
		(polygon
			(pts
				(xy 56.769 -16.891) (xy 58.928 -16.891) (xy 59.055 -17.018) (xy 59.055 -18.288) (xy 58.801 -18.542)
				(xy 57.023 -18.542) (xy 56.769 -18.288)
			)
		)
	)
	(zone
		(net "FPGA_MGTAVTT")
		(layer "B.Cu")
		(hatch none 0.5)
		(connect_pads
			(clearance 0.5)
		)
		(min_thickness 0.25)
		(fill yes
			(thermal_gap 0.5)
			(thermal_bridge_width 0.5)
			(island_removal_mode 0)
		)
		(polygon
			(pts
				(xy 93.1545 -36.068) (xy 93.1545 -34.9504) (xy 93.1545 -34.6964) (xy 93.1545 -34.4805) (xy 93.218 -34.417)
				(xy 96.647 -34.417) (xy 96.901 -34.417) (xy 97.282 -34.417) (xy 97.536 -34.671) (xy 97.536 -36.576)
				(xy 97.155 -36.957) (xy 96.901 -36.957) (xy 96.647 -36.957) (xy 93.345 -36.957) (xy 93.218 -36.83)
				(xy 93.218 -36.068)
			)
		)
	)
	(zone
		(net "XP3R3V_FPGA")
		(layer "B.Cu")
		(hatch none 0.5)
		(connect_pads
			(clearance 0.5)
		)
		(min_thickness 0.25)
		(fill yes
			(thermal_gap 0.5)
			(thermal_bridge_width 0.5)
			(island_removal_mode 0)
		)
		(polygon
			(pts
				(xy 106.7054 -70.0024) (xy 108.0516 -70.0024) (xy 108.2802 -70.0024) (xy 108.5088 -70.231) (xy 108.5088 -75.3364)
				(xy 108.2294 -75.6158) (xy 108.0262 -75.6158) (xy 106.2482 -75.6158) (xy 106.1212 -75.4888) (xy 106.1212 -73.0504)
				(xy 106.1339 -73.0377) (xy 106.1339 -70.2437) (xy 106.3752 -70.0024)
			)
		)
	)
	(zone
		(net "XP1R8V_FPGA")
		(layer "B.Cu")
		(hatch none 0.5)
		(connect_pads
			(clearance 0.5)
		)
		(min_thickness 0.25)
		(fill yes
			(thermal_gap 0.5)
			(thermal_bridge_width 0.5)
			(island_removal_mode 0)
		)
		(polygon
			(pts
				(xy 92.202 -56.134) (xy 92.202 -57.277) (xy 92.202 -57.404) (xy 91.948 -57.658) (xy 90.043 -57.658)
				(xy 89.916 -57.531) (xy 89.916 -57.023) (xy 89.916 -55.118) (xy 90.17 -54.864) (xy 90.297 -54.864)
				(xy 91.821 -54.864) (xy 91.821 -55.753)
			)
		)
	)
	(zone
		(layer "B.Cu")
		(hatch none 0.5)
		(connect_pads
			(clearance 0)
		)
		(min_thickness 0.25)
		(keepout
			(tracks allowed)
			(vias allowed)
			(pads allowed)
			(copperpour allowed)
			(footprints allowed)
		)
		(placement
			(enabled no)
			(sheetname "")
		)
		(fill
			(thermal_gap 0.5)
			(thermal_bridge_width 0.5)
			(island_removal_mode 0)
		)
		(polygon
			(pts
				(xy 143.13916 -60.06338) (xy 143.13916 -59.13374) (xy 143.6243 -59.13374) (xy 143.6243 -60.06338)
			)
		)
	)
	(zone
		(layer "B.Cu")
		(hatch none 0.5)
		(connect_pads
			(clearance 0)
		)
		(min_thickness 0.25)
		(keepout
			(tracks allowed)
			(vias allowed)
			(pads allowed)
			(copperpour allowed)
			(footprints not_allowed)
		)
		(placement
			(enabled no)
			(sheetname "")
		)
		(fill
			(thermal_gap 0.5)
			(thermal_bridge_width 0.5)
			(island_removal_mode 0)
		)
		(polygon
			(pts
				(xy 0.999998 -89.7001) (xy 0 -89.7001) (xy 0 -13.750036) (xy 79.30007 -13.750036) (xy 157.619954 -13.750036)
				(xy 157.619954 -22.899878) (xy 167.649906 -22.899878)
				(arc
					(start 167.649906 -60.325)
					(mid 167.503587 -60.678627)
					(end 167.150034 -60.825126)
				)
				(arc
					(start 166.931594 -60.825126)
					(mid 166.578131 -60.971535)
					(end 166.431722 -61.324998)
				)
				(arc
					(start 166.431722 -71.799958)
					(mid 166.578026 -72.153675)
					(end 166.931594 -72.300084)
				)
				(arc
					(start 167.150034 -72.300084)
					(mid 167.503497 -72.446493)
					(end 167.649906 -72.799956)
				)
				(xy 167.649906 -99.70008) (xy 157.619954 -99.70008) (xy 157.619954 -108.149898) (xy 157.619954 -110.149894)
				(xy 137.150094 -110.149894) (xy 12.7 -110.149894) (xy 12.7 -89.7001)
			)
		)
	)
	(zone
		(net "XP3R3V")
		(layer "B.Cu")
		(hatch none 0.5)
		(connect_pads
			(clearance 0.5)
		)
		(min_thickness 0.25)
		(fill yes
			(thermal_gap 0.5)
			(thermal_bridge_width 0.5)
			(island_removal_mode 0)
		)
		(polygon
			(pts
				(xy 127.889 -60.9854) (xy 127.889 -63.119) (xy 127.762 -63.246) (xy 125.1458 -63.246) (xy 125.0188 -63.246)
				(xy 124.8156 -63.0428) (xy 124.8156 -62.9158) (xy 124.8156 -60.8838) (xy 124.9934 -60.706) (xy 127.6096 -60.706)
			)
		)
	)
	(zone
		(net "XP12R0V_PCIE")
		(layer "B.Cu")
		(hatch none 0.5)
		(connect_pads
			(clearance 0.5)
		)
		(min_thickness 0.25)
		(fill yes
			(thermal_gap 0.5)
			(thermal_bridge_width 0.5)
			(island_removal_mode 0)
		)
		(polygon
			(pts
				(xy 46.5582 -9.9314) (xy 47.5996 -9.9314) (xy 47.879 -9.652) (xy 48.387 -9.144) (xy 48.387 -8.255)
				(xy 47.879 -7.747) (xy 47.879 -7.239) (xy 47.752 -7.112) (xy 46.482 -7.112) (xy 46.3296 -7.2644)
				(xy 46.3296 -9.7028)
			)
		)
	)
	(zone
		(layer "In1.Cu")
		(hatch none 0.5)
		(connect_pads
			(clearance 0)
		)
		(min_thickness 0.25)
		(keepout
			(tracks not_allowed)
			(vias allowed)
			(pads allowed)
			(copperpour not_allowed)
			(footprints allowed)
		)
		(placement
			(enabled no)
			(sheetname "")
		)
		(fill
			(thermal_gap 0.5)
			(thermal_bridge_width 0.5)
			(island_removal_mode 0)
		)
		(polygon
			(pts
				(xy 70.294246 -1.404874) (xy 71.005446 -1.404874) (xy 71.005446 -5.595874) (xy 70.294246 -5.595874)
			)
		)
	)
	(zone
		(layer "In1.Cu")
		(hatch none 0.5)
		(connect_pads
			(clearance 0)
		)
		(min_thickness 0.25)
		(keepout
			(tracks not_allowed)
			(vias allowed)
			(pads allowed)
			(copperpour not_allowed)
			(footprints allowed)
		)
		(placement
			(enabled no)
			(sheetname "")
		)
		(fill
			(thermal_gap 0.5)
			(thermal_bridge_width 0.5)
			(island_removal_mode 0)
		)
		(polygon
			(pts
				(arc
					(start 103.09733 -42.82313)
					(mid 102.59695 -42.82313)
					(end 103.09733 -42.82313)
				)
			)
		)
	)
	(zone
		(layer "In1.Cu")
		(hatch none 0.5)
		(connect_pads
			(clearance 0)
		)
		(min_thickness 0.25)
		(keepout
			(tracks not_allowed)
			(vias allowed)
			(pads allowed)
			(copperpour not_allowed)
			(footprints allowed)
		)
		(placement
			(enabled no)
			(sheetname "")
		)
		(fill
			(thermal_gap 0.5)
			(thermal_bridge_width 0.5)
			(island_removal_mode 0)
		)
		(polygon
			(pts
				(xy 74.294238 -1.404874) (xy 75.005438 -1.404874) (xy 75.005438 -5.595874) (xy 74.294238 -5.595874)
			)
		)
	)
	(zone
		(layer "In1.Cu")
		(hatch none 0.5)
		(connect_pads
			(clearance 0)
		)
		(min_thickness 0.25)
		(keepout
			(tracks not_allowed)
			(vias allowed)
			(pads allowed)
			(copperpour not_allowed)
			(footprints allowed)
		)
		(placement
			(enabled no)
			(sheetname "")
		)
		(fill
			(thermal_gap 0.5)
			(thermal_bridge_width 0.5)
			(island_removal_mode 0)
		)
		(polygon
			(pts
				(xy 69.294248 -1.404874) (xy 70.005448 -1.404874) (xy 70.005448 -5.595874) (xy 69.294248 -5.595874)
			)
		)
	)
	(zone
		(layer "In1.Cu")
		(hatch none 0.5)
		(connect_pads
			(clearance 0)
		)
		(min_thickness 0.25)
		(keepout
			(tracks not_allowed)
			(vias allowed)
			(pads allowed)
			(copperpour not_allowed)
			(footprints allowed)
		)
		(placement
			(enabled no)
			(sheetname "")
		)
		(fill
			(thermal_gap 0.5)
			(thermal_bridge_width 0.5)
			(island_removal_mode 0)
		)
		(polygon
			(pts
				(xy 61.294264 -1.404874) (xy 62.005464 -1.404874) (xy 62.005464 -5.595874) (xy 61.294264 -5.595874)
			)
		)
	)
	(zone
		(layer "In1.Cu")
		(hatch none 0.5)
		(connect_pads
			(clearance 0)
		)
		(min_thickness 0.25)
		(keepout
			(tracks not_allowed)
			(vias allowed)
			(pads allowed)
			(copperpour not_allowed)
			(footprints allowed)
		)
		(placement
			(enabled no)
			(sheetname "")
		)
		(fill
			(thermal_gap 0.5)
			(thermal_bridge_width 0.5)
			(island_removal_mode 0)
		)
		(polygon
			(pts
				(xy 65.294256 -1.404874) (xy 66.005456 -1.404874) (xy 66.005456 -5.595874) (xy 65.294256 -5.595874)
			)
		)
	)
	(zone
		(layer "In1.Cu")
		(hatch none 0.5)
		(connect_pads
			(clearance 0)
		)
		(min_thickness 0.25)
		(keepout
			(tracks not_allowed)
			(vias allowed)
			(pads allowed)
			(copperpour not_allowed)
			(footprints allowed)
		)
		(placement
			(enabled no)
			(sheetname "")
		)
		(fill
			(thermal_gap 0.5)
			(thermal_bridge_width 0.5)
			(island_removal_mode 0)
		)
		(polygon
			(pts
				(xy 73.29424 -1.404874) (xy 74.00544 -1.404874) (xy 74.00544 -5.595874) (xy 73.29424 -5.595874)
			)
		)
	)
	(zone
		(layer "In1.Cu")
		(hatch none 0.5)
		(connect_pads
			(clearance 0)
		)
		(min_thickness 0.25)
		(keepout
			(tracks not_allowed)
			(vias allowed)
			(pads allowed)
			(copperpour not_allowed)
			(footprints allowed)
		)
		(placement
			(enabled no)
			(sheetname "")
		)
		(fill
			(thermal_gap 0.5)
			(thermal_bridge_width 0.5)
			(island_removal_mode 0)
		)
		(polygon
			(pts
				(xy 89.52103 -48.351948) (xy 89.52103 -48.555148) (xy 88.58123 -48.555148) (xy 88.58123 -48.351948)
			)
		)
	)
	(zone
		(layer "In1.Cu")
		(hatch none 0.5)
		(connect_pads
			(clearance 0)
		)
		(min_thickness 0.25)
		(keepout
			(tracks not_allowed)
			(vias allowed)
			(pads allowed)
			(copperpour not_allowed)
			(footprints allowed)
		)
		(placement
			(enabled no)
			(sheetname "")
		)
		(fill
			(thermal_gap 0.5)
			(thermal_bridge_width 0.5)
			(island_removal_mode 0)
		)
		(polygon
			(pts
				(xy 28.621736 -90.0684) (xy 28.621736 -91.694) (xy 28.926536 -91.694) (xy 28.926536 -90.0684)
			)
		)
	)
	(zone
		(layer "In1.Cu")
		(hatch none 0.5)
		(connect_pads
			(clearance 0)
		)
		(min_thickness 0.25)
		(keepout
			(tracks not_allowed)
			(vias allowed)
			(pads allowed)
			(copperpour not_allowed)
			(footprints allowed)
		)
		(placement
			(enabled no)
			(sheetname "")
		)
		(fill
			(thermal_gap 0.5)
			(thermal_bridge_width 0.5)
			(island_removal_mode 0)
		)
		(polygon
			(pts
				(xy 66.294254 -1.404874) (xy 67.005454 -1.404874) (xy 67.005454 -5.595874) (xy 66.294254 -5.595874)
			)
		)
	)
	(zone
		(layer "In1.Cu")
		(hatch none 0.5)
		(connect_pads
			(clearance 0)
		)
		(min_thickness 0.25)
		(keepout
			(tracks not_allowed)
			(vias allowed)
			(pads allowed)
			(copperpour not_allowed)
			(footprints allowed)
		)
		(placement
			(enabled no)
			(sheetname "")
		)
		(fill
			(thermal_gap 0.5)
			(thermal_bridge_width 0.5)
			(island_removal_mode 0)
		)
		(polygon
			(pts
				(xy 91.454478 -48.751744) (xy 91.454478 -48.954944) (xy 90.514678 -48.954944) (xy 90.514678 -48.751744)
			)
		)
	)
	(zone
		(layer "In1.Cu")
		(hatch none 0.5)
		(connect_pads
			(clearance 0)
		)
		(min_thickness 0.25)
		(keepout
			(tracks not_allowed)
			(vias allowed)
			(pads allowed)
			(copperpour not_allowed)
			(footprints allowed)
		)
		(placement
			(enabled no)
			(sheetname "")
		)
		(fill
			(thermal_gap 0.5)
			(thermal_bridge_width 0.5)
			(island_removal_mode 0)
		)
		(polygon
			(pts
				(xy 91.454478 -48.351948) (xy 91.454478 -48.555148) (xy 90.514678 -48.555148) (xy 90.514678 -48.351948)
			)
		)
	)
	(zone
		(layer "In1.Cu")
		(hatch none 0.5)
		(connect_pads
			(clearance 0)
		)
		(min_thickness 0.25)
		(keepout
			(tracks not_allowed)
			(vias allowed)
			(pads allowed)
			(copperpour not_allowed)
			(footprints allowed)
		)
		(placement
			(enabled no)
			(sheetname "")
		)
		(fill
			(thermal_gap 0.5)
			(thermal_bridge_width 0.5)
			(island_removal_mode 0)
		)
		(polygon
			(pts
				(xy 91.454478 -47.951898) (xy 91.454478 -48.155098) (xy 90.514678 -48.155098) (xy 90.514678 -47.951898)
			)
		)
	)
	(zone
		(layer "In1.Cu")
		(hatch none 0.5)
		(connect_pads
			(clearance 0)
		)
		(min_thickness 0.25)
		(keepout
			(tracks not_allowed)
			(vias allowed)
			(pads allowed)
			(copperpour not_allowed)
			(footprints allowed)
		)
		(placement
			(enabled no)
			(sheetname "")
		)
		(fill
			(thermal_gap 0.5)
			(thermal_bridge_width 0.5)
			(island_removal_mode 0)
		)
		(polygon
			(pts
				(xy 91.454478 -49.151794) (xy 91.454478 -49.354994) (xy 90.514678 -49.354994) (xy 90.514678 -49.151794)
			)
		)
	)
	(zone
		(layer "In1.Cu")
		(hatch none 0.5)
		(connect_pads
			(clearance 0)
		)
		(min_thickness 0.25)
		(keepout
			(tracks not_allowed)
			(vias allowed)
			(pads allowed)
			(copperpour not_allowed)
			(footprints allowed)
		)
		(placement
			(enabled no)
			(sheetname "")
		)
		(fill
			(thermal_gap 0.5)
			(thermal_bridge_width 0.5)
			(island_removal_mode 0)
		)
		(polygon
			(pts
				(xy 29.121862 -90.0684) (xy 29.121862 -91.694) (xy 29.426662 -91.694) (xy 29.426662 -90.0684)
			)
		)
	)
	(zone
		(layer "In1.Cu")
		(hatch none 0.5)
		(connect_pads
			(clearance 0)
		)
		(min_thickness 0.25)
		(keepout
			(tracks not_allowed)
			(vias allowed)
			(pads allowed)
			(copperpour not_allowed)
			(footprints allowed)
		)
		(placement
			(enabled no)
			(sheetname "")
		)
		(fill
			(thermal_gap 0.5)
			(thermal_bridge_width 0.5)
			(island_removal_mode 0)
		)
		(polygon
			(pts
				(arc
					(start 104.097328 -42.82313)
					(mid 103.596948 -42.82313)
					(end 104.097328 -42.82313)
				)
			)
		)
	)
	(zone
		(layer "In1.Cu")
		(hatch none 0.5)
		(connect_pads
			(clearance 0)
		)
		(min_thickness 0.25)
		(keepout
			(tracks not_allowed)
			(vias allowed)
			(pads allowed)
			(copperpour not_allowed)
			(footprints allowed)
		)
		(placement
			(enabled no)
			(sheetname "")
		)
		(fill
			(thermal_gap 0.5)
			(thermal_bridge_width 0.5)
			(island_removal_mode 0)
		)
		(polygon
			(pts
				(xy 89.52103 -48.751744) (xy 89.52103 -48.954944) (xy 88.58123 -48.954944) (xy 88.58123 -48.751744)
			)
		)
	)
	(zone
		(layers "In1.Cu" "In2.Cu")
		(hatch none 0.5)
		(connect_pads
			(clearance 0)
		)
		(min_thickness 0.25)
		(keepout
			(tracks not_allowed)
			(vias allowed)
			(pads allowed)
			(copperpour not_allowed)
			(footprints allowed)
		)
		(placement
			(enabled no)
			(sheetname "")
		)
		(fill yes
			(thermal_gap 0.5)
			(thermal_bridge_width 0.5)
			(island_removal_mode 0)
		)
		(polygon
			(pts
				(arc
					(start 120.097296 -37.82314)
					(mid 119.596916 -37.82314)
					(end 120.097296 -37.82314)
				)
			)
		)
	)
	(zone
		(layers "In1.Cu" "In2.Cu")
		(hatch none 0.5)
		(connect_pads
			(clearance 0)
		)
		(min_thickness 0.25)
		(keepout
			(tracks not_allowed)
			(vias allowed)
			(pads allowed)
			(copperpour not_allowed)
			(footprints allowed)
		)
		(placement
			(enabled no)
			(sheetname "")
		)
		(fill yes
			(thermal_gap 0.5)
			(thermal_bridge_width 0.5)
			(island_removal_mode 0)
		)
		(polygon
			(pts
				(arc
					(start 100.097082 -42.82313)
					(mid 99.596702 -42.82313)
					(end 100.097082 -42.82313)
				)
			)
		)
	)
	(zone
		(layers "In1.Cu" "In2.Cu")
		(hatch none 0.5)
		(connect_pads
			(clearance 0)
		)
		(min_thickness 0.25)
		(keepout
			(tracks not_allowed)
			(vias allowed)
			(pads allowed)
			(copperpour not_allowed)
			(footprints allowed)
		)
		(placement
			(enabled no)
			(sheetname "")
		)
		(fill yes
			(thermal_gap 0.5)
			(thermal_bridge_width 0.5)
			(island_removal_mode 0)
		)
		(polygon
			(pts
				(xy 78.9686 -44.1452) (xy 79.6798 -44.1452) (xy 79.6798 -44.7548) (xy 78.9686 -44.7548)
			)
		)
	)
	(zone
		(layers "In1.Cu" "In2.Cu")
		(hatch none 0.5)
		(connect_pads
			(clearance 0)
		)
		(min_thickness 0.25)
		(keepout
			(tracks not_allowed)
			(vias allowed)
			(pads allowed)
			(copperpour not_allowed)
			(footprints allowed)
		)
		(placement
			(enabled no)
			(sheetname "")
		)
		(fill yes
			(thermal_gap 0.5)
			(thermal_bridge_width 0.5)
			(island_removal_mode 0)
		)
		(polygon
			(pts
				(xy 78.9686 -45.4152) (xy 79.6798 -45.4152) (xy 79.6798 -46.0248) (xy 78.9686 -46.0248)
			)
		)
	)
	(zone
		(layers "In1.Cu" "In2.Cu")
		(hatch none 0.5)
		(connect_pads
			(clearance 0)
		)
		(min_thickness 0.25)
		(keepout
			(tracks not_allowed)
			(vias allowed)
			(pads allowed)
			(copperpour not_allowed)
			(footprints allowed)
		)
		(placement
			(enabled no)
			(sheetname "")
		)
		(fill yes
			(thermal_gap 0.5)
			(thermal_bridge_width 0.5)
			(island_removal_mode 0)
		)
		(polygon
			(pts
				(xy 28.3718 -94.4118) (xy 28.3718 -95.123) (xy 27.7622 -95.123) (xy 27.7622 -94.4118)
			)
		)
	)
	(zone
		(layers "In1.Cu" "In2.Cu")
		(hatch none 0.5)
		(connect_pads
			(clearance 0)
		)
		(min_thickness 0.25)
		(keepout
			(tracks not_allowed)
			(vias allowed)
			(pads allowed)
			(copperpour not_allowed)
			(footprints allowed)
		)
		(placement
			(enabled no)
			(sheetname "")
		)
		(fill yes
			(thermal_gap 0.5)
			(thermal_bridge_width 0.5)
			(island_removal_mode 0)
		)
		(polygon
			(pts
				(arc
					(start 101.09708 -43.823128)
					(mid 100.5967 -43.823128)
					(end 101.09708 -43.823128)
				)
			)
		)
	)
	(zone
		(layers "In1.Cu" "In2.Cu")
		(hatch none 0.5)
		(connect_pads
			(clearance 0)
		)
		(min_thickness 0.25)
		(keepout
			(tracks not_allowed)
			(vias allowed)
			(pads allowed)
			(copperpour not_allowed)
			(footprints allowed)
		)
		(placement
			(enabled no)
			(sheetname "")
		)
		(fill yes
			(thermal_gap 0.5)
			(thermal_bridge_width 0.5)
			(island_removal_mode 0)
		)
		(polygon
			(pts
				(arc
					(start 101.09708 -39.823136)
					(mid 100.5967 -39.823136)
					(end 101.09708 -39.823136)
				)
			)
		)
	)
	(zone
		(layers "In1.Cu" "In2.Cu")
		(hatch none 0.5)
		(connect_pads
			(clearance 0)
		)
		(min_thickness 0.25)
		(keepout
			(tracks not_allowed)
			(vias allowed)
			(pads allowed)
			(copperpour not_allowed)
			(footprints allowed)
		)
		(placement
			(enabled no)
			(sheetname "")
		)
		(fill yes
			(thermal_gap 0.5)
			(thermal_bridge_width 0.5)
			(island_removal_mode 0)
		)
		(polygon
			(pts
				(arc
					(start 113.09731 -36.823142)
					(mid 112.59693 -36.823142)
					(end 113.09731 -36.823142)
				)
			)
		)
	)
	(zone
		(layers "In1.Cu" "In2.Cu")
		(hatch none 0.5)
		(connect_pads
			(clearance 0)
		)
		(min_thickness 0.25)
		(keepout
			(tracks not_allowed)
			(vias allowed)
			(pads allowed)
			(copperpour not_allowed)
			(footprints allowed)
		)
		(placement
			(enabled no)
			(sheetname "")
		)
		(fill yes
			(thermal_gap 0.5)
			(thermal_bridge_width 0.5)
			(island_removal_mode 0)
		)
		(polygon
			(pts
				(xy 78.867 -46.6852) (xy 79.5782 -46.6852) (xy 79.5782 -47.2948) (xy 78.867 -47.2948)
			)
		)
	)
	(zone
		(layers "In1.Cu" "In2.Cu")
		(hatch none 0.5)
		(connect_pads
			(clearance 0)
		)
		(min_thickness 0.25)
		(keepout
			(tracks not_allowed)
			(vias allowed)
			(pads allowed)
			(copperpour not_allowed)
			(footprints allowed)
		)
		(placement
			(enabled no)
			(sheetname "")
		)
		(fill yes
			(thermal_gap 0.5)
			(thermal_bridge_width 0.5)
			(island_removal_mode 0)
		)
		(polygon
			(pts
				(xy 69.452744 -44.869608) (xy 71.256144 -44.869608) (xy 71.256144 -45.123608) (xy 69.452744 -45.123608)
			)
		)
	)
	(zone
		(layers "In1.Cu" "In2.Cu")
		(hatch none 0.5)
		(connect_pads
			(clearance 0)
		)
		(min_thickness 0.25)
		(keepout
			(tracks not_allowed)
			(vias allowed)
			(pads allowed)
			(copperpour not_allowed)
			(footprints allowed)
		)
		(placement
			(enabled no)
			(sheetname "")
		)
		(fill yes
			(thermal_gap 0.5)
			(thermal_bridge_width 0.5)
			(island_removal_mode 0)
		)
		(polygon
			(pts
				(xy 17.08404 -88.4682) (xy 17.59204 -88.4682) (xy 17.59204 -89.662) (xy 17.08404 -89.662)
			)
		)
	)
	(zone
		(layers "In1.Cu" "In2.Cu")
		(hatch none 0.5)
		(connect_pads
			(clearance 0)
		)
		(min_thickness 0.25)
		(keepout
			(tracks not_allowed)
			(vias allowed)
			(pads allowed)
			(copperpour not_allowed)
			(footprints allowed)
		)
		(placement
			(enabled no)
			(sheetname "")
		)
		(fill yes
			(thermal_gap 0.5)
			(thermal_bridge_width 0.5)
			(island_removal_mode 0)
		)
		(polygon
			(pts
				(arc
					(start 102.097332 -37.82314)
					(mid 101.596952 -37.82314)
					(end 102.097332 -37.82314)
				)
			)
		)
	)
	(zone
		(layers "In1.Cu" "In2.Cu")
		(hatch none 0.5)
		(connect_pads
			(clearance 0)
		)
		(min_thickness 0.25)
		(keepout
			(tracks not_allowed)
			(vias allowed)
			(pads allowed)
			(copperpour not_allowed)
			(footprints allowed)
		)
		(placement
			(enabled no)
			(sheetname "")
		)
		(fill yes
			(thermal_gap 0.5)
			(thermal_bridge_width 0.5)
			(island_removal_mode 0)
		)
		(polygon
			(pts
				(xy 73.452736 -48.369728) (xy 75.256136 -48.369728) (xy 75.256136 -48.623728) (xy 73.452736 -48.623728)
			)
		)
	)
	(zone
		(layers "In1.Cu" "In2.Cu")
		(hatch none 0.5)
		(connect_pads
			(clearance 0)
		)
		(min_thickness 0.25)
		(keepout
			(tracks not_allowed)
			(vias allowed)
			(pads allowed)
			(copperpour not_allowed)
			(footprints allowed)
		)
		(placement
			(enabled no)
			(sheetname "")
		)
		(fill yes
			(thermal_gap 0.5)
			(thermal_bridge_width 0.5)
			(island_removal_mode 0)
		)
		(polygon
			(pts
				(arc
					(start 103.09733 -38.823138)
					(mid 102.59695 -38.823138)
					(end 103.09733 -38.823138)
				)
			)
		)
	)
	(zone
		(layers "In1.Cu" "In2.Cu")
		(hatch none 0.5)
		(connect_pads
			(clearance 0)
		)
		(min_thickness 0.25)
		(keepout
			(tracks not_allowed)
			(vias allowed)
			(pads allowed)
			(copperpour not_allowed)
			(footprints allowed)
		)
		(placement
			(enabled no)
			(sheetname "")
		)
		(fill yes
			(thermal_gap 0.5)
			(thermal_bridge_width 0.5)
			(island_removal_mode 0)
		)
		(polygon
			(pts
				(xy 82.4738 -52.07) (xy 83.0834 -52.07) (xy 83.0834 -52.7812) (xy 82.4738 -52.7812)
			)
		)
	)
	(zone
		(layers "In1.Cu" "In2.Cu")
		(hatch none 0.5)
		(connect_pads
			(clearance 0)
		)
		(min_thickness 0.25)
		(keepout
			(tracks not_allowed)
			(vias allowed)
			(pads allowed)
			(copperpour not_allowed)
			(footprints allowed)
		)
		(placement
			(enabled no)
			(sheetname "")
		)
		(fill yes
			(thermal_gap 0.5)
			(thermal_bridge_width 0.5)
			(island_removal_mode 0)
		)
		(polygon
			(pts
				(arc
					(start 102.097332 -41.823132)
					(mid 101.596952 -41.823132)
					(end 102.097332 -41.823132)
				)
			)
		)
	)
	(zone
		(layers "In1.Cu" "In2.Cu")
		(hatch none 0.5)
		(connect_pads
			(clearance 0)
		)
		(min_thickness 0.25)
		(keepout
			(tracks not_allowed)
			(vias allowed)
			(pads allowed)
			(copperpour not_allowed)
			(footprints allowed)
		)
		(placement
			(enabled no)
			(sheetname "")
		)
		(fill yes
			(thermal_gap 0.5)
			(thermal_bridge_width 0.5)
			(island_removal_mode 0)
		)
		(polygon
			(pts
				(xy 81.1784 -53.2892) (xy 81.8896 -53.2892) (xy 81.8896 -53.8988) (xy 81.1784 -53.8988)
			)
		)
	)
	(zone
		(layers "In1.Cu" "In2.Cu")
		(hatch none 0.5)
		(connect_pads
			(clearance 0)
		)
		(min_thickness 0.25)
		(keepout
			(tracks not_allowed)
			(vias allowed)
			(pads allowed)
			(copperpour not_allowed)
			(footprints allowed)
		)
		(placement
			(enabled no)
			(sheetname "")
		)
		(fill yes
			(thermal_gap 0.5)
			(thermal_bridge_width 0.5)
			(island_removal_mode 0)
		)
		(polygon
			(pts
				(xy 81.1784 -49.6062) (xy 81.8896 -49.6062) (xy 81.8896 -50.2158) (xy 81.1784 -50.2158)
			)
		)
	)
	(zone
		(layers "In1.Cu" "In2.Cu")
		(hatch none 0.5)
		(connect_pads
			(clearance 0)
		)
		(min_thickness 0.25)
		(keepout
			(tracks not_allowed)
			(vias allowed)
			(pads allowed)
			(copperpour not_allowed)
			(footprints allowed)
		)
		(placement
			(enabled no)
			(sheetname "")
		)
		(fill yes
			(thermal_gap 0.5)
			(thermal_bridge_width 0.5)
			(island_removal_mode 0)
		)
		(polygon
			(pts
				(arc
					(start 101.09708 -37.82314)
					(mid 100.5967 -37.82314)
					(end 101.09708 -37.82314)
				)
			)
		)
	)
	(zone
		(layers "In1.Cu" "In2.Cu")
		(hatch none 0.5)
		(connect_pads
			(clearance 0)
		)
		(min_thickness 0.25)
		(keepout
			(tracks not_allowed)
			(vias allowed)
			(pads allowed)
			(copperpour not_allowed)
			(footprints allowed)
		)
		(placement
			(enabled no)
			(sheetname "")
		)
		(fill yes
			(thermal_gap 0.5)
			(thermal_bridge_width 0.5)
			(island_removal_mode 0)
		)
		(polygon
			(pts
				(arc
					(start 102.097332 -39.823136)
					(mid 101.596952 -39.823136)
					(end 102.097332 -39.823136)
				)
			)
		)
	)
	(zone
		(layers "In1.Cu" "In2.Cu")
		(hatch none 0.5)
		(connect_pads
			(clearance 0)
		)
		(min_thickness 0.25)
		(keepout
			(tracks not_allowed)
			(vias allowed)
			(pads allowed)
			(copperpour not_allowed)
			(footprints allowed)
		)
		(placement
			(enabled no)
			(sheetname "")
		)
		(fill yes
			(thermal_gap 0.5)
			(thermal_bridge_width 0.5)
			(island_removal_mode 0)
		)
		(polygon
			(pts
				(arc
					(start 101.09708 -41.823132)
					(mid 100.5967 -41.823132)
					(end 101.09708 -41.823132)
				)
			)
		)
	)
	(zone
		(layers "In1.Cu" "In2.Cu")
		(hatch none 0.5)
		(connect_pads
			(clearance 0)
		)
		(min_thickness 0.25)
		(keepout
			(tracks not_allowed)
			(vias allowed)
			(pads allowed)
			(copperpour not_allowed)
			(footprints allowed)
		)
		(placement
			(enabled no)
			(sheetname "")
		)
		(fill yes
			(thermal_gap 0.5)
			(thermal_bridge_width 0.5)
			(island_removal_mode 0)
		)
		(polygon
			(pts
				(arc
					(start 104.097328 -38.823138)
					(mid 103.596948 -38.823138)
					(end 104.097328 -38.823138)
				)
			)
		)
	)
	(zone
		(layers "In1.Cu" "In2.Cu")
		(hatch none 0.5)
		(connect_pads
			(clearance 0)
		)
		(min_thickness 0.25)
		(keepout
			(tracks not_allowed)
			(vias allowed)
			(pads allowed)
			(copperpour not_allowed)
			(footprints allowed)
		)
		(placement
			(enabled no)
			(sheetname "")
		)
		(fill yes
			(thermal_gap 0.5)
			(thermal_bridge_width 0.5)
			(island_removal_mode 0)
		)
		(polygon
			(pts
				(xy 158.051246 -55.329836) (xy 158.559246 -55.329836) (xy 158.559246 -56.523636) (xy 158.051246 -56.523636)
			)
		)
	)
	(zone
		(layers "In1.Cu" "In2.Cu")
		(hatch none 0.5)
		(connect_pads
			(clearance 0)
		)
		(min_thickness 0.25)
		(keepout
			(tracks not_allowed)
			(vias allowed)
			(pads allowed)
			(copperpour not_allowed)
			(footprints allowed)
		)
		(placement
			(enabled no)
			(sheetname "")
		)
		(fill yes
			(thermal_gap 0.5)
			(thermal_bridge_width 0.5)
			(island_removal_mode 0)
		)
		(polygon
			(pts
				(xy 69.452744 -47.36973) (xy 71.256144 -47.36973) (xy 71.256144 -47.62373) (xy 69.452744 -47.62373)
			)
		)
	)
	(zone
		(layers "In1.Cu" "In2.Cu")
		(hatch none 0.5)
		(connect_pads
			(clearance 0)
		)
		(min_thickness 0.25)
		(keepout
			(tracks not_allowed)
			(vias allowed)
			(pads allowed)
			(copperpour not_allowed)
			(footprints allowed)
		)
		(placement
			(enabled no)
			(sheetname "")
		)
		(fill yes
			(thermal_gap 0.5)
			(thermal_bridge_width 0.5)
			(island_removal_mode 0)
		)
		(polygon
			(pts
				(arc
					(start 99.097084 -40.823134)
					(mid 98.596704 -40.823134)
					(end 99.097084 -40.823134)
				)
			)
		)
	)
	(zone
		(layers "In1.Cu" "In2.Cu")
		(hatch none 0.5)
		(connect_pads
			(clearance 0)
		)
		(min_thickness 0.25)
		(keepout
			(tracks not_allowed)
			(vias allowed)
			(pads allowed)
			(copperpour not_allowed)
			(footprints allowed)
		)
		(placement
			(enabled no)
			(sheetname "")
		)
		(fill yes
			(thermal_gap 0.5)
			(thermal_bridge_width 0.5)
			(island_removal_mode 0)
		)
		(polygon
			(pts
				(arc
					(start 102.097332 -43.823128)
					(mid 101.596952 -43.823128)
					(end 102.097332 -43.823128)
				)
			)
		)
	)
	(zone
		(layers "In1.Cu" "In2.Cu")
		(hatch none 0.5)
		(connect_pads
			(clearance 0)
		)
		(min_thickness 0.25)
		(keepout
			(tracks not_allowed)
			(vias allowed)
			(pads allowed)
			(copperpour not_allowed)
			(footprints allowed)
		)
		(placement
			(enabled no)
			(sheetname "")
		)
		(fill yes
			(thermal_gap 0.5)
			(thermal_bridge_width 0.5)
			(island_removal_mode 0)
		)
		(polygon
			(pts
				(arc
					(start 99.097084 -42.82313)
					(mid 98.596704 -42.82313)
					(end 99.097084 -42.82313)
				)
			)
		)
	)
	(zone
		(layers "In1.Cu" "In2.Cu")
		(hatch none 0.5)
		(connect_pads
			(clearance 0)
		)
		(min_thickness 0.25)
		(keepout
			(tracks not_allowed)
			(vias allowed)
			(pads allowed)
			(copperpour not_allowed)
			(footprints allowed)
		)
		(placement
			(enabled no)
			(sheetname "")
		)
		(fill yes
			(thermal_gap 0.5)
			(thermal_bridge_width 0.5)
			(island_removal_mode 0)
		)
		(polygon
			(pts
				(xy 82.4738 -50.7238) (xy 83.0834 -50.7238) (xy 83.0834 -51.435) (xy 82.4738 -51.435)
			)
		)
	)
	(zone
		(layers "In1.Cu" "In2.Cu")
		(hatch none 0.5)
		(connect_pads
			(clearance 0)
		)
		(min_thickness 0.25)
		(keepout
			(tracks not_allowed)
			(vias allowed)
			(pads allowed)
			(copperpour not_allowed)
			(footprints allowed)
		)
		(placement
			(enabled no)
			(sheetname "")
		)
		(fill yes
			(thermal_gap 0.5)
			(thermal_bridge_width 0.5)
			(island_removal_mode 0)
		)
		(polygon
			(pts
				(arc
					(start 113.09731 -46.823122)
					(mid 112.59693 -46.823122)
					(end 113.09731 -46.823122)
				)
			)
		)
	)
	(zone
		(layers "In1.Cu" "In2.Cu")
		(hatch none 0.5)
		(connect_pads
			(clearance 0)
		)
		(min_thickness 0.25)
		(keepout
			(tracks not_allowed)
			(vias allowed)
			(pads allowed)
			(copperpour not_allowed)
			(footprints allowed)
		)
		(placement
			(enabled no)
			(sheetname "")
		)
		(fill yes
			(thermal_gap 0.5)
			(thermal_bridge_width 0.5)
			(island_removal_mode 0)
		)
		(polygon
			(pts
				(arc
					(start 120.097296 -34.822892)
					(mid 119.596916 -34.822892)
					(end 120.097296 -34.822892)
				)
			)
		)
	)
	(zone
		(layers "In1.Cu" "In2.Cu")
		(hatch none 0.5)
		(connect_pads
			(clearance 0)
		)
		(min_thickness 0.25)
		(keepout
			(tracks not_allowed)
			(vias allowed)
			(pads allowed)
			(copperpour not_allowed)
			(footprints allowed)
		)
		(placement
			(enabled no)
			(sheetname "")
		)
		(fill yes
			(thermal_gap 0.5)
			(thermal_bridge_width 0.5)
			(island_removal_mode 0)
		)
		(polygon
			(pts
				(xy 80.1116 -53.2892) (xy 80.8228 -53.2892) (xy 80.8228 -53.8988) (xy 80.1116 -53.8988)
			)
		)
	)
	(zone
		(layers "In1.Cu" "In2.Cu")
		(hatch none 0.5)
		(connect_pads
			(clearance 0)
		)
		(min_thickness 0.25)
		(keepout
			(tracks not_allowed)
			(vias allowed)
			(pads allowed)
			(copperpour not_allowed)
			(footprints allowed)
		)
		(placement
			(enabled no)
			(sheetname "")
		)
		(fill yes
			(thermal_gap 0.5)
			(thermal_bridge_width 0.5)
			(island_removal_mode 0)
		)
		(polygon
			(pts
				(arc
					(start 99.097084 -38.823138)
					(mid 98.596704 -38.823138)
					(end 99.097084 -38.823138)
				)
			)
		)
	)
	(zone
		(layers "In1.Cu" "In2.Cu")
		(hatch none 0.5)
		(connect_pads
			(clearance 0)
		)
		(min_thickness 0.25)
		(keepout
			(tracks not_allowed)
			(vias allowed)
			(pads allowed)
			(copperpour not_allowed)
			(footprints allowed)
		)
		(placement
			(enabled no)
			(sheetname "")
		)
		(fill yes
			(thermal_gap 0.5)
			(thermal_bridge_width 0.5)
			(island_removal_mode 0)
		)
		(polygon
			(pts
				(xy 69.452744 -47.869602) (xy 71.256144 -47.869602) (xy 71.256144 -48.123602) (xy 69.452744 -48.123602)
			)
		)
	)
	(zone
		(layers "In1.Cu" "In2.Cu")
		(hatch none 0.5)
		(connect_pads
			(clearance 0)
		)
		(min_thickness 0.25)
		(keepout
			(tracks not_allowed)
			(vias allowed)
			(pads allowed)
			(copperpour not_allowed)
			(footprints allowed)
		)
		(placement
			(enabled no)
			(sheetname "")
		)
		(fill yes
			(thermal_gap 0.5)
			(thermal_bridge_width 0.5)
			(island_removal_mode 0)
		)
		(polygon
			(pts
				(xy 79.9338 -47.8282) (xy 80.645 -47.8282) (xy 80.645 -48.4378) (xy 79.9338 -48.4378)
			)
		)
	)
	(zone
		(layers "In1.Cu" "In2.Cu")
		(hatch none 0.5)
		(connect_pads
			(clearance 0)
		)
		(min_thickness 0.25)
		(keepout
			(tracks not_allowed)
			(vias allowed)
			(pads allowed)
			(copperpour not_allowed)
			(footprints allowed)
		)
		(placement
			(enabled no)
			(sheetname "")
		)
		(fill yes
			(thermal_gap 0.5)
			(thermal_bridge_width 0.5)
			(island_removal_mode 0)
		)
		(polygon
			(pts
				(xy 80.1116 -49.6062) (xy 80.8228 -49.6062) (xy 80.8228 -50.2158) (xy 80.1116 -50.2158)
			)
		)
	)
	(zone
		(layers "In1.Cu" "In2.Cu")
		(hatch none 0.5)
		(connect_pads
			(clearance 0)
		)
		(min_thickness 0.25)
		(keepout
			(tracks not_allowed)
			(vias allowed)
			(pads allowed)
			(copperpour not_allowed)
			(footprints allowed)
		)
		(placement
			(enabled no)
			(sheetname "")
		)
		(fill yes
			(thermal_gap 0.5)
			(thermal_bridge_width 0.5)
			(island_removal_mode 0)
		)
		(polygon
			(pts
				(arc
					(start 118.0973 -33.822894)
					(mid 117.59692 -33.822894)
					(end 118.0973 -33.822894)
				)
			)
		)
	)
	(zone
		(layers "In1.Cu" "In2.Cu")
		(hatch none 0.5)
		(connect_pads
			(clearance 0)
		)
		(min_thickness 0.25)
		(keepout
			(tracks not_allowed)
			(vias allowed)
			(pads allowed)
			(copperpour not_allowed)
			(footprints allowed)
		)
		(placement
			(enabled no)
			(sheetname "")
		)
		(fill yes
			(thermal_gap 0.5)
			(thermal_bridge_width 0.5)
			(island_removal_mode 0)
		)
		(polygon
			(pts
				(arc
					(start 100.097082 -36.823142)
					(mid 99.596702 -36.823142)
					(end 100.097082 -36.823142)
				)
			)
		)
	)
	(zone
		(layers "In1.Cu" "In2.Cu")
		(hatch none 0.5)
		(connect_pads
			(clearance 0)
		)
		(min_thickness 0.25)
		(keepout
			(tracks not_allowed)
			(vias allowed)
			(pads allowed)
			(copperpour not_allowed)
			(footprints allowed)
		)
		(placement
			(enabled no)
			(sheetname "")
		)
		(fill yes
			(thermal_gap 0.5)
			(thermal_bridge_width 0.5)
			(island_removal_mode 0)
		)
		(polygon
			(pts
				(xy 162.1536 -53.396896) (xy 163.4998 -53.396896) (xy 163.4998 -53.803296) (xy 162.1536 -53.803296)
			)
		)
	)
	(zone
		(layers "In1.Cu" "In2.Cu")
		(hatch none 0.5)
		(connect_pads
			(clearance 0)
		)
		(min_thickness 0.25)
		(keepout
			(tracks not_allowed)
			(vias allowed)
			(pads allowed)
			(copperpour not_allowed)
			(footprints allowed)
		)
		(placement
			(enabled no)
			(sheetname "")
		)
		(fill yes
			(thermal_gap 0.5)
			(thermal_bridge_width 0.5)
			(island_removal_mode 0)
		)
		(polygon
			(pts
				(xy 81.1784 -50.8762) (xy 81.8896 -50.8762) (xy 81.8896 -51.4858) (xy 81.1784 -51.4858)
			)
		)
	)
	(zone
		(layers "In1.Cu" "In2.Cu")
		(hatch none 0.5)
		(connect_pads
			(clearance 0)
		)
		(min_thickness 0.25)
		(keepout
			(tracks not_allowed)
			(vias allowed)
			(pads allowed)
			(copperpour not_allowed)
			(footprints allowed)
		)
		(placement
			(enabled no)
			(sheetname "")
		)
		(fill yes
			(thermal_gap 0.5)
			(thermal_bridge_width 0.5)
			(island_removal_mode 0)
		)
		(polygon
			(pts
				(xy 80.1116 -50.8762) (xy 80.8228 -50.8762) (xy 80.8228 -51.4858) (xy 80.1116 -51.4858)
			)
		)
	)
	(zone
		(layers "In1.Cu" "In2.Cu")
		(hatch none 0.5)
		(connect_pads
			(clearance 0)
		)
		(min_thickness 0.25)
		(keepout
			(tracks not_allowed)
			(vias allowed)
			(pads allowed)
			(copperpour not_allowed)
			(footprints allowed)
		)
		(placement
			(enabled no)
			(sheetname "")
		)
		(fill yes
			(thermal_gap 0.5)
			(thermal_bridge_width 0.5)
			(island_removal_mode 0)
		)
		(polygon
			(pts
				(xy 82.4738 -49.657) (xy 83.0834 -49.657) (xy 83.0834 -50.3682) (xy 82.4738 -50.3682)
			)
		)
	)
	(zone
		(layers "In1.Cu" "In2.Cu")
		(hatch none 0.5)
		(connect_pads
			(clearance 0)
		)
		(min_thickness 0.25)
		(keepout
			(tracks not_allowed)
			(vias allowed)
			(pads allowed)
			(copperpour not_allowed)
			(footprints allowed)
		)
		(placement
			(enabled no)
			(sheetname "")
		)
		(fill yes
			(thermal_gap 0.5)
			(thermal_bridge_width 0.5)
			(island_removal_mode 0)
		)
		(polygon
			(pts
				(xy 81.1784 -52.0192) (xy 81.8896 -52.0192) (xy 81.8896 -52.6288) (xy 81.1784 -52.6288)
			)
		)
	)
	(zone
		(layers "In1.Cu" "In2.Cu")
		(hatch none 0.5)
		(connect_pads
			(clearance 0)
		)
		(min_thickness 0.25)
		(keepout
			(tracks not_allowed)
			(vias allowed)
			(pads allowed)
			(copperpour not_allowed)
			(footprints allowed)
		)
		(placement
			(enabled no)
			(sheetname "")
		)
		(fill yes
			(thermal_gap 0.5)
			(thermal_bridge_width 0.5)
			(island_removal_mode 0)
		)
		(polygon
			(pts
				(xy 69.452744 -48.369728) (xy 71.256144 -48.369728) (xy 71.256144 -48.623728) (xy 69.452744 -48.623728)
			)
		)
	)
	(zone
		(layers "In1.Cu" "In2.Cu")
		(hatch none 0.5)
		(connect_pads
			(clearance 0)
		)
		(min_thickness 0.25)
		(keepout
			(tracks not_allowed)
			(vias allowed)
			(pads allowed)
			(copperpour not_allowed)
			(footprints allowed)
		)
		(placement
			(enabled no)
			(sheetname "")
		)
		(fill yes
			(thermal_gap 0.5)
			(thermal_bridge_width 0.5)
			(island_removal_mode 0)
		)
		(polygon
			(pts
				(arc
					(start 112.097312 -46.823122)
					(mid 111.596932 -46.823122)
					(end 112.097312 -46.823122)
				)
			)
		)
	)
	(zone
		(layers "In1.Cu" "In2.Cu")
		(hatch none 0.5)
		(connect_pads
			(clearance 0)
		)
		(min_thickness 0.25)
		(keepout
			(tracks not_allowed)
			(vias allowed)
			(pads allowed)
			(copperpour not_allowed)
			(footprints allowed)
		)
		(placement
			(enabled no)
			(sheetname "")
		)
		(fill yes
			(thermal_gap 0.5)
			(thermal_bridge_width 0.5)
			(island_removal_mode 0)
		)
		(polygon
			(pts
				(arc
					(start 100.097082 -40.823134)
					(mid 99.596702 -40.823134)
					(end 100.097082 -40.823134)
				)
			)
		)
	)
	(zone
		(layers "In1.Cu" "In2.Cu")
		(hatch none 0.5)
		(connect_pads
			(clearance 0)
		)
		(min_thickness 0.25)
		(keepout
			(tracks not_allowed)
			(vias allowed)
			(pads allowed)
			(copperpour not_allowed)
			(footprints allowed)
		)
		(placement
			(enabled no)
			(sheetname "")
		)
		(fill yes
			(thermal_gap 0.5)
			(thermal_bridge_width 0.5)
			(island_removal_mode 0)
		)
		(polygon
			(pts
				(xy 79.9338 -46.6852) (xy 80.645 -46.6852) (xy 80.645 -47.2948) (xy 79.9338 -47.2948)
			)
		)
	)
	(zone
		(layers "In1.Cu" "In2.Cu")
		(hatch none 0.5)
		(connect_pads
			(clearance 0)
		)
		(min_thickness 0.25)
		(keepout
			(tracks not_allowed)
			(vias allowed)
			(pads allowed)
			(copperpour not_allowed)
			(footprints allowed)
		)
		(placement
			(enabled no)
			(sheetname "")
		)
		(fill yes
			(thermal_gap 0.5)
			(thermal_bridge_width 0.5)
			(island_removal_mode 0)
		)
		(polygon
			(pts
				(xy 78.867 -47.8282) (xy 79.5782 -47.8282) (xy 79.5782 -48.4378) (xy 78.867 -48.4378)
			)
		)
	)
	(zone
		(layers "In1.Cu" "In2.Cu")
		(hatch none 0.5)
		(connect_pads
			(clearance 0)
		)
		(min_thickness 0.25)
		(keepout
			(tracks not_allowed)
			(vias allowed)
			(pads allowed)
			(copperpour not_allowed)
			(footprints allowed)
		)
		(placement
			(enabled no)
			(sheetname "")
		)
		(fill yes
			(thermal_gap 0.5)
			(thermal_bridge_width 0.5)
			(island_removal_mode 0)
		)
		(polygon
			(pts
				(arc
					(start 120.097296 -35.82289)
					(mid 119.596916 -35.82289)
					(end 120.097296 -35.82289)
				)
			)
		)
	)
	(zone
		(layers "In1.Cu" "In2.Cu")
		(hatch none 0.5)
		(connect_pads
			(clearance 0)
		)
		(min_thickness 0.25)
		(keepout
			(tracks not_allowed)
			(vias allowed)
			(pads allowed)
			(copperpour not_allowed)
			(footprints allowed)
		)
		(placement
			(enabled no)
			(sheetname "")
		)
		(fill yes
			(thermal_gap 0.5)
			(thermal_bridge_width 0.5)
			(island_removal_mode 0)
		)
		(polygon
			(pts
				(xy 162.1536 -52.74691) (xy 163.4998 -52.74691) (xy 163.4998 -53.15331) (xy 162.1536 -53.15331)
			)
		)
	)
	(zone
		(layers "In1.Cu" "In2.Cu")
		(hatch none 0.5)
		(connect_pads
			(clearance 0)
		)
		(min_thickness 0.25)
		(keepout
			(tracks not_allowed)
			(vias allowed)
			(pads allowed)
			(copperpour not_allowed)
			(footprints allowed)
		)
		(placement
			(enabled no)
			(sheetname "")
		)
		(fill yes
			(thermal_gap 0.5)
			(thermal_bridge_width 0.5)
			(island_removal_mode 0)
		)
		(polygon
			(pts
				(arc
					(start 114.097308 -36.823142)
					(mid 113.596928 -36.823142)
					(end 114.097308 -36.823142)
				)
			)
		)
	)
	(zone
		(layers "In1.Cu" "In2.Cu")
		(hatch none 0.5)
		(connect_pads
			(clearance 0)
		)
		(min_thickness 0.25)
		(keepout
			(tracks not_allowed)
			(vias allowed)
			(pads allowed)
			(copperpour not_allowed)
			(footprints allowed)
		)
		(placement
			(enabled no)
			(sheetname "")
		)
		(fill yes
			(thermal_gap 0.5)
			(thermal_bridge_width 0.5)
			(island_removal_mode 0)
		)
		(polygon
			(pts
				(arc
					(start 119.097298 -37.82314)
					(mid 118.596918 -37.82314)
					(end 119.097298 -37.82314)
				)
			)
		)
	)
	(zone
		(layers "In1.Cu" "In2.Cu")
		(hatch none 0.5)
		(connect_pads
			(clearance 0)
		)
		(min_thickness 0.25)
		(keepout
			(tracks not_allowed)
			(vias allowed)
			(pads allowed)
			(copperpour not_allowed)
			(footprints allowed)
		)
		(placement
			(enabled no)
			(sheetname "")
		)
		(fill yes
			(thermal_gap 0.5)
			(thermal_bridge_width 0.5)
			(island_removal_mode 0)
		)
		(polygon
			(pts
				(xy 28.3718 -93.345) (xy 28.3718 -94.0562) (xy 27.7622 -94.0562) (xy 27.7622 -93.345)
			)
		)
	)
	(zone
		(layers "In1.Cu" "In2.Cu")
		(hatch none 0.5)
		(connect_pads
			(clearance 0)
		)
		(min_thickness 0.25)
		(keepout
			(tracks not_allowed)
			(vias allowed)
			(pads allowed)
			(copperpour not_allowed)
			(footprints allowed)
		)
		(placement
			(enabled no)
			(sheetname "")
		)
		(fill yes
			(thermal_gap 0.5)
			(thermal_bridge_width 0.5)
			(island_removal_mode 0)
		)
		(polygon
			(pts
				(xy 69.452744 -48.8696) (xy 71.256144 -48.8696) (xy 71.256144 -49.1236) (xy 69.452744 -49.1236)
			)
		)
	)
	(zone
		(layers "In1.Cu" "In2.Cu")
		(hatch none 0.5)
		(connect_pads
			(clearance 0)
		)
		(min_thickness 0.25)
		(keepout
			(tracks not_allowed)
			(vias allowed)
			(pads allowed)
			(copperpour not_allowed)
			(footprints allowed)
		)
		(placement
			(enabled no)
			(sheetname "")
		)
		(fill yes
			(thermal_gap 0.5)
			(thermal_bridge_width 0.5)
			(island_removal_mode 0)
		)
		(polygon
			(pts
				(arc
					(start 100.097082 -38.823138)
					(mid 99.596702 -38.823138)
					(end 100.097082 -38.823138)
				)
			)
		)
	)
	(zone
		(layers "In1.Cu" "In2.Cu")
		(hatch none 0.5)
		(connect_pads
			(clearance 0)
		)
		(min_thickness 0.25)
		(keepout
			(tracks not_allowed)
			(vias allowed)
			(pads allowed)
			(copperpour not_allowed)
			(footprints allowed)
		)
		(placement
			(enabled no)
			(sheetname "")
		)
		(fill yes
			(thermal_gap 0.5)
			(thermal_bridge_width 0.5)
			(island_removal_mode 0)
		)
		(polygon
			(pts
				(xy 159.951166 -55.329836) (xy 160.459166 -55.329836) (xy 160.459166 -56.523636) (xy 159.951166 -56.523636)
			)
		)
	)
	(zone
		(layers "In1.Cu" "In2.Cu")
		(hatch none 0.5)
		(connect_pads
			(clearance 0)
		)
		(min_thickness 0.25)
		(keepout
			(tracks not_allowed)
			(vias allowed)
			(pads allowed)
			(copperpour not_allowed)
			(footprints allowed)
		)
		(placement
			(enabled no)
			(sheetname "")
		)
		(fill yes
			(thermal_gap 0.5)
			(thermal_bridge_width 0.5)
			(island_removal_mode 0)
		)
		(polygon
			(pts
				(xy 18.98396 -88.4682) (xy 19.49196 -88.4682) (xy 19.49196 -89.662) (xy 18.98396 -89.662)
			)
		)
	)
	(zone
		(layers "In1.Cu" "In2.Cu")
		(hatch none 0.5)
		(connect_pads
			(clearance 0)
		)
		(min_thickness 0.25)
		(keepout
			(tracks not_allowed)
			(vias allowed)
			(pads allowed)
			(copperpour not_allowed)
			(footprints allowed)
		)
		(placement
			(enabled no)
			(sheetname "")
		)
		(fill yes
			(thermal_gap 0.5)
			(thermal_bridge_width 0.5)
			(island_removal_mode 0)
		)
		(polygon
			(pts
				(arc
					(start 117.097302 -33.822894)
					(mid 116.596922 -33.822894)
					(end 117.097302 -33.822894)
				)
			)
		)
	)
	(zone
		(layers "In1.Cu" "In2.Cu")
		(hatch none 0.5)
		(connect_pads
			(clearance 0)
		)
		(min_thickness 0.25)
		(keepout
			(tracks not_allowed)
			(vias allowed)
			(pads allowed)
			(copperpour not_allowed)
			(footprints allowed)
		)
		(placement
			(enabled no)
			(sheetname "")
		)
		(fill yes
			(thermal_gap 0.5)
			(thermal_bridge_width 0.5)
			(island_removal_mode 0)
		)
		(polygon
			(pts
				(xy 69.452744 -44.369736) (xy 71.256144 -44.369736) (xy 71.256144 -44.623736) (xy 69.452744 -44.623736)
			)
		)
	)
	(zone
		(layers "In1.Cu" "In2.Cu")
		(hatch none 0.5)
		(connect_pads
			(clearance 0)
		)
		(min_thickness 0.25)
		(keepout
			(tracks not_allowed)
			(vias allowed)
			(pads allowed)
			(copperpour not_allowed)
			(footprints allowed)
		)
		(placement
			(enabled no)
			(sheetname "")
		)
		(fill yes
			(thermal_gap 0.5)
			(thermal_bridge_width 0.5)
			(island_removal_mode 0)
		)
		(polygon
			(pts
				(xy 80.0354 -45.4152) (xy 80.7466 -45.4152) (xy 80.7466 -46.0248) (xy 80.0354 -46.0248)
			)
		)
	)
	(zone
		(layers "In1.Cu" "In2.Cu")
		(hatch none 0.5)
		(connect_pads
			(clearance 0)
		)
		(min_thickness 0.25)
		(keepout
			(tracks not_allowed)
			(vias allowed)
			(pads allowed)
			(copperpour not_allowed)
			(footprints allowed)
		)
		(placement
			(enabled no)
			(sheetname "")
		)
		(fill yes
			(thermal_gap 0.5)
			(thermal_bridge_width 0.5)
			(island_removal_mode 0)
		)
		(polygon
			(pts
				(xy 29.6418 -93.345) (xy 29.6418 -94.0562) (xy 29.0322 -94.0562) (xy 29.0322 -93.345)
			)
		)
	)
	(zone
		(layers "In1.Cu" "In2.Cu")
		(hatch none 0.5)
		(connect_pads
			(clearance 0)
		)
		(min_thickness 0.25)
		(keepout
			(tracks not_allowed)
			(vias allowed)
			(pads allowed)
			(copperpour not_allowed)
			(footprints allowed)
		)
		(placement
			(enabled no)
			(sheetname "")
		)
		(fill yes
			(thermal_gap 0.5)
			(thermal_bridge_width 0.5)
			(island_removal_mode 0)
		)
		(polygon
			(pts
				(xy 29.6418 -94.4118) (xy 29.6418 -95.123) (xy 29.0322 -95.123) (xy 29.0322 -94.4118)
			)
		)
	)
	(zone
		(layers "In1.Cu" "In2.Cu")
		(hatch none 0.5)
		(connect_pads
			(clearance 0)
		)
		(min_thickness 0.25)
		(keepout
			(tracks not_allowed)
			(vias allowed)
			(pads allowed)
			(copperpour not_allowed)
			(footprints allowed)
		)
		(placement
			(enabled no)
			(sheetname "")
		)
		(fill yes
			(thermal_gap 0.5)
			(thermal_bridge_width 0.5)
			(island_removal_mode 0)
		)
		(polygon
			(pts
				(xy 82.4738 -53.1368) (xy 83.0834 -53.1368) (xy 83.0834 -53.848) (xy 82.4738 -53.848)
			)
		)
	)
	(zone
		(layers "In1.Cu" "In2.Cu")
		(hatch none 0.5)
		(connect_pads
			(clearance 0)
		)
		(min_thickness 0.25)
		(keepout
			(tracks not_allowed)
			(vias allowed)
			(pads allowed)
			(copperpour not_allowed)
			(footprints allowed)
		)
		(placement
			(enabled no)
			(sheetname "")
		)
		(fill yes
			(thermal_gap 0.5)
			(thermal_bridge_width 0.5)
			(island_removal_mode 0)
		)
		(polygon
			(pts
				(xy 80.1116 -52.0192) (xy 80.8228 -52.0192) (xy 80.8228 -52.6288) (xy 80.1116 -52.6288)
			)
		)
	)
	(zone
		(layers "In1.Cu" "In2.Cu")
		(hatch none 0.5)
		(connect_pads
			(clearance 0)
		)
		(min_thickness 0.25)
		(keepout
			(tracks not_allowed)
			(vias allowed)
			(pads allowed)
			(copperpour not_allowed)
			(footprints allowed)
		)
		(placement
			(enabled no)
			(sheetname "")
		)
		(fill yes
			(thermal_gap 0.5)
			(thermal_bridge_width 0.5)
			(island_removal_mode 0)
		)
		(polygon
			(pts
				(arc
					(start 99.097084 -36.823142)
					(mid 98.596704 -36.823142)
					(end 99.097084 -36.823142)
				)
			)
		)
	)
	(zone
		(layers "In1.Cu" "In2.Cu")
		(hatch none 0.5)
		(connect_pads
			(clearance 0)
		)
		(min_thickness 0.25)
		(keepout
			(tracks not_allowed)
			(vias allowed)
			(pads allowed)
			(copperpour not_allowed)
			(footprints allowed)
		)
		(placement
			(enabled no)
			(sheetname "")
		)
		(fill yes
			(thermal_gap 0.5)
			(thermal_bridge_width 0.5)
			(island_removal_mode 0)
		)
		(polygon
			(pts
				(xy 73.452736 -48.8696) (xy 75.256136 -48.8696) (xy 75.256136 -49.1236) (xy 73.452736 -49.1236)
			)
		)
	)
	(zone
		(layers "In1.Cu" "In2.Cu")
		(hatch none 0.5)
		(connect_pads
			(clearance 0)
		)
		(min_thickness 0.25)
		(keepout
			(tracks not_allowed)
			(vias allowed)
			(pads allowed)
			(copperpour not_allowed)
			(footprints allowed)
		)
		(placement
			(enabled no)
			(sheetname "")
		)
		(fill yes
			(thermal_gap 0.5)
			(thermal_bridge_width 0.5)
			(island_removal_mode 0)
		)
		(polygon
			(pts
				(xy 80.0354 -44.1452) (xy 80.7466 -44.1452) (xy 80.7466 -44.7548) (xy 80.0354 -44.7548)
			)
		)
	)
	(zone
		(layers "In1.Cu" "In3.Cu" "In4.Cu" "In5.Cu" "In6.Cu" "In8.Cu")
		(hatch none 0.5)
		(connect_pads
			(clearance 0)
		)
		(min_thickness 0.25)
		(keepout
			(tracks not_allowed)
			(vias allowed)
			(pads allowed)
			(copperpour not_allowed)
			(footprints allowed)
		)
		(placement
			(enabled no)
			(sheetname "")
		)
		(fill yes
			(thermal_gap 0.5)
			(thermal_bridge_width 0.5)
			(island_removal_mode 0)
		)
		(polygon
			(pts
				(xy 45.306488 0.512826) (xy 79.001112 0.512826) (xy 79.8068 -0.292862) (xy 79.8068 -6.103874) (xy 44.5008 -6.103874)
				(xy 44.5008 -0.292862)
			)
		)
	)
	(zone
		(net "SG")
		(layers "In1.Cu" "In3.Cu" "In6.Cu" "In8.Cu")
		(hatch none 0.5)
		(connect_pads
			(clearance 0.5)
		)
		(min_thickness 0.25)
		(fill yes
			(thermal_gap 0.5)
			(thermal_bridge_width 0.5)
			(island_removal_mode 0)
		)
		(polygon
			(pts
				(arc
					(start 0.763016 -110.149894)
					(mid 0.832426 -110.317466)
					(end 0.999998 -110.386876)
				)
				(arc
					(start 166.649908 -110.386876)
					(mid 166.81748 -110.317466)
					(end 166.88689 -110.149894)
				)
				(arc
					(start 166.88689 -73.062338)
					(mid 166.023068 -72.677197)
					(end 165.668706 -71.800212)
				)
				(arc
					(start 165.668706 -61.324998)
					(mid 166.02293 -60.447949)
					(end 166.88689 -60.062872)
				)
				(arc
					(start 166.88689 -13.750036)
					(mid 166.81748 -13.582464)
					(end 166.649908 -13.513054)
				)
				(arc
					(start 80.300068 -13.513054)
					(mid 79.053429 -12.996679)
					(end 78.537054 -11.75004)
				)
				(xy 78.537054 -6.6548) (xy 58.862976 -6.6548)
				(arc
					(start 58.862976 -7.450074)
					(mid 57.15 -9.16305)
					(end 55.437024 -7.450074)
				)
				(xy 55.437024 -6.6548) (xy 45.762926 -6.6548)
				(arc
					(start 45.762926 -10.925048)
					(mid 43.17492 -13.513054)
					(end 40.586914 -10.925048)
				)
				(arc
					(start 40.586914 -5.500116)
					(mid 40.517504 -5.332544)
					(end 40.349932 -5.263134)
				)
				(arc
					(start 34.349944 -5.263134)
					(mid 34.182372 -5.332544)
					(end 34.112962 -5.500116)
				)
				(arc
					(start 34.112962 -11.75004)
					(mid 33.596587 -12.996679)
					(end 32.349948 -13.513054)
				)
				(arc
					(start 15.999968 -13.513054)
					(mid 14.753329 -12.996679)
					(end 14.236954 -11.75004)
				)
				(arc
					(start 14.236954 -5.500116)
					(mid 14.167544 -5.332544)
					(end 13.999972 -5.263134)
				)
				(arc
					(start 0.999998 -5.263134)
					(mid 0.832426 -5.332544)
					(end 0.763016 -5.500116)
				)
			)
		)
	)
	(zone
		(layers "In1.Cu" "In8.Cu")
		(hatch none 0.5)
		(connect_pads
			(clearance 0)
		)
		(min_thickness 0.25)
		(keepout
			(tracks not_allowed)
			(vias allowed)
			(pads allowed)
			(copperpour not_allowed)
			(footprints allowed)
		)
		(placement
			(enabled no)
			(sheetname "")
		)
		(fill yes
			(thermal_gap 0.5)
			(thermal_bridge_width 0.5)
			(island_removal_mode 0)
		)
		(polygon
			(pts
				(xy 60.294266 -1.404874) (xy 61.005466 -1.404874) (xy 61.005466 -5.595874) (xy 60.294266 -5.595874)
			)
		)
	)
	(zone
		(layer "In2.Cu")
		(hatch none 0.5)
		(connect_pads
			(clearance 0)
		)
		(min_thickness 0.25)
		(keepout
			(tracks not_allowed)
			(vias allowed)
			(pads allowed)
			(copperpour not_allowed)
			(footprints allowed)
		)
		(placement
			(enabled no)
			(sheetname "")
		)
		(fill
			(thermal_gap 0.5)
			(thermal_bridge_width 0.5)
			(island_removal_mode 0)
		)
		(polygon
			(pts
				(xy 88.58123 -48.751744) (xy 89.52103 -48.751744) (xy 89.52103 -48.954944) (xy 88.58123 -48.954944)
			)
		)
	)
	(zone
		(layer "In2.Cu")
		(hatch none 0.5)
		(connect_pads
			(clearance 0)
		)
		(min_thickness 0.25)
		(keepout
			(tracks not_allowed)
			(vias allowed)
			(pads allowed)
			(copperpour not_allowed)
			(footprints allowed)
		)
		(placement
			(enabled no)
			(sheetname "")
		)
		(fill
			(thermal_gap 0.5)
			(thermal_bridge_width 0.5)
			(island_removal_mode 0)
		)
		(polygon
			(pts
				(xy 90.514678 -47.951898) (xy 91.454478 -47.951898) (xy 91.454478 -48.155098) (xy 90.514678 -48.155098)
			)
		)
	)
	(zone
		(net "XP1R8V_ICP10100")
		(layer "In2.Cu")
		(hatch none 0.5)
		(connect_pads
			(clearance 0.5)
		)
		(min_thickness 0.25)
		(fill yes
			(thermal_gap 0.5)
			(thermal_bridge_width 0.5)
			(island_removal_mode 0)
		)
		(polygon
			(pts
				(xy 15.748 -68.8848) (xy 15.748 -69.596) (xy 16.383 -70.231) (xy 27.178 -70.231) (xy 28.3718 -69.0372)
				(xy 28.3718 -64.9478) (xy 27.178 -63.754) (xy 16.3322 -63.754) (xy 15.748 -64.3382)
			)
		)
	)
	(zone
		(layer "In2.Cu")
		(hatch none 0.5)
		(connect_pads
			(clearance 0)
		)
		(min_thickness 0.25)
		(keepout
			(tracks not_allowed)
			(vias allowed)
			(pads allowed)
			(copperpour not_allowed)
			(footprints allowed)
		)
		(placement
			(enabled no)
			(sheetname "")
		)
		(fill
			(thermal_gap 0.5)
			(thermal_bridge_width 0.5)
			(island_removal_mode 0)
		)
		(polygon
			(pts
				(xy 90.514678 -48.751744) (xy 91.454478 -48.751744) (xy 91.454478 -48.954944) (xy 90.514678 -48.954944)
			)
		)
	)
	(zone
		(net "VIN_XP5R0V")
		(layer "In2.Cu")
		(hatch none 0.5)
		(connect_pads
			(clearance 0.5)
		)
		(min_thickness 0.25)
		(fill yes
			(thermal_gap 0.5)
			(thermal_bridge_width 0.5)
			(island_removal_mode 0)
		)
		(polygon
			(pts
				(xy 39.751 -106.426) (xy 43.053 -106.426) (xy 43.561 -105.918) (xy 43.561 -96.393) (xy 42.926 -95.758)
				(xy 39.751 -95.758) (xy 39.116 -96.393) (xy 39.116 -105.791)
			)
		)
	)
	(zone
		(layer "In2.Cu")
		(hatch none 0.5)
		(connect_pads
			(clearance 0)
		)
		(min_thickness 0.25)
		(keepout
			(tracks not_allowed)
			(vias allowed)
			(pads allowed)
			(copperpour not_allowed)
			(footprints allowed)
		)
		(placement
			(enabled no)
			(sheetname "")
		)
		(fill
			(thermal_gap 0.5)
			(thermal_bridge_width 0.5)
			(island_removal_mode 0)
		)
		(polygon
			(pts
				(xy 90.514678 -48.351948) (xy 91.454478 -48.351948) (xy 91.454478 -48.555148) (xy 90.514678 -48.555148)
			)
		)
	)
	(zone
		(net "VIN_XP1R0V")
		(layer "In2.Cu")
		(hatch none 0.5)
		(connect_pads
			(clearance 0.5)
		)
		(min_thickness 0.25)
		(fill yes
			(thermal_gap 0.5)
			(thermal_bridge_width 0.5)
			(island_removal_mode 0)
		)
		(polygon
			(pts
				(xy 135.89 -54.991) (xy 135.89 -52.959) (xy 136.271 -52.578) (xy 146.431 -52.578) (xy 146.685 -52.832)
				(xy 146.685 -56.134) (xy 146.558 -56.261) (xy 145.288 -56.261) (xy 145.034 -56.007) (xy 145.034 -55.499)
				(xy 144.78 -55.245) (xy 142.113 -55.245) (xy 141.732 -55.626) (xy 136.525 -55.626)
			)
		)
	)
	(zone
		(layer "In2.Cu")
		(hatch none 0.5)
		(connect_pads
			(clearance 0)
		)
		(min_thickness 0.25)
		(keepout
			(tracks not_allowed)
			(vias allowed)
			(pads allowed)
			(copperpour not_allowed)
			(footprints allowed)
		)
		(placement
			(enabled no)
			(sheetname "")
		)
		(fill
			(thermal_gap 0.5)
			(thermal_bridge_width 0.5)
			(island_removal_mode 0)
		)
		(polygon
			(pts
				(xy 28.621736 -90.0684) (xy 28.926536 -90.0684) (xy 28.926536 -91.694) (xy 28.621736 -91.694)
			)
		)
	)
	(zone
		(net "XP1R0V_AGND")
		(layer "In2.Cu")
		(hatch none 0.5)
		(connect_pads
			(clearance 0.5)
		)
		(min_thickness 0.25)
		(fill yes
			(thermal_gap 0.5)
			(thermal_bridge_width 0.5)
			(island_removal_mode 0)
		)
		(polygon
			(pts
				(xy 142.113 -61.468) (xy 146.685 -61.468) (xy 147.447 -60.706) (xy 147.447 -58.166) (xy 146.939 -57.658)
				(xy 146.05 -57.658) (xy 144.145 -55.753) (xy 142.621 -55.753) (xy 141.605 -56.769) (xy 140.843 -57.531)
				(xy 140.843 -60.198) (xy 141.605 -60.96)
			)
		)
	)
	(zone
		(layer "In2.Cu")
		(hatch none 0.5)
		(connect_pads
			(clearance 0)
		)
		(min_thickness 0.25)
		(keepout
			(tracks not_allowed)
			(vias allowed)
			(pads allowed)
			(copperpour not_allowed)
			(footprints allowed)
		)
		(placement
			(enabled no)
			(sheetname "")
		)
		(fill
			(thermal_gap 0.5)
			(thermal_bridge_width 0.5)
			(island_removal_mode 0)
		)
		(polygon
			(pts
				(xy 29.121862 -90.0684) (xy 29.426662 -90.0684) (xy 29.426662 -91.694) (xy 29.121862 -91.694)
			)
		)
	)
	(zone
		(net "VIN_XP3R3")
		(layer "In2.Cu")
		(hatch none 0.5)
		(connect_pads
			(clearance 0.5)
		)
		(min_thickness 0.25)
		(fill yes
			(thermal_gap 0.5)
			(thermal_bridge_width 0.5)
			(island_removal_mode 0)
		)
		(polygon
			(pts
				(xy 82.804 -96.647) (xy 82.804 -107.3404) (xy 83.439 -107.9754) (xy 86.741 -107.9754) (xy 87.376 -107.3404)
				(xy 87.376 -96.774) (xy 86.741 -96.139) (xy 83.312 -96.139)
			)
		)
	)
	(zone
		(layer "In2.Cu")
		(hatch none 0.5)
		(connect_pads
			(clearance 0)
		)
		(min_thickness 0.25)
		(keepout
			(tracks not_allowed)
			(vias allowed)
			(pads allowed)
			(copperpour not_allowed)
			(footprints allowed)
		)
		(placement
			(enabled no)
			(sheetname "")
		)
		(fill
			(thermal_gap 0.5)
			(thermal_bridge_width 0.5)
			(island_removal_mode 0)
		)
		(polygon
			(pts
				(xy 88.58123 -48.351948) (xy 89.52103 -48.351948) (xy 89.52103 -48.555148) (xy 88.58123 -48.555148)
			)
		)
	)
	(zone
		(layer "In2.Cu")
		(hatch none 0.5)
		(connect_pads
			(clearance 0)
		)
		(min_thickness 0.25)
		(keepout
			(tracks not_allowed)
			(vias allowed)
			(pads allowed)
			(copperpour not_allowed)
			(footprints allowed)
		)
		(placement
			(enabled no)
			(sheetname "")
		)
		(fill
			(thermal_gap 0.5)
			(thermal_bridge_width 0.5)
			(island_removal_mode 0)
		)
		(polygon
			(pts
				(xy 90.514678 -49.151794) (xy 91.454478 -49.151794) (xy 91.454478 -49.354994) (xy 90.514678 -49.354994)
			)
		)
	)
	(zone
		(net "XP3R3V_FT4232")
		(layer "In4.Cu")
		(hatch none 0.5)
		(connect_pads
			(clearance 0.5)
		)
		(min_thickness 0.25)
		(fill yes
			(thermal_gap 0.5)
			(thermal_bridge_width 0.5)
			(island_removal_mode 0)
		)
		(polygon
			(pts
				(xy 34.373312 -92.456) (xy 43.551094 -92.456) (xy 43.97502 -92.032074) (xy 43.97502 -87.018876)
				(xy 42.180764 -85.22462)
				(arc
					(start 39.10584 -85.22462)
					(mid 39.008653 -85.20527)
					(end 38.926262 -85.150198)
				)
				(arc
					(start 38.476682 -84.700618)
					(mid 38.421576 -84.618241)
					(end 38.40226 -84.52104)
				)
				(arc
					(start 38.40226 -80.73898)
					(mid 38.42161 -80.641793)
					(end 38.476682 -80.559402)
				)
				(arc
					(start 39.688262 -79.347822)
					(mid 39.770639 -79.292716)
					(end 39.86784 -79.2734)
				)
				(arc
					(start 43.30192 -79.2734)
					(mid 43.399107 -79.29275)
					(end 43.481498 -79.347822)
				)
				(xy 50.547016 -86.41334) (xy 57.156604 -86.41334) (xy 58.3819 -85.188044)
				(arc
					(start 58.3819 -84.202778)
					(mid 58.339459 -84.12745)
					(end 58.32475 -84.04225)
				)
				(arc
					(start 58.32475 -84.04225)
					(mid 58.339465 -83.957052)
					(end 58.3819 -83.881722)
				)
				(xy 58.3819 -83.211416) (xy 47.758604 -72.58812) (xy 23.495 -72.58812) (xy 23.495 -88.816688) (xy 24.721312 -90.043)
				(arc
					(start 31.75 -90.043)
					(mid 31.944389 -90.081684)
					(end 32.109156 -90.191844)
				)
			)
		)
	)
	(zone
		(net "XP3R3V_FPGA")
		(layer "In4.Cu")
		(hatch none 0.5)
		(connect_pads
			(clearance 0.5)
		)
		(min_thickness 0.25)
		(fill yes
			(thermal_gap 0.5)
			(thermal_bridge_width 0.5)
			(island_removal_mode 0)
		)
		(polygon
			(pts
				(xy 101.197156 -75.565) (xy 108.098844 -75.565) (xy 108.966 -74.697844)
				(arc
					(start 108.966 -70.231)
					(mid 108.98535 -70.133813)
					(end 109.040422 -70.051422)
				)
				(arc
					(start 110.564422 -68.527422)
					(mid 110.646799 -68.472316)
					(end 110.744 -68.453)
				)
				(xy 119.782844 -68.453) (xy 121.92 -66.315844) (xy 121.92 -44.45)
				(arc
					(start 106.045 -44.45)
					(mid 105.947813 -44.43065)
					(end 105.865422 -44.375578)
				)
				(xy 104.775 -43.285156)
				(arc
					(start 103.938578 -44.121578)
					(mid 103.856201 -44.176684)
					(end 103.759 -44.196)
				)
				(xy 96.012 -44.196) (xy 96.012 -67.331844)
				(arc
					(start 97.969578 -69.289422)
					(mid 98.024684 -69.371799)
					(end 98.044 -69.469)
				)
				(xy 98.044 -72.411844)
			)
		)
	)
	(zone
		(net "XP1R0V_FPGA")
		(layer "In4.Cu")
		(hatch none 0.5)
		(connect_pads
			(clearance 0.5)
		)
		(min_thickness 0.25)
		(fill yes
			(thermal_gap 0.5)
			(thermal_bridge_width 0.5)
			(island_removal_mode 0)
		)
		(polygon
			(pts
				(xy 131.931156 -45.212) (xy 137.816844 -45.212) (xy 139.827 -43.201844) (xy 139.827 -31.347156)
				(xy 138.832844 -30.353) (xy 92.180156 -30.353) (xy 91.186 -31.347156)
				(arc
					(start 91.186 -36.068)
					(mid 91.16665 -36.165187)
					(end 91.111578 -36.247578)
				)
				(arc
					(start 90.603578 -36.755578)
					(mid 90.521201 -36.810684)
					(end 90.424 -36.83)
				)
				(xy 88.624156 -36.83) (xy 88.265 -37.189156) (xy 88.265 -39.264844) (xy 89.132156 -40.132) (xy 92.71 -40.132)
				(arc
					(start 92.71 -38.735)
					(mid 92.72935 -38.637813)
					(end 92.784422 -38.555422)
				)
				(arc
					(start 93.927422 -37.412422)
					(mid 94.009799 -37.357316)
					(end 94.107 -37.338)
				)
				(arc
					(start 103.759 -37.338)
					(mid 103.856187 -37.35735)
					(end 103.938578 -37.412422)
				)
				(xy 104.775 -38.248844)
				(arc
					(start 106.246422 -36.777422)
					(mid 106.328799 -36.722316)
					(end 106.426 -36.703)
				)
				(arc
					(start 131.064 -36.703)
					(mid 131.161187 -36.72235)
					(end 131.243578 -36.777422)
				)
				(arc
					(start 131.751578 -37.285422)
					(mid 131.806684 -37.367799)
					(end 131.826 -37.465)
				)
				(arc
					(start 131.826 -43.18)
					(mid 131.80665 -43.277187)
					(end 131.751578 -43.359578)
				)
				(xy 130.915156 -44.196)
			)
		)
	)
	(zone
		(net "XP3R3V")
		(layer "In4.Cu")
		(hatch none 0.5)
		(connect_pads
			(clearance 0.5)
		)
		(min_thickness 0.25)
		(fill yes
			(thermal_gap 0.5)
			(thermal_bridge_width 0.5)
			(island_removal_mode 0)
		)
		(polygon
			(pts
				(xy 74.273156 -92.456)
				(arc
					(start 132.929884 -92.456)
					(mid 132.95864 -92.417866)
					(end 132.990844 -92.382594)
				)
				(xy 133.985 -91.388438)
				(arc
					(start 133.985 -58.801)
					(mid 134.023684 -58.606611)
					(end 134.133844 -58.441844)
				)
				(arc
					(start 135.149844 -57.425844)
					(mid 135.314612 -57.315686)
					(end 135.509 -57.277)
				)
				(arc
					(start 145.034 -57.277)
					(mid 145.100353 -57.281319)
					(end 145.165572 -57.294272)
				)
				(xy 148.082 -54.377844) (xy 148.082 -14.782038)
				(arc
					(start 80.300068 -14.782038)
					(mid 78.156122 -13.893986)
					(end 77.26807 -11.75004)
				)
				(xy 77.26807 -6.6548) (xy 60.13196 -6.6548)
				(arc
					(start 60.13196 -7.450074)
					(mid 59.431115 -9.370647)
					(end 57.658 -10.388346)
				)
				(xy 57.658 -18.786094) (xy 58.175906 -19.304)
				(arc
					(start 72.263 -19.304)
					(mid 72.360187 -19.32335)
					(end 72.442578 -19.378422)
				)
				(xy 84.052156 -30.988) (xy 90.826844 -30.988)
				(arc
					(start 91.895422 -29.919422)
					(mid 91.977799 -29.864316)
					(end 92.075 -29.845)
				)
				(arc
					(start 138.938 -29.845)
					(mid 139.035187 -29.86435)
					(end 139.117578 -29.919422)
				)
				(arc
					(start 140.260578 -31.062422)
					(mid 140.315684 -31.144799)
					(end 140.335 -31.242)
				)
				(arc
					(start 140.335 -43.307)
					(mid 140.31565 -43.404187)
					(end 140.260578 -43.486578)
				)
				(arc
					(start 138.101578 -45.645578)
					(mid 138.019201 -45.700684)
					(end 137.922 -45.72)
				)
				(arc
					(start 131.826 -45.72)
					(mid 131.728813 -45.70065)
					(end 131.646422 -45.645578)
				)
				(xy 130.450844 -44.45) (xy 122.428 -44.45)
				(arc
					(start 122.428 -66.421)
					(mid 122.40865 -66.518187)
					(end 122.353578 -66.600578)
				)
				(arc
					(start 120.067578 -68.886578)
					(mid 119.985201 -68.941684)
					(end 119.888 -68.961)
				)
				(xy 110.849156 -68.961) (xy 109.474 -70.336156)
				(arc
					(start 109.474 -74.803)
					(mid 109.45465 -74.900187)
					(end 109.399578 -74.982578)
				)
				(arc
					(start 108.383578 -75.998578)
					(mid 108.301201 -76.053684)
					(end 108.204 -76.073)
				)
				(arc
					(start 101.092 -76.073)
					(mid 100.994813 -76.05365)
					(end 100.912422 -75.998578)
				)
				(xy 97.79 -72.876156)
				(arc
					(start 96.318578 -74.347578)
					(mid 96.236201 -74.402684)
					(end 96.139 -74.422)
				)
				(xy 83.439 -74.422)
				(arc
					(start 83.439 -76.454)
					(mid 83.41965 -76.551187)
					(end 83.364578 -76.633578)
				)
				(xy 72.517 -87.481156) (xy 72.517 -90.699844)
			)
		)
	)
	(zone
		(net "XP3R3V_FPGA")
		(layer "In4.Cu")
		(hatch none 0.5)
		(connect_pads
			(clearance 0.5)
		)
		(min_thickness 0.25)
		(fill yes
			(thermal_gap 0.5)
			(thermal_bridge_width 0.5)
			(island_removal_mode 0)
		)
		(polygon
			(pts
				(xy 154.889454 -109.117892) (xy 163.56584 -109.117892) (xy 163.56584 -106.66476) (xy 165.617906 -106.66476)
				(arc
					(start 165.617906 -73.964546)
					(mid 164.725004 -73.041803)
					(end 164.399722 -71.799704)
				)
				(arc
					(start 164.399722 -61.324998)
					(mid 164.725179 -60.083181)
					(end 165.617906 -59.160664)
				)
				(xy 165.617906 -14.782038) (xy 148.59 -14.782038)
				(arc
					(start 148.59 -54.483)
					(mid 148.57065 -54.580187)
					(end 148.515578 -54.662578)
				)
				(xy 145.572734 -57.605422)
				(arc
					(start 147.425156 -59.457844)
					(mid 147.535314 -59.622612)
					(end 147.574 -59.817)
				)
				(xy 147.574 -78.148688) (xy 149.943312 -80.518)
				(arc
					(start 153.67 -80.518)
					(mid 153.864389 -80.556684)
					(end 154.029156 -80.666844)
				)
				(arc
					(start 156.188156 -82.825844)
					(mid 156.298314 -82.990612)
					(end 156.337 -83.185)
				)
				(arc
					(start 156.337 -97.409)
					(mid 156.298316 -97.603389)
					(end 156.188156 -97.768156)
				)
				(xy 154.432 -99.524312) (xy 154.432 -108.660438)
			)
		)
	)
	(zone
		(net "XP3R3V_FPGA")
		(layer "In4.Cu")
		(hatch none 0.5)
		(connect_pads
			(clearance 0.5)
		)
		(min_thickness 0.25)
		(fill yes
			(thermal_gap 0.5)
			(thermal_bridge_width 0.5)
			(island_removal_mode 0)
		)
		(polygon
			(pts
				(arc
					(start 60.03925 -82.83575)
					(mid 60.104039 -82.839898)
					(end 60.167774 -82.85226)
				)
				(xy 63.092584 -82.85226)
				(arc
					(start 72.845422 -73.099422)
					(mid 72.927799 -73.044316)
					(end 73.025 -73.025)
				)
				(xy 82.042 -73.025)
				(arc
					(start 82.042 -32.893)
					(mid 82.06135 -32.795813)
					(end 82.116422 -32.713422)
				)
				(xy 83.587844 -31.242) (xy 72.157844 -19.812) (xy 58.112406 -19.812) (xy 57.658 -20.266406)
				(arc
					(start 57.658 -29.591)
					(mid 57.619316 -29.785389)
					(end 57.509156 -29.950156)
				)
				(xy 23.495 -63.964312) (xy 23.495 -72.08012)
				(arc
					(start 47.86376 -72.08012)
					(mid 47.960947 -72.09947)
					(end 48.043338 -72.154542)
				)
				(xy 58.741056 -82.85226)
				(arc
					(start 59.44108 -82.85226)
					(mid 59.485413 -82.839888)
					(end 59.53125 -82.83575)
				)
				(arc
					(start 59.53125 -82.83575)
					(mid 59.577082 -82.839919)
					(end 59.62142 -82.85226)
				)
				(arc
					(start 59.910726 -82.85226)
					(mid 59.974459 -82.839882)
					(end 60.03925 -82.83575)
				)
			)
		)
	)
	(zone
		(net "XP12R0V")
		(layer "In4.Cu")
		(hatch none 0.5)
		(connect_pads
			(clearance 0.5)
		)
		(min_thickness 0.25)
		(fill yes
			(thermal_gap 0.5)
			(thermal_bridge_width 0.5)
			(island_removal_mode 0)
		)
		(polygon
			(pts
				(xy 37.167312 -106.807) (xy 126.154688 -106.807)
				(arc
					(start 129.815844 -103.145844)
					(mid 129.980612 -103.035686)
					(end 130.175 -102.997)
				)
				(xy 146.868388 -102.997) (xy 148.50618 -101.359208) (xy 148.50618 -95.630492)
				(arc
					(start 146.960844 -94.085156)
					(mid 146.850686 -93.920388)
					(end 146.812 -93.726)
				)
				(arc
					(start 146.812 -83.312)
					(mid 146.850684 -83.117611)
					(end 146.960844 -82.952844)
				)
				(xy 148.951188 -80.9625)
				(arc
					(start 146.706844 -78.718156)
					(mid 146.596686 -78.553388)
					(end 146.558 -78.359)
				)
				(xy 146.558 -60.027312) (xy 144.823688 -58.293) (xy 135.719312 -58.293) (xy 135.001 -59.011312)
				(arc
					(start 135.001 -93.472)
					(mid 134.962316 -93.666389)
					(end 134.852156 -93.831156)
				)
				(arc
					(start 134.751318 -93.931994)
					(mid 134.661638 -94.053388)
					(end 134.540244 -94.143068)
				)
				(arc
					(start 132.439156 -96.244156)
					(mid 132.274388 -96.354314)
					(end 132.08 -96.393)
				)
				(arc
					(start 48.514 -96.393)
					(mid 48.319611 -96.354316)
					(end 48.154844 -96.244156)
				)
				(xy 45.382688 -93.472) (xy 34.671 -93.472) (xy 34.671 -104.310688)
			)
		)
	)
	(zone
		(net "XP1R0V_FPGA_MGTAVCC")
		(layer "In4.Cu")
		(hatch none 0.5)
		(connect_pads
			(clearance 0.5)
		)
		(min_thickness 0.25)
		(fill yes
			(thermal_gap 0.5)
			(thermal_bridge_width 0.5)
			(island_removal_mode 0)
		)
		(polygon
			(pts
				(xy 94.212156 -43.688) (xy 103.653844 -43.688) (xy 104.521 -42.820844) (xy 104.521 -38.713156) (xy 103.653844 -37.846)
				(xy 94.212156 -37.846) (xy 93.218 -38.840156) (xy 93.218 -42.693844)
			)
		)
	)
	(zone
		(net "XP5R0V")
		(layer "In4.Cu")
		(hatch none 0.5)
		(connect_pads
			(clearance 0.5)
		)
		(min_thickness 0.25)
		(fill yes
			(thermal_gap 0.5)
			(thermal_bridge_width 0.5)
			(island_removal_mode 0)
		)
		(polygon
			(pts
				(xy 48.724312 -95.377) (xy 131.869688 -95.377) (xy 133.568186 -93.678248)
				(arc
					(start 132.990844 -93.100906)
					(mid 132.936363 -93.036522)
					(end 132.893308 -92.964)
				)
				(arc
					(start 74.168 -92.964)
					(mid 74.070813 -92.94465)
					(end 73.988422 -92.889578)
				)
				(arc
					(start 72.083422 -90.984578)
					(mid 72.028316 -90.902201)
					(end 72.009 -90.805)
				)
				(arc
					(start 72.009 -87.376)
					(mid 72.02835 -87.278813)
					(end 72.083422 -87.196422)
				)
				(xy 82.931 -76.348844) (xy 82.931 -74.273156) (xy 82.190844 -73.533) (xy 73.130156 -73.533)
				(arc
					(start 63.377318 -83.285838)
					(mid 63.294941 -83.340944)
					(end 63.19774 -83.36026)
				)
				(arc
					(start 60.546996 -83.36026)
					(mid 60.505373 -83.545761)
					(end 60.398406 -83.702906)
				)
				(arc
					(start 60.392818 -83.708494)
					(mid 60.352512 -83.772541)
					(end 60.303156 -83.829906)
				)
				(xy 59.83732 -84.295742) (xy 59.825382 -84.30768)
				(arc
					(start 59.287156 -84.845906)
					(mid 59.122388 -84.956064)
					(end 58.928 -84.99475)
				)
				(xy 58.8899 -84.993226)
				(arc
					(start 58.8899 -85.2932)
					(mid 58.87055 -85.390387)
					(end 58.815478 -85.472778)
				)
				(arc
					(start 57.441338 -86.846918)
					(mid 57.358961 -86.902024)
					(end 57.26176 -86.92134)
				)
				(arc
					(start 50.44186 -86.92134)
					(mid 50.344673 -86.90199)
					(end 50.262282 -86.846918)
				)
				(xy 43.196764 -79.7814) (xy 39.972996 -79.7814) (xy 38.91026 -80.844136) (xy 38.91026 -84.415884)
				(xy 39.210996 -84.71662)
				(arc
					(start 42.28592 -84.71662)
					(mid 42.383107 -84.73597)
					(end 42.465498 -84.791042)
				)
				(arc
					(start 44.408598 -86.734142)
					(mid 44.463704 -86.816519)
					(end 44.48302 -86.91372)
				)
				(xy 44.48302 -91.907614) (xy 45.031406 -92.456)
				(arc
					(start 45.593 -92.456)
					(mid 45.787389 -92.494684)
					(end 45.952156 -92.604844)
				)
			)
		)
	)
	(zone
		(net "XP1R0V_FPGA_VCCINT")
		(layer "In4.Cu")
		(hatch none 0.5)
		(connect_pads
			(clearance 0.5)
		)
		(min_thickness 0.25)
		(fill yes
			(thermal_gap 0.5)
			(thermal_bridge_width 0.5)
			(island_removal_mode 0)
		)
		(polygon
			(pts
				(xy 106.150156 -43.942) (xy 130.450844 -43.942) (xy 131.318 -43.074844) (xy 131.318 -37.570156)
				(xy 130.958844 -37.211) (xy 106.531156 -37.211) (xy 105.029 -38.713156) (xy 105.029 -42.820844)
			)
		)
	)
	(zone
		(net "XP3R3V_FPGA")
		(layer "In4.Cu")
		(hatch none 0.5)
		(connect_pads
			(clearance 0.5)
		)
		(min_thickness 0.25)
		(fill yes
			(thermal_gap 0.5)
			(thermal_bridge_width 0.5)
			(island_removal_mode 0)
		)
		(polygon
			(pts
				(xy 2.032 -109.117892) (xy 12.687046 -109.117892) (xy 13.335 -108.469938)
				(arc
					(start 13.335 -98.425)
					(mid 13.373684 -98.230611)
					(end 13.483844 -98.065844)
				)
				(xy 14.224 -97.325688)
				(arc
					(start 14.224 -56.642)
					(mid 14.262684 -56.447611)
					(end 14.372844 -56.282844)
				)
				(xy 42.164 -28.491688)
				(arc
					(start 42.164 -14.647164)
					(mid 40.111003 -13.267806)
					(end 39.31793 -10.925048)
				)
				(xy 39.31793 -6.532118) (xy 35.381946 -6.532118)
				(arc
					(start 35.381946 -11.75004)
					(mid 34.493894 -13.893986)
					(end 32.349948 -14.782038)
				)
				(arc
					(start 15.999968 -14.782038)
					(mid 13.856022 -13.893986)
					(end 12.96797 -11.75004)
				)
				(xy 12.96797 -6.532118) (xy 2.032 -6.532118)
			)
		)
	)
	(zone
		(net "XP1R2V_FPGA")
		(layer "In4.Cu")
		(hatch none 0.5)
		(connect_pads
			(clearance 0.5)
		)
		(min_thickness 0.25)
		(fill yes
			(thermal_gap 0.5)
			(thermal_bridge_width 0.5)
			(island_removal_mode 0)
		)
		(polygon
			(pts
				(xy 83.290156 -73.914) (xy 96.033844 -73.914) (xy 97.536 -72.411844) (xy 97.536 -69.574156)
				(arc
					(start 95.578422 -67.616578)
					(mid 95.523316 -67.534201)
					(end 95.504 -67.437)
				)
				(xy 95.504 -44.196)
				(arc
					(start 94.107 -44.196)
					(mid 94.009813 -44.17665)
					(end 93.927422 -44.121578)
				)
				(arc
					(start 92.784422 -42.978578)
					(mid 92.729316 -42.896201)
					(end 92.71 -42.799)
				)
				(xy 92.71 -40.64)
				(arc
					(start 89.027 -40.64)
					(mid 88.929813 -40.62065)
					(end 88.847422 -40.565578)
				)
				(arc
					(start 87.831422 -39.549578)
					(mid 87.776316 -39.467201)
					(end 87.757 -39.37)
				)
				(arc
					(start 87.757 -37.084)
					(mid 87.77635 -36.986813)
					(end 87.831422 -36.904422)
				)
				(arc
					(start 88.339422 -36.396422)
					(mid 88.421799 -36.341316)
					(end 88.519 -36.322)
				)
				(xy 90.318844 -36.322) (xy 90.678 -35.962844) (xy 90.678 -31.496) (xy 84.052156 -31.496) (xy 82.55 -32.998156)
				(xy 82.55 -73.173844)
			)
		)
	)
	(zone
		(net "XP12R0V_EXT")
		(layer "In4.Cu")
		(hatch none 0.5)
		(connect_pads
			(clearance 0.5)
		)
		(min_thickness 0.25)
		(fill yes
			(thermal_gap 0.5)
			(thermal_bridge_width 0.5)
			(island_removal_mode 0)
		)
		(polygon
			(pts
				(xy 14.935454 -109.117892) (xy 152.895046 -109.117892) (xy 153.416 -108.596938)
				(arc
					(start 153.416 -99.314)
					(mid 153.454684 -99.119611)
					(end 153.564844 -98.954844)
				)
				(xy 155.321 -97.198688) (xy 155.321 -83.395312) (xy 153.459688 -81.534) (xy 149.816312 -81.534)
				(xy 147.828 -83.522312) (xy 147.828 -93.515688)
				(arc
					(start 149.373336 -95.061024)
					(mid 149.483494 -95.225792)
					(end 149.52218 -95.42018)
				)
				(arc
					(start 149.52218 -101.56952)
					(mid 149.483496 -101.763909)
					(end 149.373336 -101.928676)
				)
				(arc
					(start 147.437856 -103.864156)
					(mid 147.273088 -103.974314)
					(end 147.0787 -104.013)
				)
				(xy 130.385312 -104.013)
				(arc
					(start 126.724156 -107.674156)
					(mid 126.559388 -107.784314)
					(end 126.365 -107.823)
				)
				(arc
					(start 36.957 -107.823)
					(mid 36.762611 -107.784316)
					(end 36.597844 -107.674156)
				)
				(arc
					(start 33.803844 -104.880156)
					(mid 33.693686 -104.715388)
					(end 33.655 -104.521)
				)
				(xy 33.655 -93.174312) (xy 31.539688 -91.059)
				(arc
					(start 24.511 -91.059)
					(mid 24.316611 -91.020316)
					(end 24.151844 -90.910156)
				)
				(xy 23.411688 -90.17) (xy 22.606 -90.17) (xy 22.56409 -90.168222) (xy 20.32 -92.412312)
				(arc
					(start 20.32 -97.282)
					(mid 20.281316 -97.476389)
					(end 20.171156 -97.641156)
				)
				(arc
					(start 19.282156 -98.530156)
					(mid 19.117388 -98.640314)
					(end 18.923 -98.679)
				)
				(arc
					(start 15.367 -98.679)
					(mid 15.172611 -98.640316)
					(end 15.007844 -98.530156)
				)
				(xy 14.732 -98.254312) (xy 14.351 -98.635312) (xy 14.351 -108.533438)
			)
		)
	)
	(zone
		(layers "In4.Cu" "In5.Cu")
		(hatch none 0.5)
		(connect_pads
			(clearance 0)
		)
		(min_thickness 0.25)
		(keepout
			(tracks not_allowed)
			(vias allowed)
			(pads allowed)
			(copperpour not_allowed)
			(footprints allowed)
		)
		(placement
			(enabled no)
			(sheetname "")
		)
		(fill yes
			(thermal_gap 0.5)
			(thermal_bridge_width 0.5)
			(island_removal_mode 0)
		)
		(polygon
			(pts
				(arc
					(start 147.41652 -93.382846)
					(mid 149.549866 -95.483428)
					(end 151.683212 -93.382846)
				)
				(xy 151.683466 -93.382846)
				(arc
					(start 151.683466 -84.950046)
					(mid 149.549866 -82.816446)
					(end 147.416266 -84.950046)
				)
				(xy 147.416266 -93.382846)
			)
		)
	)
	(zone
		(layers "In4.Cu" "In5.Cu")
		(hatch none 0.5)
		(connect_pads
			(clearance 0)
		)
		(min_thickness 0.25)
		(keepout
			(tracks not_allowed)
			(vias allowed)
			(pads allowed)
			(copperpour not_allowed)
			(footprints allowed)
		)
		(placement
			(enabled no)
			(sheetname "")
		)
		(fill yes
			(thermal_gap 0.5)
			(thermal_bridge_width 0.5)
			(island_removal_mode 0)
		)
		(polygon
			(pts
				(arc
					(start 68.606924 -104.650032)
					(mid 61.393324 -104.650032)
					(end 68.606924 -104.650032)
				)
			)
		)
	)
	(zone
		(layers "In4.Cu" "In5.Cu")
		(hatch none 0.5)
		(connect_pads
			(clearance 0)
		)
		(min_thickness 0.25)
		(keepout
			(tracks not_allowed)
			(vias allowed)
			(pads allowed)
			(copperpour not_allowed)
			(footprints allowed)
		)
		(placement
			(enabled no)
			(sheetname "")
		)
		(fill yes
			(thermal_gap 0.5)
			(thermal_bridge_width 0.5)
			(island_removal_mode 0)
		)
		(polygon
			(pts
				(arc
					(start 11.005312 -9.349994)
					(mid 3.994912 -9.349994)
					(end 11.005312 -9.349994)
				)
			)
		)
	)
	(zone
		(layers "In4.Cu" "In5.Cu")
		(hatch none 0.5)
		(connect_pads
			(clearance 0)
		)
		(min_thickness 0.25)
		(keepout
			(tracks not_allowed)
			(vias allowed)
			(pads allowed)
			(copperpour not_allowed)
			(footprints allowed)
		)
		(placement
			(enabled no)
			(sheetname "")
		)
		(fill yes
			(thermal_gap 0.5)
			(thermal_bridge_width 0.5)
			(island_removal_mode 0)
		)
		(polygon
			(pts
				(arc
					(start 33.799018 -46.746922)
					(mid 30.243018 -46.746922)
					(end 33.799018 -46.746922)
				)
			)
		)
	)
	(zone
		(net "XP12R0V_PCIE")
		(layers "In4.Cu" "In5.Cu")
		(hatch none 0.5)
		(connect_pads
			(clearance 0.5)
		)
		(min_thickness 0.25)
		(fill yes
			(thermal_gap 0.5)
			(thermal_bridge_width 0.5)
			(island_removal_mode 0)
		)
		(polygon
			(pts
				(xy 15.577312 -97.663) (xy 18.712688 -97.663) (xy 19.304 -97.071688)
				(arc
					(start 19.304 -92.202)
					(mid 19.342684 -92.007611)
					(end 19.452844 -91.842844)
				)
				(xy 22.479 -88.816688)
				(arc
					(start 22.479 -63.754)
					(mid 22.517684 -63.559611)
					(end 22.627844 -63.394844)
				)
				(xy 56.642 -29.380688)
				(arc
					(start 56.642 -10.388346)
					(mid 54.868959 -9.370584)
					(end 54.16804 -7.450074)
				)
				(xy 54.16804 -6.6548) (xy 47.03191 -6.6548)
				(arc
					(start 47.03191 -10.925048)
					(mid 45.904019 -13.650555)
					(end 43.18 -14.782038)
				)
				(arc
					(start 43.18 -28.702)
					(mid 43.141316 -28.896389)
					(end 43.031156 -29.061156)
				)
				(xy 15.24 -56.852312) (xy 15.24 -97.325688)
			)
		)
	)
	(zone
		(layers "In4.Cu" "In5.Cu")
		(hatch none 0.5)
		(connect_pads
			(clearance 0)
		)
		(min_thickness 0.25)
		(keepout
			(tracks not_allowed)
			(vias allowed)
			(pads allowed)
			(copperpour not_allowed)
			(footprints allowed)
		)
		(placement
			(enabled no)
			(sheetname "")
		)
		(fill yes
			(thermal_gap 0.5)
			(thermal_bridge_width 0.5)
			(island_removal_mode 0)
		)
		(polygon
			(pts
				(arc
					(start 68.606924 -78.650084)
					(mid 61.393324 -78.650084)
					(end 68.606924 -78.650084)
				)
			)
		)
	)
	(zone
		(layers "In4.Cu" "In5.Cu")
		(hatch none 0.5)
		(connect_pads
			(clearance 0)
		)
		(min_thickness 0.25)
		(keepout
			(tracks not_allowed)
			(vias allowed)
			(pads allowed)
			(copperpour not_allowed)
			(footprints allowed)
		)
		(placement
			(enabled no)
			(sheetname "")
		)
		(fill yes
			(thermal_gap 0.5)
			(thermal_bridge_width 0.5)
			(island_removal_mode 0)
		)
		(polygon
			(pts
				(arc
					(start 74.439018 -26.426922)
					(mid 70.883018 -26.426922)
					(end 74.439018 -26.426922)
				)
			)
		)
	)
	(zone
		(layers "In4.Cu" "In5.Cu")
		(hatch none 0.5)
		(connect_pads
			(clearance 0)
		)
		(min_thickness 0.25)
		(keepout
			(tracks not_allowed)
			(vias allowed)
			(pads allowed)
			(copperpour not_allowed)
			(footprints allowed)
		)
		(placement
			(enabled no)
			(sheetname "")
		)
		(fill yes
			(thermal_gap 0.5)
			(thermal_bridge_width 0.5)
			(island_removal_mode 0)
		)
		(polygon
			(pts
				(arc
					(start 11.005312 -94.749874)
					(mid 3.994912 -94.749874)
					(end 11.005312 -94.749874)
				)
			)
		)
	)
	(zone
		(layers "In4.Cu" "In5.Cu")
		(hatch none 0.5)
		(connect_pads
			(clearance 0)
		)
		(min_thickness 0.25)
		(keepout
			(tracks not_allowed)
			(vias allowed)
			(pads allowed)
			(copperpour not_allowed)
			(footprints allowed)
		)
		(placement
			(enabled no)
			(sheetname "")
		)
		(fill yes
			(thermal_gap 0.5)
			(thermal_bridge_width 0.5)
			(island_removal_mode 0)
		)
		(polygon
			(pts
				(arc
					(start 129.106676 -78.650084)
					(mid 121.893076 -78.650084)
					(end 129.106676 -78.650084)
				)
			)
		)
	)
	(zone
		(layers "In4.Cu" "In5.Cu")
		(hatch none 0.5)
		(connect_pads
			(clearance 0)
		)
		(min_thickness 0.25)
		(keepout
			(tracks not_allowed)
			(vias allowed)
			(pads allowed)
			(copperpour not_allowed)
			(footprints allowed)
		)
		(placement
			(enabled no)
			(sheetname "")
		)
		(fill yes
			(thermal_gap 0.5)
			(thermal_bridge_width 0.5)
			(island_removal_mode 0)
		)
		(polygon
			(pts
				(arc
					(start 129.106676 -104.650032)
					(mid 121.893076 -104.650032)
					(end 129.106676 -104.650032)
				)
			)
		)
	)
	(zone
		(layers "In4.Cu" "In5.Cu")
		(hatch none 0.5)
		(connect_pads
			(clearance 0)
		)
		(min_thickness 0.25)
		(keepout
			(tracks not_allowed)
			(vias allowed)
			(pads allowed)
			(copperpour not_allowed)
			(footprints allowed)
		)
		(placement
			(enabled no)
			(sheetname "")
		)
		(fill yes
			(thermal_gap 0.5)
			(thermal_bridge_width 0.5)
			(island_removal_mode 0)
		)
		(polygon
			(pts
				(arc
					(start 166.075106 -16.599916)
					(mid 159.064706 -16.599916)
					(end 166.075106 -16.599916)
				)
			)
		)
	)
	(zone
		(layers "In4.Cu" "In5.Cu")
		(hatch none 0.5)
		(connect_pads
			(clearance 0)
		)
		(min_thickness 0.25)
		(keepout
			(tracks not_allowed)
			(vias allowed)
			(pads allowed)
			(copperpour not_allowed)
			(footprints allowed)
		)
		(placement
			(enabled no)
			(sheetname "")
		)
		(fill yes
			(thermal_gap 0.5)
			(thermal_bridge_width 0.5)
			(island_removal_mode 0)
		)
		(polygon
			(pts
				(xy 26.5176 -96.4184) (xy 28.8036 -96.4184) (xy 28.8036 -97.8916) (xy 26.5176 -97.8916)
			)
		)
	)
	(zone
		(layers "In4.Cu" "In5.Cu")
		(hatch none 0.5)
		(connect_pads
			(clearance 0)
		)
		(min_thickness 0.25)
		(keepout
			(tracks not_allowed)
			(vias allowed)
			(pads allowed)
			(copperpour not_allowed)
			(footprints allowed)
		)
		(placement
			(enabled no)
			(sheetname "")
		)
		(fill yes
			(thermal_gap 0.5)
			(thermal_bridge_width 0.5)
			(island_removal_mode 0)
		)
		(polygon
			(pts
				(arc
					(start 166.075106 -106.13009)
					(mid 159.064706 -106.13009)
					(end 166.075106 -106.13009)
				)
			)
		)
	)
	(zone
		(net "XP3R3V_FPGA")
		(layer "In5.Cu")
		(hatch none 0.5)
		(connect_pads
			(clearance 0.5)
		)
		(min_thickness 0.25)
		(fill yes
			(thermal_gap 0.5)
			(thermal_bridge_width 0.5)
			(island_removal_mode 0)
		)
		(polygon
			(pts
				(xy 155.063444 -109.117892) (xy 163.56584 -109.117892) (xy 163.56584 -106.66476) (xy 165.617906 -106.66476)
				(arc
					(start 165.617906 -73.964546)
					(mid 164.725004 -73.041803)
					(end 164.399722 -71.799704)
				)
				(arc
					(start 164.399722 -61.324998)
					(mid 164.725179 -60.083181)
					(end 165.617906 -59.160664)
				)
				(xy 165.617906 -14.782038)
				(arc
					(start 80.300068 -14.782038)
					(mid 78.156122 -13.893986)
					(end 77.26807 -11.75004)
				)
				(xy 77.26807 -6.6548) (xy 60.13196 -6.6548)
				(arc
					(start 60.13196 -7.450074)
					(mid 59.431115 -9.370647)
					(end 57.658 -10.388346)
				)
				(arc
					(start 57.658 -29.591)
					(mid 57.619316 -29.785389)
					(end 57.509156 -29.950156)
				)
				(xy 28.448 -59.011312) (xy 28.448 -69.109844)
				(arc
					(start 35.018218 -75.680062)
					(mid 35.073324 -75.762439)
					(end 35.09264 -75.85964)
				)
				(xy 35.09264 -78.070964) (xy 35.317176 -78.2955)
				(arc
					(start 37.5285 -78.2955)
					(mid 37.625687 -78.31485)
					(end 37.708078 -78.369922)
				)
				(xy 44.682156 -85.344) (xy 79.015844 -85.344) (xy 91.186 -73.173844) (xy 91.186 -66.272156)
				(arc
					(start 89.101422 -64.187578)
					(mid 89.046316 -64.105201)
					(end 89.027 -64.008)
				)
				(arc
					(start 89.027 -55.372)
					(mid 89.04635 -55.274813)
					(end 89.101422 -55.192422)
				)
				(arc
					(start 89.863422 -54.430422)
					(mid 89.945799 -54.375316)
					(end 90.043 -54.356)
				)
				(xy 94.107 -54.356) (xy 94.107 -45.085)
				(arc
					(start 92.71 -45.085)
					(mid 92.612813 -45.06565)
					(end 92.530422 -45.010578)
				)
				(arc
					(start 91.768422 -44.248578)
					(mid 91.713316 -44.166201)
					(end 91.694 -44.069)
				)
				(arc
					(start 91.694 -35.687)
					(mid 91.71335 -35.589813)
					(end 91.768422 -35.507422)
				)
				(xy 92.456 -34.819844)
				(arc
					(start 92.456 -19.812)
					(mid 92.47535 -19.714813)
					(end 92.530422 -19.632422)
				)
				(arc
					(start 94.181422 -17.981422)
					(mid 94.263799 -17.926316)
					(end 94.361 -17.907)
				)
				(arc
					(start 139.954 -17.907)
					(mid 140.051187 -17.92635)
					(end 140.133578 -17.981422)
				)
				(arc
					(start 141.276578 -19.124422)
					(mid 141.331684 -19.206799)
					(end 141.351 -19.304)
				)
				(arc
					(start 141.351 -25.654)
					(mid 141.33165 -25.751187)
					(end 141.276578 -25.833578)
				)
				(arc
					(start 125.147578 -41.962578)
					(mid 125.065201 -42.017684)
					(end 124.968 -42.037)
				)
				(xy 114.427 -42.037)
				(arc
					(start 114.427 -43.688)
					(mid 114.40765 -43.785187)
					(end 114.352578 -43.867578)
				)
				(xy 113.792 -44.428156)
				(arc
					(start 113.792 -46.482)
					(mid 113.77265 -46.579187)
					(end 113.717578 -46.661578)
				)
				(arc
					(start 112.574578 -47.804578)
					(mid 112.492201 -47.859684)
					(end 112.395 -47.879)
				)
				(xy 106.531156 -47.879) (xy 100.33 -54.080156)
				(arc
					(start 100.33 -57.531)
					(mid 100.31065 -57.628187)
					(end 100.255578 -57.710578)
				)
				(xy 99.419156 -58.547)
				(arc
					(start 103.684578 -62.812422)
					(mid 103.739684 -62.894799)
					(end 103.759 -62.992)
				)
				(xy 103.759 -75.078844) (xy 105.896156 -77.216) (xy 117.115844 -77.216) (xy 123.063 -71.268844)
				(arc
					(start 123.063 -62.611)
					(mid 123.08235 -62.513813)
					(end 123.137422 -62.431422)
				)
				(arc
					(start 123.899422 -61.669422)
					(mid 123.981799 -61.614316)
					(end 124.079 -61.595)
				)
				(xy 133.985 -61.595)
				(arc
					(start 133.985 -58.801)
					(mid 134.023684 -58.606611)
					(end 134.133844 -58.441844)
				)
				(arc
					(start 135.149844 -57.425844)
					(mid 135.314612 -57.315686)
					(end 135.509 -57.277)
				)
				(arc
					(start 145.034 -57.277)
					(mid 145.228389 -57.315684)
					(end 145.393156 -57.425844)
				)
				(arc
					(start 147.425156 -59.457844)
					(mid 147.535314 -59.622612)
					(end 147.574 -59.817)
				)
				(xy 147.574 -78.148688) (xy 149.943312 -80.518)
				(arc
					(start 153.67 -80.518)
					(mid 153.864389 -80.556684)
					(end 154.029156 -80.666844)
				)
				(arc
					(start 156.188156 -82.825844)
					(mid 156.298314 -82.990612)
					(end 156.337 -83.185)
				)
				(arc
					(start 156.337 -97.409)
					(mid 156.298316 -97.603389)
					(end 156.188156 -97.768156)
				)
				(xy 154.432 -99.524312) (xy 154.432 -108.486448)
			)
		)
	)
	(zone
		(net "XP1R8V_FPGA")
		(layer "In5.Cu")
		(hatch none 0.5)
		(connect_pads
			(clearance 0.5)
		)
		(min_thickness 0.25)
		(fill yes
			(thermal_gap 0.5)
			(thermal_bridge_width 0.5)
			(island_removal_mode 0)
		)
		(polygon
			(pts
				(xy 48.724312 -95.377) (xy 131.869688 -95.377) (xy 133.985 -93.261688) (xy 133.985 -62.103) (xy 124.184156 -62.103)
				(xy 123.571 -62.716156)
				(arc
					(start 123.571 -71.374)
					(mid 123.55165 -71.471187)
					(end 123.496578 -71.553578)
				)
				(arc
					(start 117.400578 -77.649578)
					(mid 117.318201 -77.704684)
					(end 117.221 -77.724)
				)
				(arc
					(start 105.791 -77.724)
					(mid 105.693813 -77.70465)
					(end 105.611422 -77.649578)
				)
				(arc
					(start 103.325422 -75.363578)
					(mid 103.270316 -75.281201)
					(end 103.251 -75.184)
				)
				(xy 103.251 -63.097156) (xy 98.954844 -58.801)
				(arc
					(start 94.742 -58.801)
					(mid 94.644813 -58.78165)
					(end 94.562422 -58.726578)
				)
				(arc
					(start 94.181422 -58.345578)
					(mid 94.126316 -58.263201)
					(end 94.107 -58.166)
				)
				(xy 94.107 -54.864) (xy 90.148156 -54.864) (xy 89.535 -55.477156) (xy 89.535 -63.902844)
				(arc
					(start 91.619578 -65.987422)
					(mid 91.674684 -66.069799)
					(end 91.694 -66.167)
				)
				(arc
					(start 91.694 -73.279)
					(mid 91.67465 -73.376187)
					(end 91.619578 -73.458578)
				)
				(arc
					(start 79.300578 -85.777578)
					(mid 79.218201 -85.832684)
					(end 79.121 -85.852)
				)
				(arc
					(start 44.577 -85.852)
					(mid 44.479813 -85.83265)
					(end 44.397422 -85.777578)
				)
				(xy 37.423344 -78.8035)
				(arc
					(start 35.21202 -78.8035)
					(mid 35.114833 -78.78415)
					(end 35.032442 -78.729078)
				)
				(arc
					(start 34.659062 -78.355698)
					(mid 34.603956 -78.273321)
					(end 34.58464 -78.17612)
				)
				(xy 34.58464 -75.964796)
				(arc
					(start 28.014422 -69.394578)
					(mid 27.959316 -69.312201)
					(end 27.94 -69.215)
				)
				(arc
					(start 27.94 -60.417964)
					(mid 27.912377 -60.399506)
					(end 27.887422 -60.377578)
				)
				(xy 27.707844 -60.198) (xy 27.261312 -60.198) (xy 23.495 -63.964312) (xy 23.495 -88.816688) (xy 24.721312 -90.043)
				(arc
					(start 31.75 -90.043)
					(mid 31.944389 -90.081684)
					(end 32.109156 -90.191844)
				)
				(xy 34.373312 -92.456)
				(arc
					(start 45.593 -92.456)
					(mid 45.787389 -92.494684)
					(end 45.952156 -92.604844)
				)
			)
		)
	)
	(zone
		(net "XP3R3V_FPGA")
		(layer "In5.Cu")
		(hatch none 0.5)
		(connect_pads
			(clearance 0.5)
		)
		(min_thickness 0.25)
		(fill yes
			(thermal_gap 0.5)
			(thermal_bridge_width 0.5)
			(island_removal_mode 0)
		)
		(polygon
			(pts
				(xy 2.032 -109.117892) (xy 12.736576 -109.117892) (xy 13.335 -108.519468)
				(arc
					(start 13.335 -98.425)
					(mid 13.373684 -98.230611)
					(end 13.483844 -98.065844)
				)
				(xy 14.224 -97.325688)
				(arc
					(start 14.224 -56.642)
					(mid 14.262684 -56.447611)
					(end 14.372844 -56.282844)
				)
				(xy 42.164 -28.491688)
				(arc
					(start 42.164 -14.647164)
					(mid 40.111003 -13.267806)
					(end 39.31793 -10.925048)
				)
				(xy 39.31793 -6.532118) (xy 35.381946 -6.532118)
				(arc
					(start 35.381946 -11.75004)
					(mid 34.493894 -13.893986)
					(end 32.349948 -14.782038)
				)
				(arc
					(start 15.999968 -14.782038)
					(mid 13.856022 -13.893986)
					(end 12.96797 -11.75004)
				)
				(xy 12.96797 -6.532118) (xy 2.032 -6.532118)
			)
		)
	)
	(zone
		(net "FPGA_MGTAVTT")
		(layer "In5.Cu")
		(hatch none 0.5)
		(connect_pads
			(clearance 0.5)
		)
		(min_thickness 0.25)
		(fill yes
			(thermal_gap 0.5)
			(thermal_bridge_width 0.5)
			(island_removal_mode 0)
		)
		(polygon
			(pts
				(xy 92.815156 -44.577) (xy 100.351844 -44.577) (xy 100.711 -44.217844) (xy 100.711 -36.173156) (xy 99.716844 -35.179)
				(xy 92.815156 -35.179) (xy 92.202 -35.792156) (xy 92.202 -43.963844)
			)
		)
	)
	(zone
		(net "XP12R0V_EXT")
		(layer "In5.Cu")
		(hatch none 0.5)
		(connect_pads
			(clearance 0.5)
		)
		(min_thickness 0.25)
		(fill yes
			(thermal_gap 0.5)
			(thermal_bridge_width 0.5)
			(island_removal_mode 0)
		)
		(polygon
			(pts
				(xy 82.056732 -99.43846) (xy 116.886228 -99.43846)
				(arc
					(start 118.131844 -98.192844)
					(mid 118.296612 -98.082686)
					(end 118.491 -98.044)
				)
				(xy 134.409688 -98.044) (xy 138.557 -93.896688)
				(arc
					(start 138.557 -81.407)
					(mid 138.595684 -81.212611)
					(end 138.705844 -81.047844)
				)
				(arc
					(start 139.848844 -79.904844)
					(mid 140.013612 -79.794686)
					(end 140.208 -79.756)
				)
				(arc
					(start 143.256 -79.756)
					(mid 143.450389 -79.794684)
					(end 143.615156 -79.904844)
				)
				(arc
					(start 144.631156 -80.920844)
					(mid 144.741314 -81.085612)
					(end 144.78 -81.28)
				)
				(xy 144.78 -82.339688)
				(arc
					(start 147.679156 -85.238844)
					(mid 147.789314 -85.403612)
					(end 147.828 -85.598)
				)
				(xy 147.828 -94.785688) (xy 151.848312 -98.806) (xy 153.713688 -98.806) (xy 155.321 -97.198688)
				(xy 155.321 -83.395312) (xy 153.459688 -81.534)
				(arc
					(start 149.733 -81.534)
					(mid 149.538611 -81.495316)
					(end 149.373844 -81.385156)
				)
				(arc
					(start 146.706844 -78.718156)
					(mid 146.596686 -78.553388)
					(end 146.558 -78.359)
				)
				(xy 146.558 -60.027312) (xy 144.823688 -58.293) (xy 135.719312 -58.293) (xy 135.001 -59.011312)
				(arc
					(start 135.001 -93.472)
					(mid 134.962316 -93.666389)
					(end 134.852156 -93.831156)
				)
				(arc
					(start 132.439156 -96.244156)
					(mid 132.274388 -96.354314)
					(end 132.08 -96.393)
				)
				(arc
					(start 48.514 -96.393)
					(mid 48.319611 -96.354316)
					(end 48.154844 -96.244156)
				)
				(xy 45.382688 -93.472)
				(arc
					(start 34.163 -93.472)
					(mid 33.968611 -93.433316)
					(end 33.803844 -93.323156)
				)
				(xy 31.539688 -91.059)
				(arc
					(start 24.511 -91.059)
					(mid 24.316611 -91.020316)
					(end 24.151844 -90.910156)
				)
				(xy 22.987 -89.745312) (xy 20.32 -92.412312)
				(arc
					(start 20.32 -97.282)
					(mid 20.281316 -97.476389)
					(end 20.171156 -97.641156)
				)
				(xy 20.149312 -97.663)
				(arc
					(start 42.58818 -97.663)
					(mid 42.782569 -97.701684)
					(end 42.947336 -97.811844)
				)
				(xy 43.555412 -98.41992)
				(arc
					(start 80.82788 -98.41992)
					(mid 81.022269 -98.458604)
					(end 81.187036 -98.568764)
				)
			)
		)
	)
	(zone
		(net "XP2R5V_FPGA")
		(layer "In5.Cu")
		(hatch none 0.5)
		(connect_pads
			(clearance 0.5)
		)
		(min_thickness 0.25)
		(fill yes
			(thermal_gap 0.5)
			(thermal_bridge_width 0.5)
			(island_removal_mode 0)
		)
		(polygon
			(pts
				(xy 101.219 -41.529) (xy 124.862844 -41.529) (xy 140.843 -25.548844) (xy 140.843 -19.409156) (xy 139.848844 -18.415)
				(xy 94.466156 -18.415) (xy 92.964 -19.917156) (xy 92.964 -34.671)
				(arc
					(start 99.822 -34.671)
					(mid 99.919187 -34.69035)
					(end 100.001578 -34.745422)
				)
				(arc
					(start 101.144578 -35.888422)
					(mid 101.199684 -35.970799)
					(end 101.219 -36.068)
				)
			)
		)
	)
	(zone
		(net "XP1R8V_FPGA_VCCAUX")
		(layer "In5.Cu")
		(hatch none 0.5)
		(connect_pads
			(clearance 0.5)
		)
		(min_thickness 0.25)
		(fill yes
			(thermal_gap 0.5)
			(thermal_bridge_width 0.5)
			(island_removal_mode 0)
		)
		(polygon
			(pts
				(xy 94.847156 -58.293) (xy 98.954844 -58.293) (xy 99.822 -57.425844)
				(arc
					(start 99.822 -53.975)
					(mid 99.84135 -53.877813)
					(end 99.896422 -53.795422)
				)
				(arc
					(start 106.246422 -47.445422)
					(mid 106.328799 -47.390316)
					(end 106.426 -47.371)
				)
				(xy 112.289844 -47.371) (xy 113.284 -46.376844)
				(arc
					(start 113.284 -44.323)
					(mid 113.30335 -44.225813)
					(end 113.358422 -44.143422)
				)
				(xy 113.919 -43.582844) (xy 113.919 -42.037) (xy 101.219 -42.037)
				(arc
					(start 101.219 -44.323)
					(mid 101.19965 -44.420187)
					(end 101.144578 -44.502578)
				)
				(arc
					(start 100.636578 -45.010578)
					(mid 100.554201 -45.065684)
					(end 100.457 -45.085)
				)
				(xy 94.615 -45.085) (xy 94.615 -58.060844)
			)
		)
	)
	(zone
		(net "XP12R0V_IN")
		(layer "In5.Cu")
		(hatch none 0.5)
		(connect_pads
			(clearance 0.5)
		)
		(min_thickness 0.25)
		(fill yes
			(thermal_gap 0.5)
			(thermal_bridge_width 0.5)
			(island_removal_mode 0)
		)
		(polygon
			(pts
				(xy 14.924024 -109.117892) (xy 152.860756 -109.117892) (xy 153.416 -108.562648) (xy 153.416 -99.822)
				(arc
					(start 151.638 -99.822)
					(mid 151.443611 -99.783316)
					(end 151.278844 -99.673156)
				)
				(arc
					(start 146.960844 -95.355156)
					(mid 146.850686 -95.190388)
					(end 146.812 -94.996)
				)
				(xy 146.812 -85.808312)
				(arc
					(start 143.912844 -82.909156)
					(mid 143.802686 -82.744388)
					(end 143.764 -82.55)
				)
				(xy 143.764 -81.490312) (xy 143.045688 -80.772) (xy 140.418312 -80.772) (xy 139.573 -81.617312)
				(arc
					(start 139.573 -94.107)
					(mid 139.534316 -94.301389)
					(end 139.424156 -94.466156)
				)
				(arc
					(start 134.979156 -98.911156)
					(mid 134.814388 -99.021314)
					(end 134.62 -99.06)
				)
				(xy 118.701312 -99.06)
				(arc
					(start 117.455696 -100.305616)
					(mid 117.290928 -100.415774)
					(end 117.09654 -100.45446)
				)
				(arc
					(start 81.84642 -100.45446)
					(mid 81.652031 -100.415776)
					(end 81.487264 -100.305616)
				)
				(xy 80.617568 -99.43592)
				(arc
					(start 43.3451 -99.43592)
					(mid 43.150711 -99.397236)
					(end 42.985944 -99.287076)
				)
				(xy 42.377868 -98.679)
				(arc
					(start 15.367 -98.679)
					(mid 15.172611 -98.640316)
					(end 15.007844 -98.530156)
				)
				(xy 14.732 -98.254312) (xy 14.351 -98.635312) (xy 14.351 -108.544868)
			)
		)
	)
	(zone
		(layer "In7.Cu")
		(hatch none 0.5)
		(connect_pads
			(clearance 0)
		)
		(min_thickness 0.25)
		(keepout
			(tracks allowed)
			(vias allowed)
			(pads allowed)
			(copperpour allowed)
			(footprints allowed)
		)
		(placement
			(enabled no)
			(sheetname "")
		)
		(fill
			(thermal_gap 0.5)
			(thermal_bridge_width 0.5)
			(island_removal_mode 0)
		)
		(polygon
			(pts
				(xy 99.441 -63.881) (xy 97.028 -63.881) (xy 95.504 -63.881) (xy 94.996 -63.373) (xy 94.996 -60.071)
				(xy 96.393 -58.674) (xy 104.775 -58.674) (xy 106.934 -56.515) (xy 109.093 -56.515) (xy 117.856 -56.515)
				(xy 118.491 -57.15) (xy 118.491 -59.563) (xy 118.11 -59.944) (xy 111.379 -59.944) (xy 109.22 -62.103)
				(xy 107.442 -63.881)
			)
		)
	)
	(zone
		(layer "In7.Cu")
		(hatch none 0.5)
		(connect_pads
			(clearance 0)
		)
		(min_thickness 0.25)
		(keepout
			(tracks not_allowed)
			(vias allowed)
			(pads allowed)
			(copperpour not_allowed)
			(footprints allowed)
		)
		(placement
			(enabled no)
			(sheetname "")
		)
		(fill
			(thermal_gap 0.5)
			(thermal_bridge_width 0.5)
			(island_removal_mode 0)
		)
		(polygon
			(pts
				(xy 68.480178 -14.478) (xy 69.089778 -14.478) (xy 69.089778 -15.1892) (xy 68.480178 -15.1892)
			)
		)
	)
	(zone
		(layer "In7.Cu")
		(hatch none 0.5)
		(connect_pads
			(clearance 0)
		)
		(min_thickness 0.25)
		(keepout
			(tracks not_allowed)
			(vias allowed)
			(pads allowed)
			(copperpour not_allowed)
			(footprints allowed)
		)
		(placement
			(enabled no)
			(sheetname "")
		)
		(fill
			(thermal_gap 0.5)
			(thermal_bridge_width 0.5)
			(island_removal_mode 0)
		)
		(polygon
			(pts
				(xy 62.210188 -15.5448) (xy 62.819788 -15.5448) (xy 62.819788 -16.256) (xy 62.210188 -16.256)
			)
		)
	)
	(zone
		(layer "In7.Cu")
		(hatch none 0.5)
		(connect_pads
			(clearance 0)
		)
		(min_thickness 0.25)
		(keepout
			(tracks not_allowed)
			(vias allowed)
			(pads allowed)
			(copperpour not_allowed)
			(footprints allowed)
		)
		(placement
			(enabled no)
			(sheetname "")
		)
		(fill
			(thermal_gap 0.5)
			(thermal_bridge_width 0.5)
			(island_removal_mode 0)
		)
		(polygon
			(pts
				(xy 70.82917 -14.478) (xy 71.43877 -14.478) (xy 71.43877 -15.1892) (xy 70.82917 -15.1892)
			)
		)
	)
	(zone
		(layer "In7.Cu")
		(hatch none 0.5)
		(connect_pads
			(clearance 0)
		)
		(min_thickness 0.25)
		(keepout
			(tracks not_allowed)
			(vias allowed)
			(pads allowed)
			(copperpour not_allowed)
			(footprints allowed)
		)
		(placement
			(enabled no)
			(sheetname "")
		)
		(fill
			(thermal_gap 0.5)
			(thermal_bridge_width 0.5)
			(island_removal_mode 0)
		)
		(polygon
			(pts
				(xy 72.09917 -15.5448) (xy 72.70877 -15.5448) (xy 72.70877 -16.256) (xy 72.09917 -16.256)
			)
		)
	)
	(zone
		(layer "In7.Cu")
		(hatch none 0.5)
		(connect_pads
			(clearance 0)
		)
		(min_thickness 0.25)
		(keepout
			(tracks not_allowed)
			(vias allowed)
			(pads allowed)
			(copperpour not_allowed)
			(footprints allowed)
		)
		(placement
			(enabled no)
			(sheetname "")
		)
		(fill
			(thermal_gap 0.5)
			(thermal_bridge_width 0.5)
			(island_removal_mode 0)
		)
		(polygon
			(pts
				(xy 75.210162 -14.478) (xy 75.819762 -14.478) (xy 75.819762 -15.1892) (xy 75.210162 -15.1892)
			)
		)
	)
	(zone
		(layer "In7.Cu")
		(hatch none 0.5)
		(connect_pads
			(clearance 0)
		)
		(min_thickness 0.25)
		(keepout
			(tracks not_allowed)
			(vias allowed)
			(pads allowed)
			(copperpour not_allowed)
			(footprints allowed)
		)
		(placement
			(enabled no)
			(sheetname "")
		)
		(fill
			(thermal_gap 0.5)
			(thermal_bridge_width 0.5)
			(island_removal_mode 0)
		)
		(polygon
			(pts
				(xy 90.4494 -48.755046) (xy 91.1606 -48.755046) (xy 91.1606 -49.364646) (xy 90.4494 -49.364646)
			)
		)
	)
	(zone
		(layer "In7.Cu")
		(hatch none 0.5)
		(connect_pads
			(clearance 0)
		)
		(min_thickness 0.25)
		(keepout
			(tracks not_allowed)
			(vias allowed)
			(pads allowed)
			(copperpour not_allowed)
			(footprints allowed)
		)
		(placement
			(enabled no)
			(sheetname "")
		)
		(fill
			(thermal_gap 0.5)
			(thermal_bridge_width 0.5)
			(island_removal_mode 0)
		)
		(polygon
			(pts
				(xy 89.3826 -48.755046) (xy 90.0938 -48.755046) (xy 90.0938 -49.364646) (xy 89.3826 -49.364646)
			)
		)
	)
	(zone
		(layer "In7.Cu")
		(hatch none 0.5)
		(connect_pads
			(clearance 0)
		)
		(min_thickness 0.25)
		(keepout
			(tracks not_allowed)
			(vias allowed)
			(pads allowed)
			(copperpour not_allowed)
			(footprints allowed)
		)
		(placement
			(enabled no)
			(sheetname "")
		)
		(fill
			(thermal_gap 0.5)
			(thermal_bridge_width 0.5)
			(island_removal_mode 0)
		)
		(polygon
			(pts
				(xy 90.4494 -47.612046) (xy 91.1606 -47.612046) (xy 91.1606 -48.221646) (xy 90.4494 -48.221646)
			)
		)
	)
	(zone
		(net "XP3R3V_AGND")
		(layer "In7.Cu")
		(hatch none 0.5)
		(connect_pads
			(clearance 0.5)
		)
		(min_thickness 0.25)
		(fill yes
			(thermal_gap 0.5)
			(thermal_bridge_width 0.5)
			(island_removal_mode 0)
		)
		(polygon
			(pts
				(xy 91.637866 -101.333046) (xy 87.107522 -101.333046) (xy 86.184994 -100.410518) (xy 86.184994 -98.190558)
				(xy 87.89924 -96.476312) (xy 88.903556 -96.476312) (xy 91.882722 -99.455478) (xy 91.882722 -101.08819)
			)
		)
	)
	(zone
		(layer "In7.Cu")
		(hatch none 0.5)
		(connect_pads
			(clearance 0)
		)
		(min_thickness 0.25)
		(keepout
			(tracks not_allowed)
			(vias allowed)
			(pads allowed)
			(copperpour not_allowed)
			(footprints allowed)
		)
		(placement
			(enabled no)
			(sheetname "")
		)
		(fill
			(thermal_gap 0.5)
			(thermal_bridge_width 0.5)
			(island_removal_mode 0)
		)
		(polygon
			(pts
				(xy 68.480178 -15.5448) (xy 69.089778 -15.5448) (xy 69.089778 -16.256) (xy 68.480178 -16.256)
			)
		)
	)
	(zone
		(layer "In7.Cu")
		(hatch none 0.5)
		(connect_pads
			(clearance 0)
		)
		(min_thickness 0.25)
		(keepout
			(tracks not_allowed)
			(vias allowed)
			(pads allowed)
			(copperpour not_allowed)
			(footprints allowed)
		)
		(placement
			(enabled no)
			(sheetname "")
		)
		(fill
			(thermal_gap 0.5)
			(thermal_bridge_width 0.5)
			(island_removal_mode 0)
		)
		(polygon
			(pts
				(xy 67.210178 -15.5448) (xy 67.819778 -15.5448) (xy 67.819778 -16.256) (xy 67.210178 -16.256)
			)
		)
	)
	(zone
		(layer "In7.Cu")
		(hatch none 0.5)
		(connect_pads
			(clearance 0)
		)
		(min_thickness 0.25)
		(keepout
			(tracks not_allowed)
			(vias allowed)
			(pads allowed)
			(copperpour not_allowed)
			(footprints allowed)
		)
		(placement
			(enabled no)
			(sheetname "")
		)
		(fill
			(thermal_gap 0.5)
			(thermal_bridge_width 0.5)
			(island_removal_mode 0)
		)
		(polygon
			(pts
				(xy 67.210178 -14.478) (xy 67.819778 -14.478) (xy 67.819778 -15.1892) (xy 67.210178 -15.1892)
			)
		)
	)
	(zone
		(layer "In7.Cu")
		(hatch none 0.5)
		(connect_pads
			(clearance 0)
		)
		(min_thickness 0.25)
		(keepout
			(tracks not_allowed)
			(vias allowed)
			(pads allowed)
			(copperpour not_allowed)
			(footprints allowed)
		)
		(placement
			(enabled no)
			(sheetname "")
		)
		(fill
			(thermal_gap 0.5)
			(thermal_bridge_width 0.5)
			(island_removal_mode 0)
		)
		(polygon
			(pts
				(xy 59.210194 -15.5448) (xy 59.819794 -15.5448) (xy 59.819794 -16.256) (xy 59.210194 -16.256)
			)
		)
	)
	(zone
		(net "XP5R0V_AGND")
		(layer "In7.Cu")
		(hatch none 0.5)
		(connect_pads
			(clearance 0.5)
		)
		(min_thickness 0.25)
		(fill yes
			(thermal_gap 0.5)
			(thermal_bridge_width 0.5)
			(island_removal_mode 0)
		)
		(polygon
			(pts
				(xy 36.195 -106.553) (xy 39.751 -106.553) (xy 40.64 -105.664) (xy 40.64 -101.6) (xy 40.132 -101.092)
				(xy 35.56 -101.092) (xy 35.179 -101.473) (xy 35.179 -105.537)
			)
		)
	)
	(zone
		(layer "In7.Cu")
		(hatch none 0.5)
		(connect_pads
			(clearance 0)
		)
		(min_thickness 0.25)
		(keepout
			(tracks not_allowed)
			(vias allowed)
			(pads allowed)
			(copperpour not_allowed)
			(footprints allowed)
		)
		(placement
			(enabled no)
			(sheetname "")
		)
		(fill
			(thermal_gap 0.5)
			(thermal_bridge_width 0.5)
			(island_removal_mode 0)
		)
		(polygon
			(pts
				(xy 76.480162 -14.478) (xy 77.089762 -14.478) (xy 77.089762 -15.1892) (xy 76.480162 -15.1892)
			)
		)
	)
	(zone
		(layer "In7.Cu")
		(hatch none 0.5)
		(connect_pads
			(clearance 0)
		)
		(min_thickness 0.25)
		(keepout
			(tracks not_allowed)
			(vias allowed)
			(pads allowed)
			(copperpour not_allowed)
			(footprints allowed)
		)
		(placement
			(enabled no)
			(sheetname "")
		)
		(fill
			(thermal_gap 0.5)
			(thermal_bridge_width 0.5)
			(island_removal_mode 0)
		)
		(polygon
			(pts
				(xy 60.480194 -14.478) (xy 61.089794 -14.478) (xy 61.089794 -15.1892) (xy 60.480194 -15.1892)
			)
		)
	)
	(zone
		(layer "In7.Cu")
		(hatch none 0.5)
		(connect_pads
			(clearance 0)
		)
		(min_thickness 0.25)
		(keepout
			(tracks not_allowed)
			(vias allowed)
			(pads allowed)
			(copperpour not_allowed)
			(footprints allowed)
		)
		(placement
			(enabled no)
			(sheetname "")
		)
		(fill
			(thermal_gap 0.5)
			(thermal_bridge_width 0.5)
			(island_removal_mode 0)
		)
		(polygon
			(pts
				(xy 70.82917 -15.5448) (xy 71.43877 -15.5448) (xy 71.43877 -16.256) (xy 70.82917 -16.256)
			)
		)
	)
	(zone
		(net "XP3R3V_FPGA")
		(layer "In7.Cu")
		(hatch none 0.5)
		(connect_pads
			(clearance 0.5)
		)
		(min_thickness 0.25)
		(fill yes
			(thermal_gap 0.5)
			(thermal_bridge_width 0.5)
			(island_removal_mode 0)
		)
		(polygon
			(pts
				(xy 40.513 -17.78) (xy 41.021 -17.78) (xy 44.196 -20.955) (xy 51.181 -20.955) (xy 51.943 -21.717)
				(xy 54.229 -21.717) (xy 57.531 -18.415) (xy 58.166 -18.415) (xy 58.674 -18.923) (xy 58.674 -21.59)
				(xy 56.896 -23.368) (xy 43.307 -23.368) (xy 40.386 -20.447) (xy 40.386 -17.907)
			)
		)
	)
	(zone
		(layer "In7.Cu")
		(hatch none 0.5)
		(connect_pads
			(clearance 0)
		)
		(min_thickness 0.25)
		(keepout
			(tracks not_allowed)
			(vias allowed)
			(pads allowed)
			(copperpour not_allowed)
			(footprints allowed)
		)
		(placement
			(enabled no)
			(sheetname "")
		)
		(fill
			(thermal_gap 0.5)
			(thermal_bridge_width 0.5)
			(island_removal_mode 0)
		)
		(polygon
			(pts
				(xy 76.480162 -15.5448) (xy 77.089762 -15.5448) (xy 77.089762 -16.256) (xy 76.480162 -16.256)
			)
		)
	)
	(zone
		(layer "In7.Cu")
		(hatch none 0.5)
		(connect_pads
			(clearance 0)
		)
		(min_thickness 0.25)
		(keepout
			(tracks not_allowed)
			(vias allowed)
			(pads allowed)
			(copperpour not_allowed)
			(footprints allowed)
		)
		(placement
			(enabled no)
			(sheetname "")
		)
		(fill
			(thermal_gap 0.5)
			(thermal_bridge_width 0.5)
			(island_removal_mode 0)
		)
		(polygon
			(pts
				(xy 89.3826 -47.612046) (xy 90.0938 -47.612046) (xy 90.0938 -48.221646) (xy 89.3826 -48.221646)
			)
		)
	)
	(zone
		(layer "In7.Cu")
		(hatch none 0.5)
		(connect_pads
			(clearance 0)
		)
		(min_thickness 0.25)
		(keepout
			(tracks not_allowed)
			(vias allowed)
			(pads allowed)
			(copperpour not_allowed)
			(footprints allowed)
		)
		(placement
			(enabled no)
			(sheetname "")
		)
		(fill
			(thermal_gap 0.5)
			(thermal_bridge_width 0.5)
			(island_removal_mode 0)
		)
		(polygon
			(pts
				(xy 63.480188 -14.478) (xy 64.089788 -14.478) (xy 64.089788 -15.1892) (xy 63.480188 -15.1892)
			)
		)
	)
	(zone
		(layer "In7.Cu")
		(hatch none 0.5)
		(connect_pads
			(clearance 0)
		)
		(min_thickness 0.25)
		(keepout
			(tracks not_allowed)
			(vias allowed)
			(pads allowed)
			(copperpour not_allowed)
			(footprints allowed)
		)
		(placement
			(enabled no)
			(sheetname "")
		)
		(fill
			(thermal_gap 0.5)
			(thermal_bridge_width 0.5)
			(island_removal_mode 0)
		)
		(polygon
			(pts
				(xy 72.09917 -14.478) (xy 72.70877 -14.478) (xy 72.70877 -15.1892) (xy 72.09917 -15.1892)
			)
		)
	)
	(zone
		(layer "In7.Cu")
		(hatch none 0.5)
		(connect_pads
			(clearance 0)
		)
		(min_thickness 0.25)
		(keepout
			(tracks not_allowed)
			(vias allowed)
			(pads allowed)
			(copperpour not_allowed)
			(footprints allowed)
		)
		(placement
			(enabled no)
			(sheetname "")
		)
		(fill
			(thermal_gap 0.5)
			(thermal_bridge_width 0.5)
			(island_removal_mode 0)
		)
		(polygon
			(pts
				(xy 60.480194 -15.5448) (xy 61.089794 -15.5448) (xy 61.089794 -16.256) (xy 60.480194 -16.256)
			)
		)
	)
	(zone
		(layer "In7.Cu")
		(hatch none 0.5)
		(connect_pads
			(clearance 0)
		)
		(min_thickness 0.25)
		(keepout
			(tracks not_allowed)
			(vias allowed)
			(pads allowed)
			(copperpour not_allowed)
			(footprints allowed)
		)
		(placement
			(enabled no)
			(sheetname "")
		)
		(fill
			(thermal_gap 0.5)
			(thermal_bridge_width 0.5)
			(island_removal_mode 0)
		)
		(polygon
			(pts
				(xy 62.210188 -14.478) (xy 62.819788 -14.478) (xy 62.819788 -15.1892) (xy 62.210188 -15.1892)
			)
		)
	)
	(zone
		(net "XP5R0V_FT4232")
		(layer "In7.Cu")
		(hatch none 0.5)
		(connect_pads
			(clearance 0.5)
		)
		(min_thickness 0.25)
		(fill yes
			(thermal_gap 0.5)
			(thermal_bridge_width 0.5)
			(island_removal_mode 0)
		)
		(polygon
			(pts
				(xy 10.414 -88.646) (xy 11.938 -88.646) (xy 13.208 -89.916) (xy 13.208 -90.297) (xy 16.256 -90.297)
				(xy 17.78 -88.773) (xy 19.177 -88.773) (xy 25.781 -88.773) (xy 25.781 -90.678) (xy 30.099 -94.996)
				(xy 35.941 -94.996) (xy 37.846 -93.091) (xy 37.846 -90.805) (xy 41.402 -87.249) (xy 41.402 -86.106)
				(xy 41.402 -80.518) (xy 39.497 -78.613) (xy 33.909 -78.613) (xy 33.02 -79.502) (xy 21.209 -79.502)
				(xy 20.193 -78.486) (xy 13.589 -78.486) (xy 11.43 -80.645) (xy 9.906 -80.645) (xy 7.747 -82.804)
				(xy 7.239 -82.804) (xy 6.35 -83.693) (xy 6.35 -86.995) (xy 6.731 -87.376) (xy 6.858 -87.376) (xy 6.858 -88.011)
				(xy 8.128 -89.281) (xy 9.779 -89.281)
			)
		)
	)
	(zone
		(layer "In7.Cu")
		(hatch none 0.5)
		(connect_pads
			(clearance 0)
		)
		(min_thickness 0.25)
		(keepout
			(tracks not_allowed)
			(vias allowed)
			(pads allowed)
			(copperpour not_allowed)
			(footprints allowed)
		)
		(placement
			(enabled no)
			(sheetname "")
		)
		(fill
			(thermal_gap 0.5)
			(thermal_bridge_width 0.5)
			(island_removal_mode 0)
		)
		(polygon
			(pts
				(xy 63.480188 -15.5448) (xy 64.089788 -15.5448) (xy 64.089788 -16.256) (xy 63.480188 -16.256)
			)
		)
	)
	(zone
		(layer "In7.Cu")
		(hatch none 0.5)
		(connect_pads
			(clearance 0)
		)
		(min_thickness 0.25)
		(keepout
			(tracks not_allowed)
			(vias allowed)
			(pads allowed)
			(copperpour not_allowed)
			(footprints allowed)
		)
		(placement
			(enabled no)
			(sheetname "")
		)
		(fill
			(thermal_gap 0.5)
			(thermal_bridge_width 0.5)
			(island_removal_mode 0)
		)
		(polygon
			(pts
				(xy 75.210162 -15.5448) (xy 75.819762 -15.5448) (xy 75.819762 -16.256) (xy 75.210162 -16.256)
			)
		)
	)
	(zone
		(layer "In7.Cu")
		(hatch none 0.5)
		(connect_pads
			(clearance 0)
		)
		(min_thickness 0.25)
		(keepout
			(tracks not_allowed)
			(vias allowed)
			(pads allowed)
			(copperpour not_allowed)
			(footprints allowed)
		)
		(placement
			(enabled no)
			(sheetname "")
		)
		(fill
			(thermal_gap 0.5)
			(thermal_bridge_width 0.5)
			(island_removal_mode 0)
		)
		(polygon
			(pts
				(xy 59.210194 -14.478) (xy 59.819794 -14.478) (xy 59.819794 -15.1892) (xy 59.210194 -15.1892)
			)
		)
	)
	(zone
		(layers "In7.Cu" "In8.Cu")
		(hatch none 0.5)
		(connect_pads
			(clearance 0)
		)
		(min_thickness 0.25)
		(keepout
			(tracks not_allowed)
			(vias allowed)
			(pads allowed)
			(copperpour not_allowed)
			(footprints allowed)
		)
		(placement
			(enabled no)
			(sheetname "")
		)
		(fill yes
			(thermal_gap 0.5)
			(thermal_bridge_width 0.5)
			(island_removal_mode 0)
		)
		(polygon
			(pts
				(xy 70.6882 -47.3964) (xy 71.2978 -47.3964) (xy 71.2978 -48.1076) (xy 70.6882 -48.1076)
			)
		)
	)
	(zone
		(layers "In7.Cu" "In8.Cu")
		(hatch none 0.5)
		(connect_pads
			(clearance 0)
		)
		(min_thickness 0.25)
		(keepout
			(tracks not_allowed)
			(vias allowed)
			(pads allowed)
			(copperpour not_allowed)
			(footprints allowed)
		)
		(placement
			(enabled no)
			(sheetname "")
		)
		(fill yes
			(thermal_gap 0.5)
			(thermal_bridge_width 0.5)
			(island_removal_mode 0)
		)
		(polygon
			(pts
				(xy 72.4535 -49.0982) (xy 72.4535 -49.7078) (xy 71.7423 -49.7078) (xy 71.7423 -49.0982)
			)
		)
	)
	(zone
		(layers "In7.Cu" "In8.Cu")
		(hatch none 0.5)
		(connect_pads
			(clearance 0)
		)
		(min_thickness 0.25)
		(keepout
			(tracks not_allowed)
			(vias allowed)
			(pads allowed)
			(copperpour not_allowed)
			(footprints allowed)
		)
		(placement
			(enabled no)
			(sheetname "")
		)
		(fill yes
			(thermal_gap 0.5)
			(thermal_bridge_width 0.5)
			(island_removal_mode 0)
		)
		(polygon
			(pts
				(xy 70.6882 -46.3296) (xy 71.2978 -46.3296) (xy 71.2978 -47.0408) (xy 70.6882 -47.0408)
			)
		)
	)
	(zone
		(layers "In7.Cu" "In8.Cu")
		(hatch none 0.5)
		(connect_pads
			(clearance 0)
		)
		(min_thickness 0.25)
		(keepout
			(tracks not_allowed)
			(vias allowed)
			(pads allowed)
			(copperpour not_allowed)
			(footprints allowed)
		)
		(placement
			(enabled no)
			(sheetname "")
		)
		(fill yes
			(thermal_gap 0.5)
			(thermal_bridge_width 0.5)
			(island_removal_mode 0)
		)
		(polygon
			(pts
				(xy 71.3867 -49.0982) (xy 71.3867 -49.7078) (xy 70.6755 -49.7078) (xy 70.6755 -49.0982)
			)
		)
	)
	(zone
		(layer "In8.Cu")
		(hatch none 0.5)
		(connect_pads
			(clearance 0)
		)
		(min_thickness 0.25)
		(keepout
			(tracks not_allowed)
			(vias allowed)
			(pads allowed)
			(copperpour not_allowed)
			(footprints allowed)
		)
		(placement
			(enabled no)
			(sheetname "")
		)
		(fill
			(thermal_gap 0.5)
			(thermal_bridge_width 0.5)
			(island_removal_mode 0)
		)
		(polygon
			(pts
				(xy 60.480194 -16.256) (xy 60.480194 -15.5448) (xy 61.089794 -15.5448) (xy 61.089794 -16.256)
			)
		)
	)
	(zone
		(layer "In8.Cu")
		(hatch none 0.5)
		(connect_pads
			(clearance 0)
		)
		(min_thickness 0.25)
		(keepout
			(tracks not_allowed)
			(vias allowed)
			(pads allowed)
			(copperpour not_allowed)
			(footprints allowed)
		)
		(placement
			(enabled no)
			(sheetname "")
		)
		(fill
			(thermal_gap 0.5)
			(thermal_bridge_width 0.5)
			(island_removal_mode 0)
		)
		(polygon
			(pts
				(xy 75.210162 -16.256) (xy 75.210162 -15.5448) (xy 75.819762 -15.5448) (xy 75.819762 -16.256)
			)
		)
	)
	(zone
		(layer "In8.Cu")
		(hatch none 0.5)
		(connect_pads
			(clearance 0)
		)
		(min_thickness 0.25)
		(keepout
			(tracks not_allowed)
			(vias allowed)
			(pads allowed)
			(copperpour not_allowed)
			(footprints allowed)
		)
		(placement
			(enabled no)
			(sheetname "")
		)
		(fill
			(thermal_gap 0.5)
			(thermal_bridge_width 0.5)
			(island_removal_mode 0)
		)
		(polygon
			(pts
				(xy 63.480188 -16.256) (xy 63.480188 -15.5448) (xy 64.089788 -15.5448) (xy 64.089788 -16.256)
			)
		)
	)
	(zone
		(layer "In8.Cu")
		(hatch none 0.5)
		(connect_pads
			(clearance 0)
		)
		(min_thickness 0.25)
		(keepout
			(tracks not_allowed)
			(vias allowed)
			(pads allowed)
			(copperpour not_allowed)
			(footprints allowed)
		)
		(placement
			(enabled no)
			(sheetname "")
		)
		(fill
			(thermal_gap 0.5)
			(thermal_bridge_width 0.5)
			(island_removal_mode 0)
		)
		(polygon
			(pts
				(xy 67.210178 -15.1892) (xy 67.210178 -14.478) (xy 67.819778 -14.478) (xy 67.819778 -15.1892)
			)
		)
	)
	(zone
		(layer "In8.Cu")
		(hatch none 0.5)
		(connect_pads
			(clearance 0)
		)
		(min_thickness 0.25)
		(keepout
			(tracks not_allowed)
			(vias allowed)
			(pads allowed)
			(copperpour not_allowed)
			(footprints allowed)
		)
		(placement
			(enabled no)
			(sheetname "")
		)
		(fill
			(thermal_gap 0.5)
			(thermal_bridge_width 0.5)
			(island_removal_mode 0)
		)
		(polygon
			(pts
				(xy 59.210194 -16.256) (xy 59.210194 -15.5448) (xy 59.819794 -15.5448) (xy 59.819794 -16.256)
			)
		)
	)
	(zone
		(layer "In8.Cu")
		(hatch none 0.5)
		(connect_pads
			(clearance 0)
		)
		(min_thickness 0.25)
		(keepout
			(tracks not_allowed)
			(vias allowed)
			(pads allowed)
			(copperpour not_allowed)
			(footprints allowed)
		)
		(placement
			(enabled no)
			(sheetname "")
		)
		(fill
			(thermal_gap 0.5)
			(thermal_bridge_width 0.5)
			(island_removal_mode 0)
		)
		(polygon
			(pts
				(xy 59.210194 -15.1892) (xy 59.210194 -14.478) (xy 59.819794 -14.478) (xy 59.819794 -15.1892)
			)
		)
	)
	(zone
		(layer "In8.Cu")
		(hatch none 0.5)
		(connect_pads
			(clearance 0)
		)
		(min_thickness 0.25)
		(keepout
			(tracks not_allowed)
			(vias allowed)
			(pads allowed)
			(copperpour not_allowed)
			(footprints allowed)
		)
		(placement
			(enabled no)
			(sheetname "")
		)
		(fill
			(thermal_gap 0.5)
			(thermal_bridge_width 0.5)
			(island_removal_mode 0)
		)
		(polygon
			(pts
				(xy 90.0938 -48.755046) (xy 90.0938 -49.364646) (xy 89.3826 -49.364646) (xy 89.3826 -48.755046)
			)
		)
	)
	(zone
		(layer "In8.Cu")
		(hatch none 0.5)
		(connect_pads
			(clearance 0)
		)
		(min_thickness 0.25)
		(keepout
			(tracks not_allowed)
			(vias allowed)
			(pads allowed)
			(copperpour not_allowed)
			(footprints allowed)
		)
		(placement
			(enabled no)
			(sheetname "")
		)
		(fill
			(thermal_gap 0.5)
			(thermal_bridge_width 0.5)
			(island_removal_mode 0)
		)
		(polygon
			(pts
				(xy 75.294236 -1.404874) (xy 76.005436 -1.404874) (xy 76.005436 -5.595874) (xy 75.294236 -5.595874)
			)
		)
	)
	(zone
		(layer "In8.Cu")
		(hatch none 0.5)
		(connect_pads
			(clearance 0)
		)
		(min_thickness 0.25)
		(keepout
			(tracks not_allowed)
			(vias allowed)
			(pads allowed)
			(copperpour not_allowed)
			(footprints allowed)
		)
		(placement
			(enabled no)
			(sheetname "")
		)
		(fill
			(thermal_gap 0.5)
			(thermal_bridge_width 0.5)
			(island_removal_mode 0)
		)
		(polygon
			(pts
				(xy 67.210178 -16.256) (xy 67.210178 -15.5448) (xy 67.819778 -15.5448) (xy 67.819778 -16.256)
			)
		)
	)
	(zone
		(layer "In8.Cu")
		(hatch none 0.5)
		(connect_pads
			(clearance 0)
		)
		(min_thickness 0.25)
		(keepout
			(tracks not_allowed)
			(vias allowed)
			(pads allowed)
			(copperpour not_allowed)
			(footprints allowed)
		)
		(placement
			(enabled no)
			(sheetname "")
		)
		(fill
			(thermal_gap 0.5)
			(thermal_bridge_width 0.5)
			(island_removal_mode 0)
		)
		(polygon
			(pts
				(xy 90.0938 -47.612046) (xy 90.0938 -48.221646) (xy 89.3826 -48.221646) (xy 89.3826 -47.612046)
			)
		)
	)
	(zone
		(layer "In8.Cu")
		(hatch none 0.5)
		(connect_pads
			(clearance 0)
		)
		(min_thickness 0.25)
		(keepout
			(tracks not_allowed)
			(vias allowed)
			(pads allowed)
			(copperpour not_allowed)
			(footprints allowed)
		)
		(placement
			(enabled no)
			(sheetname "")
		)
		(fill
			(thermal_gap 0.5)
			(thermal_bridge_width 0.5)
			(island_removal_mode 0)
		)
		(polygon
			(pts
				(xy 63.480188 -15.1892) (xy 63.480188 -14.478) (xy 64.089788 -14.478) (xy 64.089788 -15.1892)
			)
		)
	)
	(zone
		(layer "In8.Cu")
		(hatch none 0.5)
		(connect_pads
			(clearance 0)
		)
		(min_thickness 0.25)
		(keepout
			(tracks not_allowed)
			(vias allowed)
			(pads allowed)
			(copperpour not_allowed)
			(footprints allowed)
		)
		(placement
			(enabled no)
			(sheetname "")
		)
		(fill
			(thermal_gap 0.5)
			(thermal_bridge_width 0.5)
			(island_removal_mode 0)
		)
		(polygon
			(pts
				(xy 68.29425 -1.404874) (xy 69.00545 -1.404874) (xy 69.00545 -5.595874) (xy 68.29425 -5.595874)
			)
		)
	)
	(zone
		(layer "In8.Cu")
		(hatch none 0.5)
		(connect_pads
			(clearance 0)
		)
		(min_thickness 0.25)
		(keepout
			(tracks not_allowed)
			(vias allowed)
			(pads allowed)
			(copperpour not_allowed)
			(footprints allowed)
		)
		(placement
			(enabled no)
			(sheetname "")
		)
		(fill
			(thermal_gap 0.5)
			(thermal_bridge_width 0.5)
			(island_removal_mode 0)
		)
		(polygon
			(pts
				(xy 72.294242 -1.404874) (xy 73.005442 -1.404874) (xy 73.005442 -5.595874) (xy 72.294242 -5.595874)
			)
		)
	)
	(zone
		(layer "In8.Cu")
		(hatch none 0.5)
		(connect_pads
			(clearance 0)
		)
		(min_thickness 0.25)
		(keepout
			(tracks not_allowed)
			(vias allowed)
			(pads allowed)
			(copperpour not_allowed)
			(footprints allowed)
		)
		(placement
			(enabled no)
			(sheetname "")
		)
		(fill
			(thermal_gap 0.5)
			(thermal_bridge_width 0.5)
			(island_removal_mode 0)
		)
		(polygon
			(pts
				(xy 60.480194 -15.1892) (xy 60.480194 -14.478) (xy 61.089794 -14.478) (xy 61.089794 -15.1892)
			)
		)
	)
	(zone
		(layer "In8.Cu")
		(hatch none 0.5)
		(connect_pads
			(clearance 0)
		)
		(min_thickness 0.25)
		(keepout
			(tracks not_allowed)
			(vias allowed)
			(pads allowed)
			(copperpour not_allowed)
			(footprints allowed)
		)
		(placement
			(enabled no)
			(sheetname "")
		)
		(fill
			(thermal_gap 0.5)
			(thermal_bridge_width 0.5)
			(island_removal_mode 0)
		)
		(polygon
			(pts
				(xy 76.480162 -15.1892) (xy 76.480162 -14.478) (xy 77.089762 -14.478) (xy 77.089762 -15.1892)
			)
		)
	)
	(zone
		(layer "In8.Cu")
		(hatch none 0.5)
		(connect_pads
			(clearance 0)
		)
		(min_thickness 0.25)
		(keepout
			(tracks not_allowed)
			(vias allowed)
			(pads allowed)
			(copperpour not_allowed)
			(footprints allowed)
		)
		(placement
			(enabled no)
			(sheetname "")
		)
		(fill
			(thermal_gap 0.5)
			(thermal_bridge_width 0.5)
			(island_removal_mode 0)
		)
		(polygon
			(pts
				(xy 67.294252 -1.404874) (xy 68.005452 -1.404874) (xy 68.005452 -5.595874) (xy 67.294252 -5.595874)
			)
		)
	)
	(zone
		(layer "In8.Cu")
		(hatch none 0.5)
		(connect_pads
			(clearance 0)
		)
		(min_thickness 0.25)
		(keepout
			(tracks not_allowed)
			(vias allowed)
			(pads allowed)
			(copperpour not_allowed)
			(footprints allowed)
		)
		(placement
			(enabled no)
			(sheetname "")
		)
		(fill
			(thermal_gap 0.5)
			(thermal_bridge_width 0.5)
			(island_removal_mode 0)
		)
		(polygon
			(pts
				(xy 75.210162 -15.1892) (xy 75.210162 -14.478) (xy 75.819762 -14.478) (xy 75.819762 -15.1892)
			)
		)
	)
	(zone
		(layer "In8.Cu")
		(hatch none 0.5)
		(connect_pads
			(clearance 0)
		)
		(min_thickness 0.25)
		(keepout
			(tracks not_allowed)
			(vias allowed)
			(pads allowed)
			(copperpour not_allowed)
			(footprints allowed)
		)
		(placement
			(enabled no)
			(sheetname "")
		)
		(fill
			(thermal_gap 0.5)
			(thermal_bridge_width 0.5)
			(island_removal_mode 0)
		)
		(polygon
			(pts
				(xy 62.210188 -16.256) (xy 62.210188 -15.5448) (xy 62.819788 -15.5448) (xy 62.819788 -16.256)
			)
		)
	)
	(zone
		(layer "In8.Cu")
		(hatch none 0.5)
		(connect_pads
			(clearance 0)
		)
		(min_thickness 0.25)
		(keepout
			(tracks not_allowed)
			(vias allowed)
			(pads allowed)
			(copperpour not_allowed)
			(footprints allowed)
		)
		(placement
			(enabled no)
			(sheetname "")
		)
		(fill
			(thermal_gap 0.5)
			(thermal_bridge_width 0.5)
			(island_removal_mode 0)
		)
		(polygon
			(pts
				(xy 68.480178 -16.256) (xy 68.480178 -15.5448) (xy 69.089778 -15.5448) (xy 69.089778 -16.256)
			)
		)
	)
	(zone
		(layer "In8.Cu")
		(hatch none 0.5)
		(connect_pads
			(clearance 0)
		)
		(min_thickness 0.25)
		(keepout
			(tracks not_allowed)
			(vias allowed)
			(pads allowed)
			(copperpour not_allowed)
			(footprints allowed)
		)
		(placement
			(enabled no)
			(sheetname "")
		)
		(fill
			(thermal_gap 0.5)
			(thermal_bridge_width 0.5)
			(island_removal_mode 0)
		)
		(polygon
			(pts
				(xy 72.09917 -16.256) (xy 72.09917 -15.5448) (xy 72.70877 -15.5448) (xy 72.70877 -16.256)
			)
		)
	)
	(zone
		(layer "In8.Cu")
		(hatch none 0.5)
		(connect_pads
			(clearance 0)
		)
		(min_thickness 0.25)
		(keepout
			(tracks not_allowed)
			(vias allowed)
			(pads allowed)
			(copperpour not_allowed)
			(footprints allowed)
		)
		(placement
			(enabled no)
			(sheetname "")
		)
		(fill
			(thermal_gap 0.5)
			(thermal_bridge_width 0.5)
			(island_removal_mode 0)
		)
		(polygon
			(pts
				(xy 76.294234 -1.404874) (xy 77.005434 -1.404874) (xy 77.005434 -5.595874) (xy 76.294234 -5.595874)
			)
		)
	)
	(zone
		(layer "In8.Cu")
		(hatch none 0.5)
		(connect_pads
			(clearance 0)
		)
		(min_thickness 0.25)
		(keepout
			(tracks not_allowed)
			(vias allowed)
			(pads allowed)
			(copperpour not_allowed)
			(footprints allowed)
		)
		(placement
			(enabled no)
			(sheetname "")
		)
		(fill
			(thermal_gap 0.5)
			(thermal_bridge_width 0.5)
			(island_removal_mode 0)
		)
		(polygon
			(pts
				(xy 59.294268 -1.404874) (xy 60.005468 -1.404874) (xy 60.005468 -5.595874) (xy 59.294268 -5.595874)
			)
		)
	)
	(zone
		(layer "In8.Cu")
		(hatch none 0.5)
		(connect_pads
			(clearance 0)
		)
		(min_thickness 0.25)
		(keepout
			(tracks not_allowed)
			(vias allowed)
			(pads allowed)
			(copperpour not_allowed)
			(footprints allowed)
		)
		(placement
			(enabled no)
			(sheetname "")
		)
		(fill
			(thermal_gap 0.5)
			(thermal_bridge_width 0.5)
			(island_removal_mode 0)
		)
		(polygon
			(pts
				(xy 70.82917 -15.1892) (xy 70.82917 -14.478) (xy 71.43877 -14.478) (xy 71.43877 -15.1892)
			)
		)
	)
	(zone
		(layer "In8.Cu")
		(hatch none 0.5)
		(connect_pads
			(clearance 0)
		)
		(min_thickness 0.25)
		(keepout
			(tracks not_allowed)
			(vias allowed)
			(pads allowed)
			(copperpour not_allowed)
			(footprints allowed)
		)
		(placement
			(enabled no)
			(sheetname "")
		)
		(fill
			(thermal_gap 0.5)
			(thermal_bridge_width 0.5)
			(island_removal_mode 0)
		)
		(polygon
			(pts
				(xy 91.1606 -47.612046) (xy 91.1606 -48.221646) (xy 90.4494 -48.221646) (xy 90.4494 -47.612046)
			)
		)
	)
	(zone
		(layer "In8.Cu")
		(hatch none 0.5)
		(connect_pads
			(clearance 0)
		)
		(min_thickness 0.25)
		(keepout
			(tracks not_allowed)
			(vias allowed)
			(pads allowed)
			(copperpour not_allowed)
			(footprints allowed)
		)
		(placement
			(enabled no)
			(sheetname "")
		)
		(fill
			(thermal_gap 0.5)
			(thermal_bridge_width 0.5)
			(island_removal_mode 0)
		)
		(polygon
			(pts
				(xy 62.210188 -15.1892) (xy 62.210188 -14.478) (xy 62.819788 -14.478) (xy 62.819788 -15.1892)
			)
		)
	)
	(zone
		(layer "In8.Cu")
		(hatch none 0.5)
		(connect_pads
			(clearance 0)
		)
		(min_thickness 0.25)
		(keepout
			(tracks not_allowed)
			(vias allowed)
			(pads allowed)
			(copperpour not_allowed)
			(footprints allowed)
		)
		(placement
			(enabled no)
			(sheetname "")
		)
		(fill
			(thermal_gap 0.5)
			(thermal_bridge_width 0.5)
			(island_removal_mode 0)
		)
		(polygon
			(pts
				(xy 91.1606 -48.755046) (xy 91.1606 -49.364646) (xy 90.4494 -49.364646) (xy 90.4494 -48.755046)
			)
		)
	)
	(zone
		(layer "In8.Cu")
		(hatch none 0.5)
		(connect_pads
			(clearance 0)
		)
		(min_thickness 0.25)
		(keepout
			(tracks not_allowed)
			(vias allowed)
			(pads allowed)
			(copperpour not_allowed)
			(footprints allowed)
		)
		(placement
			(enabled no)
			(sheetname "")
		)
		(fill
			(thermal_gap 0.5)
			(thermal_bridge_width 0.5)
			(island_removal_mode 0)
		)
		(polygon
			(pts
				(xy 62.294262 -1.404874) (xy 63.005462 -1.404874) (xy 63.005462 -5.595874) (xy 62.294262 -5.595874)
			)
		)
	)
	(zone
		(layer "In8.Cu")
		(hatch none 0.5)
		(connect_pads
			(clearance 0)
		)
		(min_thickness 0.25)
		(keepout
			(tracks not_allowed)
			(vias allowed)
			(pads allowed)
			(copperpour not_allowed)
			(footprints allowed)
		)
		(placement
			(enabled no)
			(sheetname "")
		)
		(fill
			(thermal_gap 0.5)
			(thermal_bridge_width 0.5)
			(island_removal_mode 0)
		)
		(polygon
			(pts
				(xy 76.480162 -16.256) (xy 76.480162 -15.5448) (xy 77.089762 -15.5448) (xy 77.089762 -16.256)
			)
		)
	)
	(zone
		(layer "In8.Cu")
		(hatch none 0.5)
		(connect_pads
			(clearance 0)
		)
		(min_thickness 0.25)
		(keepout
			(tracks not_allowed)
			(vias allowed)
			(pads allowed)
			(copperpour not_allowed)
			(footprints allowed)
		)
		(placement
			(enabled no)
			(sheetname "")
		)
		(fill
			(thermal_gap 0.5)
			(thermal_bridge_width 0.5)
			(island_removal_mode 0)
		)
		(polygon
			(pts
				(xy 68.480178 -15.1892) (xy 68.480178 -14.478) (xy 69.089778 -14.478) (xy 69.089778 -15.1892)
			)
		)
	)
	(zone
		(layer "In8.Cu")
		(hatch none 0.5)
		(connect_pads
			(clearance 0)
		)
		(min_thickness 0.25)
		(keepout
			(tracks not_allowed)
			(vias allowed)
			(pads allowed)
			(copperpour not_allowed)
			(footprints allowed)
		)
		(placement
			(enabled no)
			(sheetname "")
		)
		(fill
			(thermal_gap 0.5)
			(thermal_bridge_width 0.5)
			(island_removal_mode 0)
		)
		(polygon
			(pts
				(xy 71.294244 -1.404874) (xy 72.005444 -1.404874) (xy 72.005444 -5.595874) (xy 71.294244 -5.595874)
			)
		)
	)
	(zone
		(layer "In8.Cu")
		(hatch none 0.5)
		(connect_pads
			(clearance 0)
		)
		(min_thickness 0.25)
		(keepout
			(tracks not_allowed)
			(vias allowed)
			(pads allowed)
			(copperpour not_allowed)
			(footprints allowed)
		)
		(placement
			(enabled no)
			(sheetname "")
		)
		(fill
			(thermal_gap 0.5)
			(thermal_bridge_width 0.5)
			(island_removal_mode 0)
		)
		(polygon
			(pts
				(xy 63.29426 -1.404874) (xy 64.00546 -1.404874) (xy 64.00546 -5.595874) (xy 63.29426 -5.595874)
			)
		)
	)
	(zone
		(layer "In8.Cu")
		(hatch none 0.5)
		(connect_pads
			(clearance 0)
		)
		(min_thickness 0.25)
		(keepout
			(tracks not_allowed)
			(vias allowed)
			(pads allowed)
			(copperpour not_allowed)
			(footprints allowed)
		)
		(placement
			(enabled no)
			(sheetname "")
		)
		(fill
			(thermal_gap 0.5)
			(thermal_bridge_width 0.5)
			(island_removal_mode 0)
		)
		(polygon
			(pts
				(xy 72.09917 -15.1892) (xy 72.09917 -14.478) (xy 72.70877 -14.478) (xy 72.70877 -15.1892)
			)
		)
	)
	(zone
		(layer "In8.Cu")
		(hatch none 0.5)
		(connect_pads
			(clearance 0)
		)
		(min_thickness 0.25)
		(keepout
			(tracks not_allowed)
			(vias allowed)
			(pads allowed)
			(copperpour not_allowed)
			(footprints allowed)
		)
		(placement
			(enabled no)
			(sheetname "")
		)
		(fill
			(thermal_gap 0.5)
			(thermal_bridge_width 0.5)
			(island_removal_mode 0)
		)
		(polygon
			(pts
				(xy 70.82917 -16.256) (xy 70.82917 -15.5448) (xy 71.43877 -15.5448) (xy 71.43877 -16.256)
			)
		)
	)
	(zone
		(layer "Cmts.User")
		(hatch none 0.5)
		(connect_pads
			(clearance 0)
		)
		(min_thickness 0.25)
		(keepout
			(tracks allowed)
			(vias allowed)
			(pads allowed)
			(copperpour allowed)
			(footprints allowed)
		)
		(placement
			(enabled no)
			(sheetname "")
		)
		(fill
			(thermal_gap 0.5)
			(thermal_bridge_width 0.5)
			(island_removal_mode 0)
		)
		(polygon
			(pts
				(xy 92.456 -54.61) (xy 92.456 -53.467) (xy 94.869 -53.467) (xy 94.869 -54.61)
			)
		)
	)
	(zone
		(layer "Cmts.User")
		(hatch none 0.5)
		(connect_pads
			(clearance 0)
		)
		(min_thickness 0.25)
		(keepout
			(tracks allowed)
			(vias allowed)
			(pads allowed)
			(copperpour allowed)
			(footprints allowed)
		)
		(placement
			(enabled no)
			(sheetname "")
		)
		(fill
			(thermal_gap 0.5)
			(thermal_bridge_width 0.5)
			(island_removal_mode 0)
		)
		(polygon
			(pts
				(xy 66.837306 -7.970012) (xy 67.370706 -7.970012) (xy 67.370706 -10.713212) (xy 66.837306 -10.713212)
			)
		)
	)
	(zone
		(layer "Cmts.User")
		(hatch none 0.5)
		(connect_pads
			(clearance 0)
		)
		(min_thickness 0.25)
		(keepout
			(tracks allowed)
			(vias allowed)
			(pads allowed)
			(copperpour allowed)
			(footprints allowed)
		)
		(placement
			(enabled no)
			(sheetname "")
		)
		(fill
			(thermal_gap 0.5)
			(thermal_bridge_width 0.5)
			(island_removal_mode 0)
		)
		(polygon
			(pts
				(xy 85.828124 -27.800554) (xy 85.828124 -27.267154) (xy 88.571324 -27.267154) (xy 88.571324 -27.800554)
			)
		)
	)
	(zone
		(layer "Cmts.User")
		(hatch none 0.5)
		(connect_pads
			(clearance 0)
		)
		(min_thickness 0.25)
		(keepout
			(tracks allowed)
			(vias allowed)
			(pads allowed)
			(copperpour allowed)
			(footprints allowed)
		)
		(placement
			(enabled no)
			(sheetname "")
		)
		(fill
			(thermal_gap 0.5)
			(thermal_bridge_width 0.5)
			(island_removal_mode 0)
		)
		(polygon
			(pts
				(xy 100.965 -29.718) (xy 100.965 -29.21) (xy 103.759 -29.21) (xy 103.759 -29.718) (xy 103.759 -30.353)
				(xy 103.632 -30.48) (xy 101.219 -30.48) (xy 100.965 -30.226)
			)
		)
	)
	(zone
		(layer "Cmts.User")
		(hatch none 0.5)
		(connect_pads
			(clearance 0)
		)
		(min_thickness 0.25)
		(keepout
			(tracks allowed)
			(vias allowed)
			(pads allowed)
			(copperpour allowed)
			(footprints allowed)
		)
		(placement
			(enabled no)
			(sheetname "")
		)
		(fill
			(thermal_gap 0.5)
			(thermal_bridge_width 0.5)
			(island_removal_mode 0)
		)
		(polygon
			(pts
				(xy 94.742 -36.449) (xy 94.742 -35.306) (xy 97.155 -35.306) (xy 97.155 -36.449)
			)
		)
	)
	(zone
		(layer "Cmts.User")
		(hatch none 0.5)
		(connect_pads
			(clearance 0)
		)
		(min_thickness 0.25)
		(keepout
			(tracks allowed)
			(vias allowed)
			(pads allowed)
			(copperpour allowed)
			(footprints allowed)
		)
		(placement
			(enabled no)
			(sheetname "")
		)
		(fill
			(thermal_gap 0.5)
			(thermal_bridge_width 0.5)
			(island_removal_mode 0)
		)
		(polygon
			(pts
				(xy 89.154 -43.307) (xy 89.154 -42.418) (xy 94.234 -42.418) (xy 94.234 -43.307)
			)
		)
	)
	(zone
		(layer "Cmts.User")
		(hatch none 0.5)
		(connect_pads
			(clearance 0)
		)
		(min_thickness 0.25)
		(keepout
			(tracks allowed)
			(vias allowed)
			(pads allowed)
			(copperpour allowed)
			(footprints allowed)
		)
		(placement
			(enabled no)
			(sheetname "")
		)
		(fill
			(thermal_gap 0.5)
			(thermal_bridge_width 0.5)
			(island_removal_mode 0)
		)
		(polygon
			(pts
				(xy 88.646 -33.655) (xy 88.646 -32.131) (xy 90.932 -32.131) (xy 90.932 -33.655)
			)
		)
	)
	(zone
		(layer "Cmts.User")
		(hatch none 0.5)
		(connect_pads
			(clearance 0)
		)
		(min_thickness 0.25)
		(keepout
			(tracks allowed)
			(vias allowed)
			(pads allowed)
			(copperpour allowed)
			(footprints allowed)
		)
		(placement
			(enabled no)
			(sheetname "")
		)
		(fill
			(thermal_gap 0.5)
			(thermal_bridge_width 0.5)
			(island_removal_mode 0)
		)
		(polygon
			(pts
				(xy 94.107 -33.909) (xy 94.107 -32.385) (xy 95.504 -32.385) (xy 95.504 -33.909)
			)
		)
	)
	(zone
		(layer "Cmts.User")
		(hatch none 0.5)
		(connect_pads
			(clearance 0)
		)
		(min_thickness 0.25)
		(keepout
			(tracks allowed)
			(vias allowed)
			(pads allowed)
			(copperpour allowed)
			(footprints allowed)
		)
		(placement
			(enabled no)
			(sheetname "")
		)
		(fill
			(thermal_gap 0.5)
			(thermal_bridge_width 0.5)
			(island_removal_mode 0)
		)
		(polygon
			(pts
				(xy 83.774788 -48.031146) (xy 83.774788 -48.564546) (xy 81.031588 -48.564546) (xy 81.031588 -48.031146)
			)
		)
	)
	(zone
		(layer "Cmts.User")
		(hatch none 0.5)
		(connect_pads
			(clearance 0)
		)
		(min_thickness 0.25)
		(keepout
			(tracks allowed)
			(vias allowed)
			(pads allowed)
			(copperpour allowed)
			(footprints allowed)
		)
		(placement
			(enabled no)
			(sheetname "")
		)
		(fill
			(thermal_gap 0.5)
			(thermal_bridge_width 0.5)
			(island_removal_mode 0)
		)
		(polygon
			(pts
				(xy 88.011 -36.703) (xy 88.011 -35.306) (xy 90.678 -35.306) (xy 90.678 -36.703)
			)
		)
	)
	(zone
		(layer "Cmts.User")
		(hatch none 0.5)
		(connect_pads
			(clearance 0)
		)
		(min_thickness 0.25)
		(keepout
			(tracks allowed)
			(vias allowed)
			(pads allowed)
			(copperpour allowed)
			(footprints allowed)
		)
		(placement
			(enabled no)
			(sheetname "")
		)
		(fill
			(thermal_gap 0.5)
			(thermal_bridge_width 0.5)
			(island_removal_mode 0)
		)
		(polygon
			(pts
				(xy 88.275668 -26.900378) (xy 88.275668 -26.366978) (xy 91.018868 -26.366978) (xy 91.018868 -26.900378)
			)
		)
	)
	(zone
		(layer "Cmts.User")
		(hatch none 0.5)
		(connect_pads
			(clearance 0)
		)
		(min_thickness 0.25)
		(keepout
			(tracks allowed)
			(vias allowed)
			(pads allowed)
			(copperpour allowed)
			(footprints allowed)
		)
		(placement
			(enabled no)
			(sheetname "")
		)
		(fill
			(thermal_gap 0.5)
			(thermal_bridge_width 0.5)
			(island_removal_mode 0)
		)
		(polygon
			(pts
				(xy 60.784232 -16.758412) (xy 61.317632 -16.758412) (xy 61.317632 -19.501612) (xy 60.784232 -19.501612)
			)
		)
	)
	(zone
		(layer "Cmts.User")
		(hatch none 0.5)
		(connect_pads
			(clearance 0)
		)
		(min_thickness 0.25)
		(keepout
			(tracks allowed)
			(vias allowed)
			(pads allowed)
			(copperpour allowed)
			(footprints allowed)
		)
		(placement
			(enabled no)
			(sheetname "")
		)
		(fill
			(thermal_gap 0.5)
			(thermal_bridge_width 0.5)
			(island_removal_mode 0)
		)
		(polygon
			(pts
				(xy 72.0852 -45.816012) (xy 72.6186 -45.816012) (xy 72.6186 -48.559212) (xy 72.0852 -48.559212)
			)
		)
	)
	(zone
		(layer "Cmts.User")
		(hatch none 0.5)
		(connect_pads
			(clearance 0)
		)
		(min_thickness 0.25)
		(keepout
			(tracks allowed)
			(vias allowed)
			(pads allowed)
			(copperpour allowed)
			(footprints allowed)
		)
		(placement
			(enabled no)
			(sheetname "")
		)
		(fill
			(thermal_gap 0.5)
			(thermal_bridge_width 0.5)
			(island_removal_mode 0)
		)
		(polygon
			(pts
				(xy 136.525 -44.831) (xy 136.525 -42.672) (xy 138.303 -42.672) (xy 138.303 -44.831)
			)
		)
	)
	(zone
		(layer "Cmts.User")
		(hatch none 0.5)
		(connect_pads
			(clearance 0)
		)
		(min_thickness 0.25)
		(keepout
			(tracks allowed)
			(vias allowed)
			(pads allowed)
			(copperpour allowed)
			(footprints allowed)
		)
		(placement
			(enabled no)
			(sheetname "")
		)
		(fill
			(thermal_gap 0.5)
			(thermal_bridge_width 0.5)
			(island_removal_mode 0)
		)
		(polygon
			(pts
				(xy 5.461 -87.503) (xy 5.461 -85.852) (xy 12.065 -85.852) (xy 12.065 -87.503)
			)
		)
	)
	(zone
		(layer "Cmts.User")
		(hatch none 0.5)
		(connect_pads
			(clearance 0)
		)
		(min_thickness 0.25)
		(keepout
			(tracks allowed)
			(vias allowed)
			(pads allowed)
			(copperpour allowed)
			(footprints allowed)
		)
		(placement
			(enabled no)
			(sheetname "")
		)
		(fill
			(thermal_gap 0.5)
			(thermal_bridge_width 0.5)
			(island_removal_mode 0)
		)
		(polygon
			(pts
				(xy 29.050996 -96.898206) (xy 29.050996 -97.431606) (xy 26.307796 -97.431606) (xy 26.307796 -96.898206)
			)
		)
	)
	(zone
		(layer "Cmts.User")
		(hatch none 0.5)
		(connect_pads
			(clearance 0)
		)
		(min_thickness 0.25)
		(keepout
			(tracks allowed)
			(vias allowed)
			(pads allowed)
			(copperpour allowed)
			(footprints allowed)
		)
		(placement
			(enabled no)
			(sheetname "")
		)
		(fill
			(thermal_gap 0.5)
			(thermal_bridge_width 0.5)
			(island_removal_mode 0)
		)
		(polygon
			(pts
				(xy 76.708 -86.8426) (xy 76.708 -82.296) (xy 82.7532 -82.296) (xy 82.7532 -86.8426)
			)
		)
	)
	(zone
		(layer "Cmts.User")
		(hatch none 0.5)
		(connect_pads
			(clearance 0)
		)
		(min_thickness 0.25)
		(keepout
			(tracks allowed)
			(vias allowed)
			(pads allowed)
			(copperpour allowed)
			(footprints allowed)
		)
		(placement
			(enabled no)
			(sheetname "")
		)
		(fill
			(thermal_gap 0.5)
			(thermal_bridge_width 0.5)
			(island_removal_mode 0)
		)
		(polygon
			(pts
				(xy 88.011254 -50.043334) (xy 87.477854 -50.043334) (xy 87.477854 -47.300134) (xy 88.011254 -47.300134)
			)
		)
	)
	(zone
		(layer "Cmts.User")
		(hatch none 0.5)
		(connect_pads
			(clearance 0)
		)
		(min_thickness 0.25)
		(keepout
			(tracks allowed)
			(vias allowed)
			(pads allowed)
			(copperpour allowed)
			(footprints allowed)
		)
		(placement
			(enabled no)
			(sheetname "")
		)
		(fill
			(thermal_gap 0.5)
			(thermal_bridge_width 0.5)
			(island_removal_mode 0)
		)
		(polygon
			(pts
				(xy 92.430854 -46.846998) (xy 92.964254 -46.846998) (xy 92.964254 -49.590198) (xy 92.430854 -49.590198)
			)
		)
	)
	(zone
		(layer "Cmts.User")
		(hatch none 0.5)
		(connect_pads
			(clearance 0)
		)
		(min_thickness 0.25)
		(keepout
			(tracks allowed)
			(vias allowed)
			(pads allowed)
			(copperpour allowed)
			(footprints allowed)
		)
		(placement
			(enabled no)
			(sheetname "")
		)
		(fill
			(thermal_gap 0.5)
			(thermal_bridge_width 0.5)
			(island_removal_mode 0)
		)
		(polygon
			(pts
				(xy 21.082 -57.912) (xy 21.082 -56.515) (xy 22.098 -56.515) (xy 22.098 -57.912)
			)
		)
	)
	(zone
		(layer "Cmts.User")
		(hatch none 0.5)
		(connect_pads
			(clearance 0)
		)
		(min_thickness 0.25)
		(keepout
			(tracks allowed)
			(vias allowed)
			(pads allowed)
			(copperpour allowed)
			(footprints allowed)
		)
		(placement
			(enabled no)
			(sheetname "")
		)
		(fill
			(thermal_gap 0.5)
			(thermal_bridge_width 0.5)
			(island_removal_mode 0)
		)
		(polygon
			(pts
				(xy 89.789 -57.277) (xy 89.789 -55.118) (xy 91.44 -55.118) (xy 91.44 -57.277)
			)
		)
	)
	(zone
		(layer "Cmts.User")
		(hatch none 0.5)
		(connect_pads
			(clearance 0)
		)
		(min_thickness 0.25)
		(keepout
			(tracks allowed)
			(vias allowed)
			(pads allowed)
			(copperpour allowed)
			(footprints allowed)
		)
		(placement
			(enabled no)
			(sheetname "")
		)
		(fill
			(thermal_gap 0.5)
			(thermal_bridge_width 0.5)
			(island_removal_mode 0)
		)
		(polygon
			(pts
				(xy 129.921 -40.386) (xy 129.921 -35.941) (xy 131.445 -35.941) (xy 131.445 -40.386)
			)
		)
	)
	(zone
		(layer "Cmts.User")
		(hatch none 0.5)
		(connect_pads
			(clearance 0)
		)
		(min_thickness 0.25)
		(keepout
			(tracks allowed)
			(vias allowed)
			(pads allowed)
			(copperpour allowed)
			(footprints allowed)
		)
		(placement
			(enabled no)
			(sheetname "")
		)
		(fill
			(thermal_gap 0.5)
			(thermal_bridge_width 0.5)
			(island_removal_mode 0)
		)
		(polygon
			(pts
				(xy 74.83729 -7.157212) (xy 75.37069 -7.157212) (xy 75.37069 -9.900412) (xy 74.83729 -9.900412)
			)
		)
	)
	(zone
		(layer "Cmts.User")
		(hatch none 0.5)
		(connect_pads
			(clearance 0)
		)
		(min_thickness 0.25)
		(keepout
			(tracks allowed)
			(vias allowed)
			(pads allowed)
			(copperpour allowed)
			(footprints allowed)
		)
		(placement
			(enabled no)
			(sheetname "")
		)
		(fill
			(thermal_gap 0.5)
			(thermal_bridge_width 0.5)
			(island_removal_mode 0)
		)
		(polygon
			(pts
				(xy 66.74739 -19.685) (xy 66.74739 -19.1516) (xy 69.49059 -19.1516) (xy 69.49059 -19.685)
			)
		)
	)
	(zone
		(layer "Cmts.User")
		(hatch none 0.5)
		(connect_pads
			(clearance 0)
		)
		(min_thickness 0.25)
		(keepout
			(tracks allowed)
			(vias allowed)
			(pads allowed)
			(copperpour allowed)
			(footprints allowed)
		)
		(placement
			(enabled no)
			(sheetname "")
		)
		(fill
			(thermal_gap 0.5)
			(thermal_bridge_width 0.5)
			(island_removal_mode 0)
		)
		(polygon
			(pts
				(xy 74.83729 -10.408412) (xy 75.37069 -10.408412) (xy 75.37069 -13.151612) (xy 74.83729 -13.151612)
			)
		)
	)
	(zone
		(layer "Cmts.User")
		(hatch none 0.5)
		(connect_pads
			(clearance 0)
		)
		(min_thickness 0.25)
		(keepout
			(tracks allowed)
			(vias allowed)
			(pads allowed)
			(copperpour allowed)
			(footprints allowed)
		)
		(placement
			(enabled no)
			(sheetname "")
		)
		(fill
			(thermal_gap 0.5)
			(thermal_bridge_width 0.5)
			(island_removal_mode 0)
		)
		(polygon
			(pts
				(xy 157.2133 -56.0324) (xy 157.7467 -56.0324) (xy 157.7467 -58.7756) (xy 157.2133 -58.7756)
			)
		)
	)
	(zone
		(layer "Cmts.User")
		(hatch none 0.5)
		(connect_pads
			(clearance 0)
		)
		(min_thickness 0.25)
		(keepout
			(tracks allowed)
			(vias allowed)
			(pads allowed)
			(copperpour allowed)
			(footprints allowed)
		)
		(placement
			(enabled no)
			(sheetname "")
		)
		(fill
			(thermal_gap 0.5)
			(thermal_bridge_width 0.5)
			(island_removal_mode 0)
		)
		(polygon
			(pts
				(xy 70.181978 -50.711354) (xy 70.181978 -50.177954) (xy 72.925178 -50.177954) (xy 72.925178 -50.711354)
			)
		)
	)
	(zone
		(layer "Cmts.User")
		(hatch none 0.5)
		(connect_pads
			(clearance 0)
		)
		(min_thickness 0.25)
		(keepout
			(tracks allowed)
			(vias allowed)
			(pads allowed)
			(copperpour allowed)
			(footprints allowed)
		)
		(placement
			(enabled no)
			(sheetname "")
		)
		(fill
			(thermal_gap 0.5)
			(thermal_bridge_width 0.5)
			(island_removal_mode 0)
		)
		(polygon
			(pts
				(xy 98.044 -34.544) (xy 98.044 -32.766) (xy 98.044 -32.0548) (xy 121.3612 -32.0548) (xy 121.7168 -32.0548)
				(xy 122.682 -33.02) (xy 122.682 -35.2552) (xy 121.3612 -36.576) (xy 121.3612 -41.2242) (xy 122.301 -42.164)
				(xy 122.301 -47.498) (xy 121.793 -48.006) (xy 121.793 -55.753) (xy 121.3612 -55.753) (xy 120.904 -55.753)
				(xy 114.9604 -55.753) (xy 112.141 -58.5724) (xy 111.252 -58.5724) (xy 107.0356 -58.5724) (xy 106.4514 -57.9882)
				(xy 106.4514 -56.7182) (xy 105.4862 -55.753) (xy 98.044 -55.753) (xy 97.155 -55.753) (xy 96.647 -55.753)
				(xy 95.2246 -54.3306) (xy 95.2246 -52.2224) (xy 95.1738 -52.1716) (xy 95.1738 -43.8658) (xy 96.1644 -42.8752)
				(xy 96.1644 -38.227) (xy 97.2185 -37.1729) (xy 97.2185 -35.3695)
			)
		)
	)
	(zone
		(layer "Cmts.User")
		(hatch none 0.5)
		(connect_pads
			(clearance 0.5)
		)
		(min_thickness 0.25)
		(fill
			(thermal_gap 0.5)
			(thermal_bridge_width 0.5)
			(island_removal_mode 0)
		)
		(polygon
			(pts
				(xy -1100.000086 2147.483647) (xy -1100.000086 -2000.000064) (xy 1100.000086 -2000.000064) (xy 1100.000086 2147.483647)
			)
		)
	)
	(zone
		(layer "Cmts.User")
		(hatch none 0.5)
		(connect_pads
			(clearance 0)
		)
		(min_thickness 0.25)
		(keepout
			(tracks allowed)
			(vias allowed)
			(pads allowed)
			(copperpour allowed)
			(footprints allowed)
		)
		(placement
			(enabled no)
			(sheetname "")
		)
		(fill
			(thermal_gap 0.5)
			(thermal_bridge_width 0.5)
			(island_removal_mode 0)
		)
		(polygon
			(pts
				(xy 85.344 -28.518612) (xy 86.233 -28.518612) (xy 86.233 -31.261812) (xy 85.344 -31.261812)
			)
		)
	)
	(zone
		(layer "Cmts.User")
		(hatch none 0.5)
		(connect_pads
			(clearance 0)
		)
		(min_thickness 0.25)
		(keepout
			(tracks allowed)
			(vias allowed)
			(pads allowed)
			(copperpour allowed)
			(footprints allowed)
		)
		(placement
			(enabled no)
			(sheetname "")
		)
		(fill
			(thermal_gap 0.5)
			(thermal_bridge_width 0.5)
			(island_removal_mode 0)
		)
		(polygon
			(pts
				(xy 95.504 -57.785) (xy 95.504 -55.626) (xy 95.504 -55.118) (xy 95.631 -54.991) (xy 96.139 -54.991)
				(xy 96.393 -55.245) (xy 96.393 -55.626) (xy 96.393 -57.785)
			)
		)
	)
	(zone
		(layer "Cmts.User")
		(hatch none 0.5)
		(connect_pads
			(clearance 0)
		)
		(min_thickness 0.25)
		(keepout
			(tracks allowed)
			(vias allowed)
			(pads allowed)
			(copperpour allowed)
			(footprints allowed)
		)
		(placement
			(enabled no)
			(sheetname "")
		)
		(fill
			(thermal_gap 0.5)
			(thermal_bridge_width 0.5)
			(island_removal_mode 0)
		)
		(polygon
			(pts
				(xy 110.109 -29.845) (xy 110.109 -29.337) (xy 112.903 -29.337) (xy 112.903 -29.845)
			)
		)
	)
	(zone
		(layer "Cmts.User")
		(hatch none 0.5)
		(connect_pads
			(clearance 0)
		)
		(min_thickness 0.25)
		(keepout
			(tracks allowed)
			(vias allowed)
			(pads allowed)
			(copperpour allowed)
			(footprints allowed)
		)
		(placement
			(enabled no)
			(sheetname "")
		)
		(fill
			(thermal_gap 0.5)
			(thermal_bridge_width 0.5)
			(island_removal_mode 0)
		)
		(polygon
			(pts
				(xy 91.078812 -23.6728) (xy 91.078812 -23.1394) (xy 93.822012 -23.1394) (xy 93.822012 -23.6728)
			)
		)
	)
	(zone
		(layer "Cmts.User")
		(hatch none 0.5)
		(connect_pads
			(clearance 0)
		)
		(min_thickness 0.25)
		(keepout
			(tracks allowed)
			(vias allowed)
			(pads allowed)
			(copperpour allowed)
			(footprints allowed)
		)
		(placement
			(enabled no)
			(sheetname "")
		)
		(fill
			(thermal_gap 0.5)
			(thermal_bridge_width 0.5)
			(island_removal_mode 0)
		)
		(polygon
			(pts
				(xy 70.594982 -19.685) (xy 70.594982 -19.1516) (xy 73.338182 -19.1516) (xy 73.338182 -19.685)
			)
		)
	)
	(zone
		(layer "Cmts.User")
		(hatch none 0.5)
		(connect_pads
			(clearance 0)
		)
		(min_thickness 0.25)
		(keepout
			(tracks allowed)
			(vias allowed)
			(pads allowed)
			(copperpour allowed)
			(footprints allowed)
		)
		(placement
			(enabled no)
			(sheetname "")
		)
		(fill
			(thermal_gap 0.5)
			(thermal_bridge_width 0.5)
			(island_removal_mode 0)
		)
		(polygon
			(pts
				(xy 70.837298 -7.970012) (xy 71.370698 -7.970012) (xy 71.370698 -10.713212) (xy 70.837298 -10.713212)
			)
		)
	)
	(zone
		(layer "Cmts.User")
		(hatch none 0.5)
		(connect_pads
			(clearance 0)
		)
		(min_thickness 0.25)
		(keepout
			(tracks allowed)
			(vias allowed)
			(pads allowed)
			(copperpour allowed)
			(footprints allowed)
		)
		(placement
			(enabled no)
			(sheetname "")
		)
		(fill
			(thermal_gap 0.5)
			(thermal_bridge_width 0.5)
			(island_removal_mode 0)
		)
		(polygon
			(pts
				(xy 78.88605 -23.144988) (xy 78.50886 -22.767798) (xy 80.448658 -20.828) (xy 80.825848 -21.20519)
			)
		)
	)
	(zone
		(layer "Cmts.User")
		(hatch none 0.5)
		(connect_pads
			(clearance 0)
		)
		(min_thickness 0.25)
		(keepout
			(tracks allowed)
			(vias allowed)
			(pads allowed)
			(copperpour allowed)
			(footprints allowed)
		)
		(placement
			(enabled no)
			(sheetname "")
		)
		(fill
			(thermal_gap 0.5)
			(thermal_bridge_width 0.5)
			(island_removal_mode 0)
		)
		(polygon
			(pts
				(xy 114.352832 -31.335218) (xy 114.352832 -30.801818) (xy 117.096032 -30.801818) (xy 117.096032 -31.335218)
			)
		)
	)
	(zone
		(layer "Cmts.User")
		(hatch none 0.5)
		(connect_pads
			(clearance 0)
		)
		(min_thickness 0.25)
		(keepout
			(tracks allowed)
			(vias allowed)
			(pads allowed)
			(copperpour allowed)
			(footprints allowed)
		)
		(placement
			(enabled no)
			(sheetname "")
		)
		(fill
			(thermal_gap 0.5)
			(thermal_bridge_width 0.5)
			(island_removal_mode 0)
		)
		(polygon
			(pts
				(xy 19.652996 -90.548206) (xy 19.652996 -91.081606) (xy 16.909796 -91.081606) (xy 16.909796 -90.548206)
			)
		)
	)
	(zone
		(layer "Cmts.User")
		(hatch none 0.5)
		(connect_pads
			(clearance 0)
		)
		(min_thickness 0.25)
		(keepout
			(tracks allowed)
			(vias allowed)
			(pads allowed)
			(copperpour allowed)
			(footprints allowed)
		)
		(placement
			(enabled no)
			(sheetname "")
		)
		(fill
			(thermal_gap 0.5)
			(thermal_bridge_width 0.5)
			(island_removal_mode 0)
		)
		(polygon
			(pts
				(xy 61.7474 -19.685) (xy 61.7474 -19.1516) (xy 64.4906 -19.1516) (xy 64.4906 -19.685)
			)
		)
	)
)
